(lib_symbols
	(symbol "antmicroB2BConnectors:ASP-208571-01_mounting_holes"
			(exclude_from_sim no)
			(in_bom yes)
			(on_board yes)
			(property "Reference" "J"
				(at 36.83 -5.08 0)
				(effects
					(font
						(size 1.27 1.27)
						(thickness 0.15)
					)
					(justify left bottom)
				)
			)
			(property "Value" "ASP-208571-01_mounting_holes"
				(at 36.83 -10.16 0)
				(effects
					(font
						(size 1.27 1.27)
						(thickness 0.15)
					)
					(justify left bottom)
					(hide yes)
				)
			)
			(property "Footprint" "antmicro-footprints:ASP-208571-01_mounting_holes"
				(at 36.83 -12.7 0)
				(effects
					(font
						(size 1.27 1.27)
						(thickness 0.15)
					)
					(justify left bottom)
					(hide yes)
				)
			)
			(property "Datasheet" "https://suddendocs.samtec.com/prints/asp-208571-01-mkt.pdf"
				(at 36.83 -15.24 0)
				(effects
					(font
						(size 1.27 1.27)
						(thickness 0.15)
					)
					(justify left bottom)
					(hide yes)
				)
			)
			(property "Description" "FMC connector"
				(at 36.83 -25.4 0)
				(effects
					(font
						(size 1.27 1.27)
					)
					(justify left bottom)
					(hide yes)
				)
			)
			(property "MPN" "ASP-208571-01"
				(at 36.83 -7.62 0)
				(effects
					(font
						(size 1.27 1.27)
						(thickness 0.15)
					)
					(justify left bottom)
				)
			)
			(property "Manufacturer" "Samtec"
				(at 36.83 -17.78 0)
				(effects
					(font
						(size 1.27 1.27)
						(thickness 0.15)
					)
					(justify left bottom)
					(hide yes)
				)
			)
			(property "Author" "Antmicro"
				(at 36.83 -20.32 0)
				(effects
					(font
						(size 1.27 1.27)
						(thickness 0.15)
					)
					(justify left bottom)
					(hide yes)
				)
			)
			(property "License" "Apache-2.0"
				(at 36.83 -22.86 0)
				(effects
					(font
						(size 1.27 1.27)
						(thickness 0.15)
					)
					(justify left bottom)
					(hide yes)
				)
			)
			(property "ki_locked" ""
				(at 0 0 0)
				(effects
					(font
						(size 1.27 1.27)
					)
				)
			)
			(property "ki_keywords" "CONNECTOR"
				(at 0 0 0)
				(effects
					(font
						(size 1.27 1.27)
					)
					(hide yes)
				)
			)
			(symbol "ASP-208571-01_mounting_holes_1_1"
				(rectangle
					(start 3.81 -101.6)
					(end 19.05 2.54)
					(stroke
						(width 0.254)
						(type default)
					)
					(fill
						(type background)
					)
				)
				(pin passive line
					(at 0 0 0)
					(length 3.81)
					(name "Y01"
						(effects
							(font
								(size 1.27 1.27)
							)
						)
					)
					(number "Y01"
						(effects
							(font
								(size 1.27 1.27)
							)
						)
					)
				)
				(pin passive line
					(at 0 -2.54 0)
					(length 3.81)
					(name "Y02"
						(effects
							(font
								(size 1.27 1.27)
							)
						)
					)
					(number "Y02"
						(effects
							(font
								(size 1.27 1.27)
							)
						)
					)
				)
				(pin passive line
					(at 0 -5.08 0)
					(length 3.81)
					(name "Y03"
						(effects
							(font
								(size 1.27 1.27)
							)
						)
					)
					(number "Y03"
						(effects
							(font
								(size 1.27 1.27)
							)
						)
					)
				)
				(pin passive line
					(at 0 -7.62 0)
					(length 3.81)
					(name "Y04"
						(effects
							(font
								(size 1.27 1.27)
							)
						)
					)
					(number "Y04"
						(effects
							(font
								(size 1.27 1.27)
							)
						)
					)
				)
				(pin passive line
					(at 0 -10.16 0)
					(length 3.81)
					(name "Y05"
						(effects
							(font
								(size 1.27 1.27)
							)
						)
					)
					(number "Y05"
						(effects
							(font
								(size 1.27 1.27)
							)
						)
					)
				)
				(pin passive line
					(at 0 -12.7 0)
					(length 3.81)
					(name "Y06"
						(effects
							(font
								(size 1.27 1.27)
							)
						)
					)
					(number "Y06"
						(effects
							(font
								(size 1.27 1.27)
							)
						)
					)
				)
				(pin passive line
					(at 0 -15.24 0)
					(length 3.81)
					(name "Y07"
						(effects
							(font
								(size 1.27 1.27)
							)
						)
					)
					(number "Y07"
						(effects
							(font
								(size 1.27 1.27)
							)
						)
					)
				)
				(pin passive line
					(at 0 -17.78 0)
					(length 3.81)
					(name "Y08"
						(effects
							(font
								(size 1.27 1.27)
							)
						)
					)
					(number "Y08"
						(effects
							(font
								(size 1.27 1.27)
							)
						)
					)
				)
				(pin passive line
					(at 0 -20.32 0)
					(length 3.81)
					(name "Y09"
						(effects
							(font
								(size 1.27 1.27)
							)
						)
					)
					(number "Y09"
						(effects
							(font
								(size 1.27 1.27)
							)
						)
					)
				)
				(pin passive line
					(at 0 -22.86 0)
					(length 3.81)
					(name "Y10"
						(effects
							(font
								(size 1.27 1.27)
							)
						)
					)
					(number "Y10"
						(effects
							(font
								(size 1.27 1.27)
							)
						)
					)
				)
				(pin passive line
					(at 0 -25.4 0)
					(length 3.81)
					(name "Y11"
						(effects
							(font
								(size 1.27 1.27)
							)
						)
					)
					(number "Y11"
						(effects
							(font
								(size 1.27 1.27)
							)
						)
					)
				)
				(pin passive line
					(at 0 -27.94 0)
					(length 3.81)
					(name "Y12"
						(effects
							(font
								(size 1.27 1.27)
							)
						)
					)
					(number "Y12"
						(effects
							(font
								(size 1.27 1.27)
							)
						)
					)
				)
				(pin passive line
					(at 0 -30.48 0)
					(length 3.81)
					(name "Y13"
						(effects
							(font
								(size 1.27 1.27)
							)
						)
					)
					(number "Y13"
						(effects
							(font
								(size 1.27 1.27)
							)
						)
					)
				)
				(pin passive line
					(at 0 -33.02 0)
					(length 3.81)
					(name "Y14"
						(effects
							(font
								(size 1.27 1.27)
							)
						)
					)
					(number "Y14"
						(effects
							(font
								(size 1.27 1.27)
							)
						)
					)
				)
				(pin passive line
					(at 0 -35.56 0)
					(length 3.81)
					(name "Y15"
						(effects
							(font
								(size 1.27 1.27)
							)
						)
					)
					(number "Y15"
						(effects
							(font
								(size 1.27 1.27)
							)
						)
					)
				)
				(pin passive line
					(at 0 -38.1 0)
					(length 3.81)
					(name "Y16"
						(effects
							(font
								(size 1.27 1.27)
							)
						)
					)
					(number "Y16"
						(effects
							(font
								(size 1.27 1.27)
							)
						)
					)
				)
				(pin passive line
					(at 0 -40.64 0)
					(length 3.81)
					(name "Y17"
						(effects
							(font
								(size 1.27 1.27)
							)
						)
					)
					(number "Y17"
						(effects
							(font
								(size 1.27 1.27)
							)
						)
					)
				)
				(pin passive line
					(at 0 -43.18 0)
					(length 3.81)
					(name "Y18"
						(effects
							(font
								(size 1.27 1.27)
							)
						)
					)
					(number "Y18"
						(effects
							(font
								(size 1.27 1.27)
							)
						)
					)
				)
				(pin passive line
					(at 0 -45.72 0)
					(length 3.81)
					(name "Y19"
						(effects
							(font
								(size 1.27 1.27)
							)
						)
					)
					(number "Y19"
						(effects
							(font
								(size 1.27 1.27)
							)
						)
					)
				)
				(pin passive line
					(at 0 -48.26 0)
					(length 3.81)
					(name "Y20"
						(effects
							(font
								(size 1.27 1.27)
							)
						)
					)
					(number "Y20"
						(effects
							(font
								(size 1.27 1.27)
							)
						)
					)
				)
				(pin passive line
					(at 0 -50.8 0)
					(length 3.81)
					(name "Y21"
						(effects
							(font
								(size 1.27 1.27)
							)
						)
					)
					(number "Y21"
						(effects
							(font
								(size 1.27 1.27)
							)
						)
					)
				)
				(pin passive line
					(at 0 -53.34 0)
					(length 3.81)
					(name "Y22"
						(effects
							(font
								(size 1.27 1.27)
							)
						)
					)
					(number "Y22"
						(effects
							(font
								(size 1.27 1.27)
							)
						)
					)
				)
				(pin passive line
					(at 0 -55.88 0)
					(length 3.81)
					(name "Y23"
						(effects
							(font
								(size 1.27 1.27)
							)
						)
					)
					(number "Y23"
						(effects
							(font
								(size 1.27 1.27)
							)
						)
					)
				)
				(pin passive line
					(at 0 -58.42 0)
					(length 3.81)
					(name "Y24"
						(effects
							(font
								(size 1.27 1.27)
							)
						)
					)
					(number "Y24"
						(effects
							(font
								(size 1.27 1.27)
							)
						)
					)
				)
				(pin passive line
					(at 0 -60.96 0)
					(length 3.81)
					(name "Y25"
						(effects
							(font
								(size 1.27 1.27)
							)
						)
					)
					(number "Y25"
						(effects
							(font
								(size 1.27 1.27)
							)
						)
					)
				)
				(pin passive line
					(at 0 -63.5 0)
					(length 3.81)
					(name "Y26"
						(effects
							(font
								(size 1.27 1.27)
							)
						)
					)
					(number "Y26"
						(effects
							(font
								(size 1.27 1.27)
							)
						)
					)
				)
				(pin passive line
					(at 0 -66.04 0)
					(length 3.81)
					(name "Y27"
						(effects
							(font
								(size 1.27 1.27)
							)
						)
					)
					(number "Y27"
						(effects
							(font
								(size 1.27 1.27)
							)
						)
					)
				)
				(pin passive line
					(at 0 -68.58 0)
					(length 3.81)
					(name "Y28"
						(effects
							(font
								(size 1.27 1.27)
							)
						)
					)
					(number "Y28"
						(effects
							(font
								(size 1.27 1.27)
							)
						)
					)
				)
				(pin passive line
					(at 0 -71.12 0)
					(length 3.81)
					(name "Y29"
						(effects
							(font
								(size 1.27 1.27)
							)
						)
					)
					(number "Y29"
						(effects
							(font
								(size 1.27 1.27)
							)
						)
					)
				)
				(pin passive line
					(at 0 -73.66 0)
					(length 3.81)
					(name "Y30"
						(effects
							(font
								(size 1.27 1.27)
							)
						)
					)
					(number "Y30"
						(effects
							(font
								(size 1.27 1.27)
							)
						)
					)
				)
				(pin passive line
					(at 0 -76.2 0)
					(length 3.81)
					(name "Y31"
						(effects
							(font
								(size 1.27 1.27)
							)
						)
					)
					(number "Y31"
						(effects
							(font
								(size 1.27 1.27)
							)
						)
					)
				)
				(pin passive line
					(at 0 -78.74 0)
					(length 3.81)
					(name "Y32"
						(effects
							(font
								(size 1.27 1.27)
							)
						)
					)
					(number "Y32"
						(effects
							(font
								(size 1.27 1.27)
							)
						)
					)
				)
				(pin passive line
					(at 0 -81.28 0)
					(length 3.81)
					(name "Y33"
						(effects
							(font
								(size 1.27 1.27)
							)
						)
					)
					(number "Y33"
						(effects
							(font
								(size 1.27 1.27)
							)
						)
					)
				)
				(pin passive line
					(at 0 -83.82 0)
					(length 3.81)
					(name "Y34"
						(effects
							(font
								(size 1.27 1.27)
							)
						)
					)
					(number "Y34"
						(effects
							(font
								(size 1.27 1.27)
							)
						)
					)
				)
				(pin passive line
					(at 0 -86.36 0)
					(length 3.81)
					(name "Y35"
						(effects
							(font
								(size 1.27 1.27)
							)
						)
					)
					(number "Y35"
						(effects
							(font
								(size 1.27 1.27)
							)
						)
					)
				)
				(pin passive line
					(at 0 -88.9 0)
					(length 3.81)
					(name "Y36"
						(effects
							(font
								(size 1.27 1.27)
							)
						)
					)
					(number "Y36"
						(effects
							(font
								(size 1.27 1.27)
							)
						)
					)
				)
				(pin passive line
					(at 0 -91.44 0)
					(length 3.81)
					(name "Y37"
						(effects
							(font
								(size 1.27 1.27)
							)
						)
					)
					(number "Y37"
						(effects
							(font
								(size 1.27 1.27)
							)
						)
					)
				)
				(pin passive line
					(at 0 -93.98 0)
					(length 3.81)
					(name "Y38"
						(effects
							(font
								(size 1.27 1.27)
							)
						)
					)
					(number "Y38"
						(effects
							(font
								(size 1.27 1.27)
							)
						)
					)
				)
				(pin passive line
					(at 0 -96.52 0)
					(length 3.81)
					(name "Y39"
						(effects
							(font
								(size 1.27 1.27)
							)
						)
					)
					(number "Y39"
						(effects
							(font
								(size 1.27 1.27)
							)
						)
					)
				)
				(pin passive line
					(at 0 -99.06 0)
					(length 3.81)
					(name "Y40"
						(effects
							(font
								(size 1.27 1.27)
							)
						)
					)
					(number "Y40"
						(effects
							(font
								(size 1.27 1.27)
							)
						)
					)
				)
				(pin passive line
					(at 22.86 0 180)
					(length 3.81)
					(name "Z01"
						(effects
							(font
								(size 1.27 1.27)
							)
						)
					)
					(number "Z01"
						(effects
							(font
								(size 1.27 1.27)
							)
						)
					)
				)
				(pin passive line
					(at 22.86 -2.54 180)
					(length 3.81)
					(name "Z02"
						(effects
							(font
								(size 1.27 1.27)
							)
						)
					)
					(number "Z02"
						(effects
							(font
								(size 1.27 1.27)
							)
						)
					)
				)
				(pin passive line
					(at 22.86 -5.08 180)
					(length 3.81)
					(name "Z03"
						(effects
							(font
								(size 1.27 1.27)
							)
						)
					)
					(number "Z03"
						(effects
							(font
								(size 1.27 1.27)
							)
						)
					)
				)
				(pin passive line
					(at 22.86 -7.62 180)
					(length 3.81)
					(name "Z04"
						(effects
							(font
								(size 1.27 1.27)
							)
						)
					)
					(number "Z04"
						(effects
							(font
								(size 1.27 1.27)
							)
						)
					)
				)
				(pin passive line
					(at 22.86 -10.16 180)
					(length 3.81)
					(name "Z05"
						(effects
							(font
								(size 1.27 1.27)
							)
						)
					)
					(number "Z05"
						(effects
							(font
								(size 1.27 1.27)
							)
						)
					)
				)
				(pin passive line
					(at 22.86 -12.7 180)
					(length 3.81)
					(name "Z06"
						(effects
							(font
								(size 1.27 1.27)
							)
						)
					)
					(number "Z06"
						(effects
							(font
								(size 1.27 1.27)
							)
						)
					)
				)
				(pin passive line
					(at 22.86 -15.24 180)
					(length 3.81)
					(name "Z07"
						(effects
							(font
								(size 1.27 1.27)
							)
						)
					)
					(number "Z07"
						(effects
							(font
								(size 1.27 1.27)
							)
						)
					)
				)
				(pin passive line
					(at 22.86 -17.78 180)
					(length 3.81)
					(name "Z08"
						(effects
							(font
								(size 1.27 1.27)
							)
						)
					)
					(number "Z08"
						(effects
							(font
								(size 1.27 1.27)
							)
						)
					)
				)
				(pin passive line
					(at 22.86 -20.32 180)
					(length 3.81)
					(name "Z09"
						(effects
							(font
								(size 1.27 1.27)
							)
						)
					)
					(number "Z09"
						(effects
							(font
								(size 1.27 1.27)
							)
						)
					)
				)
				(pin passive line
					(at 22.86 -22.86 180)
					(length 3.81)
					(name "Z10"
						(effects
							(font
								(size 1.27 1.27)
							)
						)
					)
					(number "Z10"
						(effects
							(font
								(size 1.27 1.27)
							)
						)
					)
				)
				(pin passive line
					(at 22.86 -25.4 180)
					(length 3.81)
					(name "Z11"
						(effects
							(font
								(size 1.27 1.27)
							)
						)
					)
					(number "Z11"
						(effects
							(font
								(size 1.27 1.27)
							)
						)
					)
				)
				(pin passive line
					(at 22.86 -27.94 180)
					(length 3.81)
					(name "Z12"
						(effects
							(font
								(size 1.27 1.27)
							)
						)
					)
					(number "Z12"
						(effects
							(font
								(size 1.27 1.27)
							)
						)
					)
				)
				(pin passive line
					(at 22.86 -30.48 180)
					(length 3.81)
					(name "Z13"
						(effects
							(font
								(size 1.27 1.27)
							)
						)
					)
					(number "Z13"
						(effects
							(font
								(size 1.27 1.27)
							)
						)
					)
				)
				(pin passive line
					(at 22.86 -33.02 180)
					(length 3.81)
					(name "Z14"
						(effects
							(font
								(size 1.27 1.27)
							)
						)
					)
					(number "Z14"
						(effects
							(font
								(size 1.27 1.27)
							)
						)
					)
				)
				(pin passive line
					(at 22.86 -35.56 180)
					(length 3.81)
					(name "Z15"
						(effects
							(font
								(size 1.27 1.27)
							)
						)
					)
					(number "Z15"
						(effects
							(font
								(size 1.27 1.27)
							)
						)
					)
				)
				(pin passive line
					(at 22.86 -38.1 180)
					(length 3.81)
					(name "Z16"
						(effects
							(font
								(size 1.27 1.27)
							)
						)
					)
					(number "Z16"
						(effects
							(font
								(size 1.27 1.27)
							)
						)
					)
				)
				(pin passive line
					(at 22.86 -40.64 180)
					(length 3.81)
					(name "Z17"
						(effects
							(font
								(size 1.27 1.27)
							)
						)
					)
					(number "Z17"
						(effects
							(font
								(size 1.27 1.27)
							)
						)
					)
				)
				(pin passive line
					(at 22.86 -43.18 180)
					(length 3.81)
					(name "Z18"
						(effects
							(font
								(size 1.27 1.27)
							)
						)
					)
					(number "Z18"
						(effects
							(font
								(size 1.27 1.27)
							)
						)
					)
				)
				(pin passive line
					(at 22.86 -45.72 180)
					(length 3.81)
					(name "Z19"
						(effects
							(font
								(size 1.27 1.27)
							)
						)
					)
					(number "Z19"
						(effects
							(font
								(size 1.27 1.27)
							)
						)
					)
				)
				(pin passive line
					(at 22.86 -48.26 180)
					(length 3.81)
					(name "Z20"
						(effects
							(font
								(size 1.27 1.27)
							)
						)
					)
					(number "Z20"
						(effects
							(font
								(size 1.27 1.27)
							)
						)
					)
				)
				(pin passive line
					(at 22.86 -50.8 180)
					(length 3.81)
					(name "Z21"
						(effects
							(font
								(size 1.27 1.27)
							)
						)
					)
					(number "Z21"
						(effects
							(font
								(size 1.27 1.27)
							)
						)
					)
				)
				(pin passive line
					(at 22.86 -53.34 180)
					(length 3.81)
					(name "Z22"
						(effects
							(font
								(size 1.27 1.27)
							)
						)
					)
					(number "Z22"
						(effects
							(font
								(size 1.27 1.27)
							)
						)
					)
				)
				(pin passive line
					(at 22.86 -55.88 180)
					(length 3.81)
					(name "Z23"
						(effects
							(font
								(size 1.27 1.27)
							)
						)
					)
					(number "Z23"
						(effects
							(font
								(size 1.27 1.27)
							)
						)
					)
				)
				(pin passive line
					(at 22.86 -58.42 180)
					(length 3.81)
					(name "Z24"
						(effects
							(font
								(size 1.27 1.27)
							)
						)
					)
					(number "Z24"
						(effects
							(font
								(size 1.27 1.27)
							)
						)
					)
				)
				(pin passive line
					(at 22.86 -60.96 180)
					(length 3.81)
					(name "Z25"
						(effects
							(font
								(size 1.27 1.27)
							)
						)
					)
					(number "Z25"
						(effects
							(font
								(size 1.27 1.27)
							)
						)
					)
				)
				(pin passive line
					(at 22.86 -63.5 180)
					(length 3.81)
					(name "Z26"
						(effects
							(font
								(size 1.27 1.27)
							)
						)
					)
					(number "Z26"
						(effects
							(font
								(size 1.27 1.27)
							)
						)
					)
				)
				(pin passive line
					(at 22.86 -66.04 180)
					(length 3.81)
					(name "Z27"
						(effects
							(font
								(size 1.27 1.27)
							)
						)
					)
					(number "Z27"
						(effects
							(font
								(size 1.27 1.27)
							)
						)
					)
				)
				(pin passive line
					(at 22.86 -68.58 180)
					(length 3.81)
					(name "Z28"
						(effects
							(font
								(size 1.27 1.27)
							)
						)
					)
					(number "Z28"
						(effects
							(font
								(size 1.27 1.27)
							)
						)
					)
				)
				(pin passive line
					(at 22.86 -71.12 180)
					(length 3.81)
					(name "Z29"
						(effects
							(font
								(size 1.27 1.27)
							)
						)
					)
					(number "Z29"
						(effects
							(font
								(size 1.27 1.27)
							)
						)
					)
				)
				(pin passive line
					(at 22.86 -73.66 180)
					(length 3.81)
					(name "Z30"
						(effects
							(font
								(size 1.27 1.27)
							)
						)
					)
					(number "Z30"
						(effects
							(font
								(size 1.27 1.27)
							)
						)
					)
				)
				(pin passive line
					(at 22.86 -76.2 180)
					(length 3.81)
					(name "Z31"
						(effects
							(font
								(size 1.27 1.27)
							)
						)
					)
					(number "Z31"
						(effects
							(font
								(size 1.27 1.27)
							)
						)
					)
				)
				(pin passive line
					(at 22.86 -78.74 180)
					(length 3.81)
					(name "Z32"
						(effects
							(font
								(size 1.27 1.27)
							)
						)
					)
					(number "Z32"
						(effects
							(font
								(size 1.27 1.27)
							)
						)
					)
				)
				(pin passive line
					(at 22.86 -81.28 180)
					(length 3.81)
					(name "Z33"
						(effects
							(font
								(size 1.27 1.27)
							)
						)
					)
					(number "Z33"
						(effects
							(font
								(size 1.27 1.27)
							)
						)
					)
				)
				(pin passive line
					(at 22.86 -83.82 180)
					(length 3.81)
					(name "Z34"
						(effects
							(font
								(size 1.27 1.27)
							)
						)
					)
					(number "Z34"
						(effects
							(font
								(size 1.27 1.27)
							)
						)
					)
				)
				(pin passive line
					(at 22.86 -86.36 180)
					(length 3.81)
					(name "Z35"
						(effects
							(font
								(size 1.27 1.27)
							)
						)
					)
					(number "Z35"
						(effects
							(font
								(size 1.27 1.27)
							)
						)
					)
				)
				(pin passive line
					(at 22.86 -88.9 180)
					(length 3.81)
					(name "Z36"
						(effects
							(font
								(size 1.27 1.27)
							)
						)
					)
					(number "Z36"
						(effects
							(font
								(size 1.27 1.27)
							)
						)
					)
				)
				(pin passive line
					(at 22.86 -91.44 180)
					(length 3.81)
					(name "Z37"
						(effects
							(font
								(size 1.27 1.27)
							)
						)
					)
					(number "Z37"
						(effects
							(font
								(size 1.27 1.27)
							)
						)
					)
				)
				(pin passive line
					(at 22.86 -93.98 180)
					(length 3.81)
					(name "Z38"
						(effects
							(font
								(size 1.27 1.27)
							)
						)
					)
					(number "Z38"
						(effects
							(font
								(size 1.27 1.27)
							)
						)
					)
				)
				(pin passive line
					(at 22.86 -96.52 180)
					(length 3.81)
					(name "Z39"
						(effects
							(font
								(size 1.27 1.27)
							)
						)
					)
					(number "Z39"
						(effects
							(font
								(size 1.27 1.27)
							)
						)
					)
				)
				(pin passive line
					(at 22.86 -99.06 180)
					(length 3.81)
					(name "Z40"
						(effects
							(font
								(size 1.27 1.27)
							)
						)
					)
					(number "Z40"
						(effects
							(font
								(size 1.27 1.27)
							)
						)
					)
				)
			)
			(symbol "ASP-208571-01_mounting_holes_2_1"
				(rectangle
					(start 3.81 -101.6)
					(end 19.05 2.54)
					(stroke
						(width 0.254)
						(type default)
					)
					(fill
						(type background)
					)
				)
				(pin passive line
					(at 0 0 0)
					(length 3.81)
					(name "A01"
						(effects
							(font
								(size 1.27 1.27)
							)
						)
					)
					(number "A01"
						(effects
							(font
								(size 1.27 1.27)
							)
						)
					)
				)
				(pin passive line
					(at 0 -2.54 0)
					(length 3.81)
					(name "A02"
						(effects
							(font
								(size 1.27 1.27)
							)
						)
					)
					(number "A02"
						(effects
							(font
								(size 1.27 1.27)
							)
						)
					)
				)
				(pin passive line
					(at 0 -5.08 0)
					(length 3.81)
					(name "A03"
						(effects
							(font
								(size 1.27 1.27)
							)
						)
					)
					(number "A03"
						(effects
							(font
								(size 1.27 1.27)
							)
						)
					)
				)
				(pin passive line
					(at 0 -7.62 0)
					(length 3.81)
					(name "A04"
						(effects
							(font
								(size 1.27 1.27)
							)
						)
					)
					(number "A04"
						(effects
							(font
								(size 1.27 1.27)
							)
						)
					)
				)
				(pin passive line
					(at 0 -10.16 0)
					(length 3.81)
					(name "A05"
						(effects
							(font
								(size 1.27 1.27)
							)
						)
					)
					(number "A05"
						(effects
							(font
								(size 1.27 1.27)
							)
						)
					)
				)
				(pin passive line
					(at 0 -12.7 0)
					(length 3.81)
					(name "A06"
						(effects
							(font
								(size 1.27 1.27)
							)
						)
					)
					(number "A06"
						(effects
							(font
								(size 1.27 1.27)
							)
						)
					)
				)
				(pin passive line
					(at 0 -15.24 0)
					(length 3.81)
					(name "A07"
						(effects
							(font
								(size 1.27 1.27)
							)
						)
					)
					(number "A07"
						(effects
							(font
								(size 1.27 1.27)
							)
						)
					)
				)
				(pin passive line
					(at 0 -17.78 0)
					(length 3.81)
					(name "A08"
						(effects
							(font
								(size 1.27 1.27)
							)
						)
					)
					(number "A08"
						(effects
							(font
								(size 1.27 1.27)
							)
						)
					)
				)
				(pin passive line
					(at 0 -20.32 0)
					(length 3.81)
					(name "A09"
						(effects
							(font
								(size 1.27 1.27)
							)
						)
					)
					(number "A09"
						(effects
							(font
								(size 1.27 1.27)
							)
						)
					)
				)
				(pin passive line
					(at 0 -22.86 0)
					(length 3.81)
					(name "A10"
						(effects
							(font
								(size 1.27 1.27)
							)
						)
					)
					(number "A10"
						(effects
							(font
								(size 1.27 1.27)
							)
						)
					)
				)
				(pin passive line
					(at 0 -25.4 0)
					(length 3.81)
					(name "A11"
						(effects
							(font
								(size 1.27 1.27)
							)
						)
					)
					(number "A11"
						(effects
							(font
								(size 1.27 1.27)
							)
						)
					)
				)
				(pin passive line
					(at 0 -27.94 0)
					(length 3.81)
					(name "A12"
						(effects
							(font
								(size 1.27 1.27)
							)
						)
					)
					(number "A12"
						(effects
							(font
								(size 1.27 1.27)
							)
						)
					)
				)
				(pin passive line
					(at 0 -30.48 0)
					(length 3.81)
					(name "A13"
						(effects
							(font
								(size 1.27 1.27)
							)
						)
					)
					(number "A13"
						(effects
							(font
								(size 1.27 1.27)
							)
						)
					)
				)
				(pin passive line
					(at 0 -33.02 0)
					(length 3.81)
					(name "A14"
						(effects
							(font
								(size 1.27 1.27)
							)
						)
					)
					(number "A14"
						(effects
							(font
								(size 1.27 1.27)
							)
						)
					)
				)
				(pin passive line
					(at 0 -35.56 0)
					(length 3.81)
					(name "A15"
						(effects
							(font
								(size 1.27 1.27)
							)
						)
					)
					(number "A15"
						(effects
							(font
								(size 1.27 1.27)
							)
						)
					)
				)
				(pin passive line
					(at 0 -38.1 0)
					(length 3.81)
					(name "A16"
						(effects
							(font
								(size 1.27 1.27)
							)
						)
					)
					(number "A16"
						(effects
							(font
								(size 1.27 1.27)
							)
						)
					)
				)
				(pin passive line
					(at 0 -40.64 0)
					(length 3.81)
					(name "A17"
						(effects
							(font
								(size 1.27 1.27)
							)
						)
					)
					(number "A17"
						(effects
							(font
								(size 1.27 1.27)
							)
						)
					)
				)
				(pin passive line
					(at 0 -43.18 0)
					(length 3.81)
					(name "A18"
						(effects
							(font
								(size 1.27 1.27)
							)
						)
					)
					(number "A18"
						(effects
							(font
								(size 1.27 1.27)
							)
						)
					)
				)
				(pin passive line
					(at 0 -45.72 0)
					(length 3.81)
					(name "A19"
						(effects
							(font
								(size 1.27 1.27)
							)
						)
					)
					(number "A19"
						(effects
							(font
								(size 1.27 1.27)
							)
						)
					)
				)
				(pin passive line
					(at 0 -48.26 0)
					(length 3.81)
					(name "A20"
						(effects
							(font
								(size 1.27 1.27)
							)
						)
					)
					(number "A20"
						(effects
							(font
								(size 1.27 1.27)
							)
						)
					)
				)
				(pin passive line
					(at 0 -50.8 0)
					(length 3.81)
					(name "A21"
						(effects
							(font
								(size 1.27 1.27)
							)
						)
					)
					(number "A21"
						(effects
							(font
								(size 1.27 1.27)
							)
						)
					)
				)
				(pin passive line
					(at 0 -53.34 0)
					(length 3.81)
					(name "A22"
						(effects
							(font
								(size 1.27 1.27)
							)
						)
					)
					(number "A22"
						(effects
							(font
								(size 1.27 1.27)
							)
						)
					)
				)
				(pin passive line
					(at 0 -55.88 0)
					(length 3.81)
					(name "A23"
						(effects
							(font
								(size 1.27 1.27)
							)
						)
					)
					(number "A23"
						(effects
							(font
								(size 1.27 1.27)
							)
						)
					)
				)
				(pin passive line
					(at 0 -58.42 0)
					(length 3.81)
					(name "A24"
						(effects
							(font
								(size 1.27 1.27)
							)
						)
					)
					(number "A24"
						(effects
							(font
								(size 1.27 1.27)
							)
						)
					)
				)
				(pin passive line
					(at 0 -60.96 0)
					(length 3.81)
					(name "A25"
						(effects
							(font
								(size 1.27 1.27)
							)
						)
					)
					(number "A25"
						(effects
							(font
								(size 1.27 1.27)
							)
						)
					)
				)
				(pin passive line
					(at 0 -63.5 0)
					(length 3.81)
					(name "A26"
						(effects
							(font
								(size 1.27 1.27)
							)
						)
					)
					(number "A26"
						(effects
							(font
								(size 1.27 1.27)
							)
						)
					)
				)
				(pin passive line
					(at 0 -66.04 0)
					(length 3.81)
					(name "A27"
						(effects
							(font
								(size 1.27 1.27)
							)
						)
					)
					(number "A27"
						(effects
							(font
								(size 1.27 1.27)
							)
						)
					)
				)
				(pin passive line
					(at 0 -68.58 0)
					(length 3.81)
					(name "A28"
						(effects
							(font
								(size 1.27 1.27)
							)
						)
					)
					(number "A28"
						(effects
							(font
								(size 1.27 1.27)
							)
						)
					)
				)
				(pin passive line
					(at 0 -71.12 0)
					(length 3.81)
					(name "A29"
						(effects
							(font
								(size 1.27 1.27)
							)
						)
					)
					(number "A29"
						(effects
							(font
								(size 1.27 1.27)
							)
						)
					)
				)
				(pin passive line
					(at 0 -73.66 0)
					(length 3.81)
					(name "A30"
						(effects
							(font
								(size 1.27 1.27)
							)
						)
					)
					(number "A30"
						(effects
							(font
								(size 1.27 1.27)
							)
						)
					)
				)
				(pin passive line
					(at 0 -76.2 0)
					(length 3.81)
					(name "A31"
						(effects
							(font
								(size 1.27 1.27)
							)
						)
					)
					(number "A31"
						(effects
							(font
								(size 1.27 1.27)
							)
						)
					)
				)
				(pin passive line
					(at 0 -78.74 0)
					(length 3.81)
					(name "A32"
						(effects
							(font
								(size 1.27 1.27)
							)
						)
					)
					(number "A32"
						(effects
							(font
								(size 1.27 1.27)
							)
						)
					)
				)
				(pin passive line
					(at 0 -81.28 0)
					(length 3.81)
					(name "A33"
						(effects
							(font
								(size 1.27 1.27)
							)
						)
					)
					(number "A33"
						(effects
							(font
								(size 1.27 1.27)
							)
						)
					)
				)
				(pin passive line
					(at 0 -83.82 0)
					(length 3.81)
					(name "A34"
						(effects
							(font
								(size 1.27 1.27)
							)
						)
					)
					(number "A34"
						(effects
							(font
								(size 1.27 1.27)
							)
						)
					)
				)
				(pin passive line
					(at 0 -86.36 0)
					(length 3.81)
					(name "A35"
						(effects
							(font
								(size 1.27 1.27)
							)
						)
					)
					(number "A35"
						(effects
							(font
								(size 1.27 1.27)
							)
						)
					)
				)
				(pin passive line
					(at 0 -88.9 0)
					(length 3.81)
					(name "A36"
						(effects
							(font
								(size 1.27 1.27)
							)
						)
					)
					(number "A36"
						(effects
							(font
								(size 1.27 1.27)
							)
						)
					)
				)
				(pin passive line
					(at 0 -91.44 0)
					(length 3.81)
					(name "A37"
						(effects
							(font
								(size 1.27 1.27)
							)
						)
					)
					(number "A37"
						(effects
							(font
								(size 1.27 1.27)
							)
						)
					)
				)
				(pin passive line
					(at 0 -93.98 0)
					(length 3.81)
					(name "A38"
						(effects
							(font
								(size 1.27 1.27)
							)
						)
					)
					(number "A38"
						(effects
							(font
								(size 1.27 1.27)
							)
						)
					)
				)
				(pin passive line
					(at 0 -96.52 0)
					(length 3.81)
					(name "A39"
						(effects
							(font
								(size 1.27 1.27)
							)
						)
					)
					(number "A39"
						(effects
							(font
								(size 1.27 1.27)
							)
						)
					)
				)
				(pin passive line
					(at 0 -99.06 0)
					(length 3.81)
					(name "A40"
						(effects
							(font
								(size 1.27 1.27)
							)
						)
					)
					(number "A40"
						(effects
							(font
								(size 1.27 1.27)
							)
						)
					)
				)
				(pin passive line
					(at 22.86 0 180)
					(length 3.81)
					(name "B01"
						(effects
							(font
								(size 1.27 1.27)
							)
						)
					)
					(number "B01"
						(effects
							(font
								(size 1.27 1.27)
							)
						)
					)
				)
				(pin passive line
					(at 22.86 -2.54 180)
					(length 3.81)
					(name "B02"
						(effects
							(font
								(size 1.27 1.27)
							)
						)
					)
					(number "B02"
						(effects
							(font
								(size 1.27 1.27)
							)
						)
					)
				)
				(pin passive line
					(at 22.86 -5.08 180)
					(length 3.81)
					(name "B03"
						(effects
							(font
								(size 1.27 1.27)
							)
						)
					)
					(number "B03"
						(effects
							(font
								(size 1.27 1.27)
							)
						)
					)
				)
				(pin passive line
					(at 22.86 -7.62 180)
					(length 3.81)
					(name "B04"
						(effects
							(font
								(size 1.27 1.27)
							)
						)
					)
					(number "B04"
						(effects
							(font
								(size 1.27 1.27)
							)
						)
					)
				)
				(pin passive line
					(at 22.86 -10.16 180)
					(length 3.81)
					(name "B05"
						(effects
							(font
								(size 1.27 1.27)
							)
						)
					)
					(number "B05"
						(effects
							(font
								(size 1.27 1.27)
							)
						)
					)
				)
				(pin passive line
					(at 22.86 -12.7 180)
					(length 3.81)
					(name "B06"
						(effects
							(font
								(size 1.27 1.27)
							)
						)
					)
					(number "B06"
						(effects
							(font
								(size 1.27 1.27)
							)
						)
					)
				)
				(pin passive line
					(at 22.86 -15.24 180)
					(length 3.81)
					(name "B07"
						(effects
							(font
								(size 1.27 1.27)
							)
						)
					)
					(number "B07"
						(effects
							(font
								(size 1.27 1.27)
							)
						)
					)
				)
				(pin passive line
					(at 22.86 -17.78 180)
					(length 3.81)
					(name "B08"
						(effects
							(font
								(size 1.27 1.27)
							)
						)
					)
					(number "B08"
						(effects
							(font
								(size 1.27 1.27)
							)
						)
					)
				)
				(pin passive line
					(at 22.86 -20.32 180)
					(length 3.81)
					(name "B09"
						(effects
							(font
								(size 1.27 1.27)
							)
						)
					)
					(number "B09"
						(effects
							(font
								(size 1.27 1.27)
							)
						)
					)
				)
				(pin passive line
					(at 22.86 -22.86 180)
					(length 3.81)
					(name "B10"
						(effects
							(font
								(size 1.27 1.27)
							)
						)
					)
					(number "B10"
						(effects
							(font
								(size 1.27 1.27)
							)
						)
					)
				)
				(pin passive line
					(at 22.86 -25.4 180)
					(length 3.81)
					(name "B11"
						(effects
							(font
								(size 1.27 1.27)
							)
						)
					)
					(number "B11"
						(effects
							(font
								(size 1.27 1.27)
							)
						)
					)
				)
				(pin passive line
					(at 22.86 -27.94 180)
					(length 3.81)
					(name "B12"
						(effects
							(font
								(size 1.27 1.27)
							)
						)
					)
					(number "B12"
						(effects
							(font
								(size 1.27 1.27)
							)
						)
					)
				)
				(pin passive line
					(at 22.86 -30.48 180)
					(length 3.81)
					(name "B13"
						(effects
							(font
								(size 1.27 1.27)
							)
						)
					)
					(number "B13"
						(effects
							(font
								(size 1.27 1.27)
							)
						)
					)
				)
				(pin passive line
					(at 22.86 -33.02 180)
					(length 3.81)
					(name "B14"
						(effects
							(font
								(size 1.27 1.27)
							)
						)
					)
					(number "B14"
						(effects
							(font
								(size 1.27 1.27)
							)
						)
					)
				)
				(pin passive line
					(at 22.86 -35.56 180)
					(length 3.81)
					(name "B15"
						(effects
							(font
								(size 1.27 1.27)
							)
						)
					)
					(number "B15"
						(effects
							(font
								(size 1.27 1.27)
							)
						)
					)
				)
				(pin passive line
					(at 22.86 -38.1 180)
					(length 3.81)
					(name "B16"
						(effects
							(font
								(size 1.27 1.27)
							)
						)
					)
					(number "B16"
						(effects
							(font
								(size 1.27 1.27)
							)
						)
					)
				)
				(pin passive line
					(at 22.86 -40.64 180)
					(length 3.81)
					(name "B17"
						(effects
							(font
								(size 1.27 1.27)
							)
						)
					)
					(number "B17"
						(effects
							(font
								(size 1.27 1.27)
							)
						)
					)
				)
				(pin passive line
					(at 22.86 -43.18 180)
					(length 3.81)
					(name "B18"
						(effects
							(font
								(size 1.27 1.27)
							)
						)
					)
					(number "B18"
						(effects
							(font
								(size 1.27 1.27)
							)
						)
					)
				)
				(pin passive line
					(at 22.86 -45.72 180)
					(length 3.81)
					(name "B19"
						(effects
							(font
								(size 1.27 1.27)
							)
						)
					)
					(number "B19"
						(effects
							(font
								(size 1.27 1.27)
							)
						)
					)
				)
				(pin passive line
					(at 22.86 -48.26 180)
					(length 3.81)
					(name "B20"
						(effects
							(font
								(size 1.27 1.27)
							)
						)
					)
					(number "B20"
						(effects
							(font
								(size 1.27 1.27)
							)
						)
					)
				)
				(pin passive line
					(at 22.86 -50.8 180)
					(length 3.81)
					(name "B21"
						(effects
							(font
								(size 1.27 1.27)
							)
						)
					)
					(number "B21"
						(effects
							(font
								(size 1.27 1.27)
							)
						)
					)
				)
				(pin passive line
					(at 22.86 -53.34 180)
					(length 3.81)
					(name "B22"
						(effects
							(font
								(size 1.27 1.27)
							)
						)
					)
					(number "B22"
						(effects
							(font
								(size 1.27 1.27)
							)
						)
					)
				)
				(pin passive line
					(at 22.86 -55.88 180)
					(length 3.81)
					(name "B23"
						(effects
							(font
								(size 1.27 1.27)
							)
						)
					)
					(number "B23"
						(effects
							(font
								(size 1.27 1.27)
							)
						)
					)
				)
				(pin passive line
					(at 22.86 -58.42 180)
					(length 3.81)
					(name "B24"
						(effects
							(font
								(size 1.27 1.27)
							)
						)
					)
					(number "B24"
						(effects
							(font
								(size 1.27 1.27)
							)
						)
					)
				)
				(pin passive line
					(at 22.86 -60.96 180)
					(length 3.81)
					(name "B25"
						(effects
							(font
								(size 1.27 1.27)
							)
						)
					)
					(number "B25"
						(effects
							(font
								(size 1.27 1.27)
							)
						)
					)
				)
				(pin passive line
					(at 22.86 -63.5 180)
					(length 3.81)
					(name "B26"
						(effects
							(font
								(size 1.27 1.27)
							)
						)
					)
					(number "B26"
						(effects
							(font
								(size 1.27 1.27)
							)
						)
					)
				)
				(pin passive line
					(at 22.86 -66.04 180)
					(length 3.81)
					(name "B27"
						(effects
							(font
								(size 1.27 1.27)
							)
						)
					)
					(number "B27"
						(effects
							(font
								(size 1.27 1.27)
							)
						)
					)
				)
				(pin passive line
					(at 22.86 -68.58 180)
					(length 3.81)
					(name "B28"
						(effects
							(font
								(size 1.27 1.27)
							)
						)
					)
					(number "B28"
						(effects
							(font
								(size 1.27 1.27)
							)
						)
					)
				)
				(pin passive line
					(at 22.86 -71.12 180)
					(length 3.81)
					(name "B29"
						(effects
							(font
								(size 1.27 1.27)
							)
						)
					)
					(number "B29"
						(effects
							(font
								(size 1.27 1.27)
							)
						)
					)
				)
				(pin passive line
					(at 22.86 -73.66 180)
					(length 3.81)
					(name "B30"
						(effects
							(font
								(size 1.27 1.27)
							)
						)
					)
					(number "B30"
						(effects
							(font
								(size 1.27 1.27)
							)
						)
					)
				)
				(pin passive line
					(at 22.86 -76.2 180)
					(length 3.81)
					(name "B31"
						(effects
							(font
								(size 1.27 1.27)
							)
						)
					)
					(number "B31"
						(effects
							(font
								(size 1.27 1.27)
							)
						)
					)
				)
				(pin passive line
					(at 22.86 -78.74 180)
					(length 3.81)
					(name "B32"
						(effects
							(font
								(size 1.27 1.27)
							)
						)
					)
					(number "B32"
						(effects
							(font
								(size 1.27 1.27)
							)
						)
					)
				)
				(pin passive line
					(at 22.86 -81.28 180)
					(length 3.81)
					(name "B33"
						(effects
							(font
								(size 1.27 1.27)
							)
						)
					)
					(number "B33"
						(effects
							(font
								(size 1.27 1.27)
							)
						)
					)
				)
				(pin passive line
					(at 22.86 -83.82 180)
					(length 3.81)
					(name "B34"
						(effects
							(font
								(size 1.27 1.27)
							)
						)
					)
					(number "B34"
						(effects
							(font
								(size 1.27 1.27)
							)
						)
					)
				)
				(pin passive line
					(at 22.86 -86.36 180)
					(length 3.81)
					(name "B35"
						(effects
							(font
								(size 1.27 1.27)
							)
						)
					)
					(number "B35"
						(effects
							(font
								(size 1.27 1.27)
							)
						)
					)
				)
				(pin passive line
					(at 22.86 -88.9 180)
					(length 3.81)
					(name "B36"
						(effects
							(font
								(size 1.27 1.27)
							)
						)
					)
					(number "B36"
						(effects
							(font
								(size 1.27 1.27)
							)
						)
					)
				)
				(pin passive line
					(at 22.86 -91.44 180)
					(length 3.81)
					(name "B37"
						(effects
							(font
								(size 1.27 1.27)
							)
						)
					)
					(number "B37"
						(effects
							(font
								(size 1.27 1.27)
							)
						)
					)
				)
				(pin passive line
					(at 22.86 -93.98 180)
					(length 3.81)
					(name "B38"
						(effects
							(font
								(size 1.27 1.27)
							)
						)
					)
					(number "B38"
						(effects
							(font
								(size 1.27 1.27)
							)
						)
					)
				)
				(pin passive line
					(at 22.86 -96.52 180)
					(length 3.81)
					(name "B39"
						(effects
							(font
								(size 1.27 1.27)
							)
						)
					)
					(number "B39"
						(effects
							(font
								(size 1.27 1.27)
							)
						)
					)
				)
				(pin passive line
					(at 22.86 -99.06 180)
					(length 3.81)
					(name "B40"
						(effects
							(font
								(size 1.27 1.27)
							)
						)
					)
					(number "B40"
						(effects
							(font
								(size 1.27 1.27)
							)
						)
					)
				)
			)
			(symbol "ASP-208571-01_mounting_holes_3_1"
				(rectangle
					(start 3.81 -101.6)
					(end 19.05 2.54)
					(stroke
						(width 0.254)
						(type default)
					)
					(fill
						(type background)
					)
				)
				(pin passive line
					(at 0 0 0)
					(length 3.81)
					(name "C01"
						(effects
							(font
								(size 1.27 1.27)
							)
						)
					)
					(number "C01"
						(effects
							(font
								(size 1.27 1.27)
							)
						)
					)
				)
				(pin passive line
					(at 0 -2.54 0)
					(length 3.81)
					(name "C02"
						(effects
							(font
								(size 1.27 1.27)
							)
						)
					)
					(number "C02"
						(effects
							(font
								(size 1.27 1.27)
							)
						)
					)
				)
				(pin passive line
					(at 0 -5.08 0)
					(length 3.81)
					(name "C03"
						(effects
							(font
								(size 1.27 1.27)
							)
						)
					)
					(number "C03"
						(effects
							(font
								(size 1.27 1.27)
							)
						)
					)
				)
				(pin passive line
					(at 0 -7.62 0)
					(length 3.81)
					(name "C04"
						(effects
							(font
								(size 1.27 1.27)
							)
						)
					)
					(number "C04"
						(effects
							(font
								(size 1.27 1.27)
							)
						)
					)
				)
				(pin passive line
					(at 0 -10.16 0)
					(length 3.81)
					(name "C05"
						(effects
							(font
								(size 1.27 1.27)
							)
						)
					)
					(number "C05"
						(effects
							(font
								(size 1.27 1.27)
							)
						)
					)
				)
				(pin passive line
					(at 0 -12.7 0)
					(length 3.81)
					(name "C06"
						(effects
							(font
								(size 1.27 1.27)
							)
						)
					)
					(number "C06"
						(effects
							(font
								(size 1.27 1.27)
							)
						)
					)
				)
				(pin passive line
					(at 0 -15.24 0)
					(length 3.81)
					(name "C07"
						(effects
							(font
								(size 1.27 1.27)
							)
						)
					)
					(number "C07"
						(effects
							(font
								(size 1.27 1.27)
							)
						)
					)
				)
				(pin passive line
					(at 0 -17.78 0)
					(length 3.81)
					(name "C08"
						(effects
							(font
								(size 1.27 1.27)
							)
						)
					)
					(number "C08"
						(effects
							(font
								(size 1.27 1.27)
							)
						)
					)
				)
				(pin passive line
					(at 0 -20.32 0)
					(length 3.81)
					(name "C09"
						(effects
							(font
								(size 1.27 1.27)
							)
						)
					)
					(number "C09"
						(effects
							(font
								(size 1.27 1.27)
							)
						)
					)
				)
				(pin passive line
					(at 0 -22.86 0)
					(length 3.81)
					(name "C10"
						(effects
							(font
								(size 1.27 1.27)
							)
						)
					)
					(number "C10"
						(effects
							(font
								(size 1.27 1.27)
							)
						)
					)
				)
				(pin passive line
					(at 0 -25.4 0)
					(length 3.81)
					(name "C11"
						(effects
							(font
								(size 1.27 1.27)
							)
						)
					)
					(number "C11"
						(effects
							(font
								(size 1.27 1.27)
							)
						)
					)
				)
				(pin passive line
					(at 0 -27.94 0)
					(length 3.81)
					(name "C12"
						(effects
							(font
								(size 1.27 1.27)
							)
						)
					)
					(number "C12"
						(effects
							(font
								(size 1.27 1.27)
							)
						)
					)
				)
				(pin passive line
					(at 0 -30.48 0)
					(length 3.81)
					(name "C13"
						(effects
							(font
								(size 1.27 1.27)
							)
						)
					)
					(number "C13"
						(effects
							(font
								(size 1.27 1.27)
							)
						)
					)
				)
				(pin passive line
					(at 0 -33.02 0)
					(length 3.81)
					(name "C14"
						(effects
							(font
								(size 1.27 1.27)
							)
						)
					)
					(number "C14"
						(effects
							(font
								(size 1.27 1.27)
							)
						)
					)
				)
				(pin passive line
					(at 0 -35.56 0)
					(length 3.81)
					(name "C15"
						(effects
							(font
								(size 1.27 1.27)
							)
						)
					)
					(number "C15"
						(effects
							(font
								(size 1.27 1.27)
							)
						)
					)
				)
				(pin passive line
					(at 0 -38.1 0)
					(length 3.81)
					(name "C16"
						(effects
							(font
								(size 1.27 1.27)
							)
						)
					)
					(number "C16"
						(effects
							(font
								(size 1.27 1.27)
							)
						)
					)
				)
				(pin passive line
					(at 0 -40.64 0)
					(length 3.81)
					(name "C17"
						(effects
							(font
								(size 1.27 1.27)
							)
						)
					)
					(number "C17"
						(effects
							(font
								(size 1.27 1.27)
							)
						)
					)
				)
				(pin passive line
					(at 0 -43.18 0)
					(length 3.81)
					(name "C18"
						(effects
							(font
								(size 1.27 1.27)
							)
						)
					)
					(number "C18"
						(effects
							(font
								(size 1.27 1.27)
							)
						)
					)
				)
				(pin passive line
					(at 0 -45.72 0)
					(length 3.81)
					(name "C19"
						(effects
							(font
								(size 1.27 1.27)
							)
						)
					)
					(number "C19"
						(effects
							(font
								(size 1.27 1.27)
							)
						)
					)
				)
				(pin passive line
					(at 0 -48.26 0)
					(length 3.81)
					(name "C20"
						(effects
							(font
								(size 1.27 1.27)
							)
						)
					)
					(number "C20"
						(effects
							(font
								(size 1.27 1.27)
							)
						)
					)
				)
				(pin passive line
					(at 0 -50.8 0)
					(length 3.81)
					(name "C21"
						(effects
							(font
								(size 1.27 1.27)
							)
						)
					)
					(number "C21"
						(effects
							(font
								(size 1.27 1.27)
							)
						)
					)
				)
				(pin passive line
					(at 0 -53.34 0)
					(length 3.81)
					(name "C22"
						(effects
							(font
								(size 1.27 1.27)
							)
						)
					)
					(number "C22"
						(effects
							(font
								(size 1.27 1.27)
							)
						)
					)
				)
				(pin passive line
					(at 0 -55.88 0)
					(length 3.81)
					(name "C23"
						(effects
							(font
								(size 1.27 1.27)
							)
						)
					)
					(number "C23"
						(effects
							(font
								(size 1.27 1.27)
							)
						)
					)
				)
				(pin passive line
					(at 0 -58.42 0)
					(length 3.81)
					(name "C24"
						(effects
							(font
								(size 1.27 1.27)
							)
						)
					)
					(number "C24"
						(effects
							(font
								(size 1.27 1.27)
							)
						)
					)
				)
				(pin passive line
					(at 0 -60.96 0)
					(length 3.81)
					(name "C25"
						(effects
							(font
								(size 1.27 1.27)
							)
						)
					)
					(number "C25"
						(effects
							(font
								(size 1.27 1.27)
							)
						)
					)
				)
				(pin passive line
					(at 0 -63.5 0)
					(length 3.81)
					(name "C26"
						(effects
							(font
								(size 1.27 1.27)
							)
						)
					)
					(number "C26"
						(effects
							(font
								(size 1.27 1.27)
							)
						)
					)
				)
				(pin passive line
					(at 0 -66.04 0)
					(length 3.81)
					(name "C27"
						(effects
							(font
								(size 1.27 1.27)
							)
						)
					)
					(number "C27"
						(effects
							(font
								(size 1.27 1.27)
							)
						)
					)
				)
				(pin passive line
					(at 0 -68.58 0)
					(length 3.81)
					(name "C28"
						(effects
							(font
								(size 1.27 1.27)
							)
						)
					)
					(number "C28"
						(effects
							(font
								(size 1.27 1.27)
							)
						)
					)
				)
				(pin passive line
					(at 0 -71.12 0)
					(length 3.81)
					(name "C29"
						(effects
							(font
								(size 1.27 1.27)
							)
						)
					)
					(number "C29"
						(effects
							(font
								(size 1.27 1.27)
							)
						)
					)
				)
				(pin passive line
					(at 0 -73.66 0)
					(length 3.81)
					(name "C30"
						(effects
							(font
								(size 1.27 1.27)
							)
						)
					)
					(number "C30"
						(effects
							(font
								(size 1.27 1.27)
							)
						)
					)
				)
				(pin passive line
					(at 0 -76.2 0)
					(length 3.81)
					(name "C31"
						(effects
							(font
								(size 1.27 1.27)
							)
						)
					)
					(number "C31"
						(effects
							(font
								(size 1.27 1.27)
							)
						)
					)
				)
				(pin passive line
					(at 0 -78.74 0)
					(length 3.81)
					(name "C32"
						(effects
							(font
								(size 1.27 1.27)
							)
						)
					)
					(number "C32"
						(effects
							(font
								(size 1.27 1.27)
							)
						)
					)
				)
				(pin passive line
					(at 0 -81.28 0)
					(length 3.81)
					(name "C33"
						(effects
							(font
								(size 1.27 1.27)
							)
						)
					)
					(number "C33"
						(effects
							(font
								(size 1.27 1.27)
							)
						)
					)
				)
				(pin passive line
					(at 0 -83.82 0)
					(length 3.81)
					(name "C34"
						(effects
							(font
								(size 1.27 1.27)
							)
						)
					)
					(number "C34"
						(effects
							(font
								(size 1.27 1.27)
							)
						)
					)
				)
				(pin passive line
					(at 0 -86.36 0)
					(length 3.81)
					(name "C35"
						(effects
							(font
								(size 1.27 1.27)
							)
						)
					)
					(number "C35"
						(effects
							(font
								(size 1.27 1.27)
							)
						)
					)
				)
				(pin passive line
					(at 0 -88.9 0)
					(length 3.81)
					(name "C36"
						(effects
							(font
								(size 1.27 1.27)
							)
						)
					)
					(number "C36"
						(effects
							(font
								(size 1.27 1.27)
							)
						)
					)
				)
				(pin passive line
					(at 0 -91.44 0)
					(length 3.81)
					(name "C37"
						(effects
							(font
								(size 1.27 1.27)
							)
						)
					)
					(number "C37"
						(effects
							(font
								(size 1.27 1.27)
							)
						)
					)
				)
				(pin passive line
					(at 0 -93.98 0)
					(length 3.81)
					(name "C38"
						(effects
							(font
								(size 1.27 1.27)
							)
						)
					)
					(number "C38"
						(effects
							(font
								(size 1.27 1.27)
							)
						)
					)
				)
				(pin passive line
					(at 0 -96.52 0)
					(length 3.81)
					(name "C39"
						(effects
							(font
								(size 1.27 1.27)
							)
						)
					)
					(number "C39"
						(effects
							(font
								(size 1.27 1.27)
							)
						)
					)
				)
				(pin passive line
					(at 0 -99.06 0)
					(length 3.81)
					(name "C40"
						(effects
							(font
								(size 1.27 1.27)
							)
						)
					)
					(number "C40"
						(effects
							(font
								(size 1.27 1.27)
							)
						)
					)
				)
				(pin passive line
					(at 22.86 0 180)
					(length 3.81)
					(name "D01"
						(effects
							(font
								(size 1.27 1.27)
							)
						)
					)
					(number "D01"
						(effects
							(font
								(size 1.27 1.27)
							)
						)
					)
				)
				(pin passive line
					(at 22.86 -2.54 180)
					(length 3.81)
					(name "D02"
						(effects
							(font
								(size 1.27 1.27)
							)
						)
					)
					(number "D02"
						(effects
							(font
								(size 1.27 1.27)
							)
						)
					)
				)
				(pin passive line
					(at 22.86 -5.08 180)
					(length 3.81)
					(name "D03"
						(effects
							(font
								(size 1.27 1.27)
							)
						)
					)
					(number "D03"
						(effects
							(font
								(size 1.27 1.27)
							)
						)
					)
				)
				(pin passive line
					(at 22.86 -7.62 180)
					(length 3.81)
					(name "D04"
						(effects
							(font
								(size 1.27 1.27)
							)
						)
					)
					(number "D04"
						(effects
							(font
								(size 1.27 1.27)
							)
						)
					)
				)
				(pin passive line
					(at 22.86 -10.16 180)
					(length 3.81)
					(name "D05"
						(effects
							(font
								(size 1.27 1.27)
							)
						)
					)
					(number "D05"
						(effects
							(font
								(size 1.27 1.27)
							)
						)
					)
				)
				(pin passive line
					(at 22.86 -12.7 180)
					(length 3.81)
					(name "D06"
						(effects
							(font
								(size 1.27 1.27)
							)
						)
					)
					(number "D06"
						(effects
							(font
								(size 1.27 1.27)
							)
						)
					)
				)
				(pin passive line
					(at 22.86 -15.24 180)
					(length 3.81)
					(name "D07"
						(effects
							(font
								(size 1.27 1.27)
							)
						)
					)
					(number "D07"
						(effects
							(font
								(size 1.27 1.27)
							)
						)
					)
				)
				(pin passive line
					(at 22.86 -17.78 180)
					(length 3.81)
					(name "D08"
						(effects
							(font
								(size 1.27 1.27)
							)
						)
					)
					(number "D08"
						(effects
							(font
								(size 1.27 1.27)
							)
						)
					)
				)
				(pin passive line
					(at 22.86 -20.32 180)
					(length 3.81)
					(name "D09"
						(effects
							(font
								(size 1.27 1.27)
							)
						)
					)
					(number "D09"
						(effects
							(font
								(size 1.27 1.27)
							)
						)
					)
				)
				(pin passive line
					(at 22.86 -22.86 180)
					(length 3.81)
					(name "D10"
						(effects
							(font
								(size 1.27 1.27)
							)
						)
					)
					(number "D10"
						(effects
							(font
								(size 1.27 1.27)
							)
						)
					)
				)
				(pin passive line
					(at 22.86 -25.4 180)
					(length 3.81)
					(name "D11"
						(effects
							(font
								(size 1.27 1.27)
							)
						)
					)
					(number "D11"
						(effects
							(font
								(size 1.27 1.27)
							)
						)
					)
				)
				(pin passive line
					(at 22.86 -27.94 180)
					(length 3.81)
					(name "D12"
						(effects
							(font
								(size 1.27 1.27)
							)
						)
					)
					(number "D12"
						(effects
							(font
								(size 1.27 1.27)
							)
						)
					)
				)
				(pin passive line
					(at 22.86 -30.48 180)
					(length 3.81)
					(name "D13"
						(effects
							(font
								(size 1.27 1.27)
							)
						)
					)
					(number "D13"
						(effects
							(font
								(size 1.27 1.27)
							)
						)
					)
				)
				(pin passive line
					(at 22.86 -33.02 180)
					(length 3.81)
					(name "D14"
						(effects
							(font
								(size 1.27 1.27)
							)
						)
					)
					(number "D14"
						(effects
							(font
								(size 1.27 1.27)
							)
						)
					)
				)
				(pin passive line
					(at 22.86 -35.56 180)
					(length 3.81)
					(name "D15"
						(effects
							(font
								(size 1.27 1.27)
							)
						)
					)
					(number "D15"
						(effects
							(font
								(size 1.27 1.27)
							)
						)
					)
				)
				(pin passive line
					(at 22.86 -38.1 180)
					(length 3.81)
					(name "D16"
						(effects
							(font
								(size 1.27 1.27)
							)
						)
					)
					(number "D16"
						(effects
							(font
								(size 1.27 1.27)
							)
						)
					)
				)
				(pin passive line
					(at 22.86 -40.64 180)
					(length 3.81)
					(name "D17"
						(effects
							(font
								(size 1.27 1.27)
							)
						)
					)
					(number "D17"
						(effects
							(font
								(size 1.27 1.27)
							)
						)
					)
				)
				(pin passive line
					(at 22.86 -43.18 180)
					(length 3.81)
					(name "D18"
						(effects
							(font
								(size 1.27 1.27)
							)
						)
					)
					(number "D18"
						(effects
							(font
								(size 1.27 1.27)
							)
						)
					)
				)
				(pin passive line
					(at 22.86 -45.72 180)
					(length 3.81)
					(name "D19"
						(effects
							(font
								(size 1.27 1.27)
							)
						)
					)
					(number "D19"
						(effects
							(font
								(size 1.27 1.27)
							)
						)
					)
				)
				(pin passive line
					(at 22.86 -48.26 180)
					(length 3.81)
					(name "D20"
						(effects
							(font
								(size 1.27 1.27)
							)
						)
					)
					(number "D20"
						(effects
							(font
								(size 1.27 1.27)
							)
						)
					)
				)
				(pin passive line
					(at 22.86 -50.8 180)
					(length 3.81)
					(name "D21"
						(effects
							(font
								(size 1.27 1.27)
							)
						)
					)
					(number "D21"
						(effects
							(font
								(size 1.27 1.27)
							)
						)
					)
				)
				(pin passive line
					(at 22.86 -53.34 180)
					(length 3.81)
					(name "D22"
						(effects
							(font
								(size 1.27 1.27)
							)
						)
					)
					(number "D22"
						(effects
							(font
								(size 1.27 1.27)
							)
						)
					)
				)
				(pin passive line
					(at 22.86 -55.88 180)
					(length 3.81)
					(name "D23"
						(effects
							(font
								(size 1.27 1.27)
							)
						)
					)
					(number "D23"
						(effects
							(font
								(size 1.27 1.27)
							)
						)
					)
				)
				(pin passive line
					(at 22.86 -58.42 180)
					(length 3.81)
					(name "D24"
						(effects
							(font
								(size 1.27 1.27)
							)
						)
					)
					(number "D24"
						(effects
							(font
								(size 1.27 1.27)
							)
						)
					)
				)
				(pin passive line
					(at 22.86 -60.96 180)
					(length 3.81)
					(name "D25"
						(effects
							(font
								(size 1.27 1.27)
							)
						)
					)
					(number "D25"
						(effects
							(font
								(size 1.27 1.27)
							)
						)
					)
				)
				(pin passive line
					(at 22.86 -63.5 180)
					(length 3.81)
					(name "D26"
						(effects
							(font
								(size 1.27 1.27)
							)
						)
					)
					(number "D26"
						(effects
							(font
								(size 1.27 1.27)
							)
						)
					)
				)
				(pin passive line
					(at 22.86 -66.04 180)
					(length 3.81)
					(name "D27"
						(effects
							(font
								(size 1.27 1.27)
							)
						)
					)
					(number "D27"
						(effects
							(font
								(size 1.27 1.27)
							)
						)
					)
				)
				(pin passive line
					(at 22.86 -68.58 180)
					(length 3.81)
					(name "D28"
						(effects
							(font
								(size 1.27 1.27)
							)
						)
					)
					(number "D28"
						(effects
							(font
								(size 1.27 1.27)
							)
						)
					)
				)
				(pin passive line
					(at 22.86 -71.12 180)
					(length 3.81)
					(name "D29"
						(effects
							(font
								(size 1.27 1.27)
							)
						)
					)
					(number "D29"
						(effects
							(font
								(size 1.27 1.27)
							)
						)
					)
				)
				(pin passive line
					(at 22.86 -73.66 180)
					(length 3.81)
					(name "D30"
						(effects
							(font
								(size 1.27 1.27)
							)
						)
					)
					(number "D30"
						(effects
							(font
								(size 1.27 1.27)
							)
						)
					)
				)
				(pin passive line
					(at 22.86 -76.2 180)
					(length 3.81)
					(name "D31"
						(effects
							(font
								(size 1.27 1.27)
							)
						)
					)
					(number "D31"
						(effects
							(font
								(size 1.27 1.27)
							)
						)
					)
				)
				(pin passive line
					(at 22.86 -78.74 180)
					(length 3.81)
					(name "D32"
						(effects
							(font
								(size 1.27 1.27)
							)
						)
					)
					(number "D32"
						(effects
							(font
								(size 1.27 1.27)
							)
						)
					)
				)
				(pin passive line
					(at 22.86 -81.28 180)
					(length 3.81)
					(name "D33"
						(effects
							(font
								(size 1.27 1.27)
							)
						)
					)
					(number "D33"
						(effects
							(font
								(size 1.27 1.27)
							)
						)
					)
				)
				(pin passive line
					(at 22.86 -83.82 180)
					(length 3.81)
					(name "D34"
						(effects
							(font
								(size 1.27 1.27)
							)
						)
					)
					(number "D34"
						(effects
							(font
								(size 1.27 1.27)
							)
						)
					)
				)
				(pin passive line
					(at 22.86 -86.36 180)
					(length 3.81)
					(name "D35"
						(effects
							(font
								(size 1.27 1.27)
							)
						)
					)
					(number "D35"
						(effects
							(font
								(size 1.27 1.27)
							)
						)
					)
				)
				(pin passive line
					(at 22.86 -88.9 180)
					(length 3.81)
					(name "D36"
						(effects
							(font
								(size 1.27 1.27)
							)
						)
					)
					(number "D36"
						(effects
							(font
								(size 1.27 1.27)
							)
						)
					)
				)
				(pin passive line
					(at 22.86 -91.44 180)
					(length 3.81)
					(name "D37"
						(effects
							(font
								(size 1.27 1.27)
							)
						)
					)
					(number "D37"
						(effects
							(font
								(size 1.27 1.27)
							)
						)
					)
				)
				(pin passive line
					(at 22.86 -93.98 180)
					(length 3.81)
					(name "D38"
						(effects
							(font
								(size 1.27 1.27)
							)
						)
					)
					(number "D38"
						(effects
							(font
								(size 1.27 1.27)
							)
						)
					)
				)
				(pin passive line
					(at 22.86 -96.52 180)
					(length 3.81)
					(name "D39"
						(effects
							(font
								(size 1.27 1.27)
							)
						)
					)
					(number "D39"
						(effects
							(font
								(size 1.27 1.27)
							)
						)
					)
				)
				(pin passive line
					(at 22.86 -99.06 180)
					(length 3.81)
					(name "D40"
						(effects
							(font
								(size 1.27 1.27)
							)
						)
					)
					(number "D40"
						(effects
							(font
								(size 1.27 1.27)
							)
						)
					)
				)
			)
			(symbol "ASP-208571-01_mounting_holes_4_1"
				(rectangle
					(start 3.81 -101.6)
					(end 19.05 2.54)
					(stroke
						(width 0.254)
						(type default)
					)
					(fill
						(type background)
					)
				)
				(pin passive line
					(at 0 0 0)
					(length 3.81)
					(name "E01"
						(effects
							(font
								(size 1.27 1.27)
							)
						)
					)
					(number "E01"
						(effects
							(font
								(size 1.27 1.27)
							)
						)
					)
				)
				(pin passive line
					(at 0 -2.54 0)
					(length 3.81)
					(name "E02"
						(effects
							(font
								(size 1.27 1.27)
							)
						)
					)
					(number "E02"
						(effects
							(font
								(size 1.27 1.27)
							)
						)
					)
				)
				(pin passive line
					(at 0 -5.08 0)
					(length 3.81)
					(name "E03"
						(effects
							(font
								(size 1.27 1.27)
							)
						)
					)
					(number "E03"
						(effects
							(font
								(size 1.27 1.27)
							)
						)
					)
				)
				(pin passive line
					(at 0 -7.62 0)
					(length 3.81)
					(name "E04"
						(effects
							(font
								(size 1.27 1.27)
							)
						)
					)
					(number "E04"
						(effects
							(font
								(size 1.27 1.27)
							)
						)
					)
				)
				(pin passive line
					(at 0 -10.16 0)
					(length 3.81)
					(name "E05"
						(effects
							(font
								(size 1.27 1.27)
							)
						)
					)
					(number "E05"
						(effects
							(font
								(size 1.27 1.27)
							)
						)
					)
				)
				(pin passive line
					(at 0 -12.7 0)
					(length 3.81)
					(name "E06"
						(effects
							(font
								(size 1.27 1.27)
							)
						)
					)
					(number "E06"
						(effects
							(font
								(size 1.27 1.27)
							)
						)
					)
				)
				(pin passive line
					(at 0 -15.24 0)
					(length 3.81)
					(name "E07"
						(effects
							(font
								(size 1.27 1.27)
							)
						)
					)
					(number "E07"
						(effects
							(font
								(size 1.27 1.27)
							)
						)
					)
				)
				(pin passive line
					(at 0 -17.78 0)
					(length 3.81)
					(name "E08"
						(effects
							(font
								(size 1.27 1.27)
							)
						)
					)
					(number "E08"
						(effects
							(font
								(size 1.27 1.27)
							)
						)
					)
				)
				(pin passive line
					(at 0 -20.32 0)
					(length 3.81)
					(name "E09"
						(effects
							(font
								(size 1.27 1.27)
							)
						)
					)
					(number "E09"
						(effects
							(font
								(size 1.27 1.27)
							)
						)
					)
				)
				(pin passive line
					(at 0 -22.86 0)
					(length 3.81)
					(name "E10"
						(effects
							(font
								(size 1.27 1.27)
							)
						)
					)
					(number "E10"
						(effects
							(font
								(size 1.27 1.27)
							)
						)
					)
				)
				(pin passive line
					(at 0 -25.4 0)
					(length 3.81)
					(name "E11"
						(effects
							(font
								(size 1.27 1.27)
							)
						)
					)
					(number "E11"
						(effects
							(font
								(size 1.27 1.27)
							)
						)
					)
				)
				(pin passive line
					(at 0 -27.94 0)
					(length 3.81)
					(name "E12"
						(effects
							(font
								(size 1.27 1.27)
							)
						)
					)
					(number "E12"
						(effects
							(font
								(size 1.27 1.27)
							)
						)
					)
				)
				(pin passive line
					(at 0 -30.48 0)
					(length 3.81)
					(name "E13"
						(effects
							(font
								(size 1.27 1.27)
							)
						)
					)
					(number "E13"
						(effects
							(font
								(size 1.27 1.27)
							)
						)
					)
				)
				(pin passive line
					(at 0 -33.02 0)
					(length 3.81)
					(name "E14"
						(effects
							(font
								(size 1.27 1.27)
							)
						)
					)
					(number "E14"
						(effects
							(font
								(size 1.27 1.27)
							)
						)
					)
				)
				(pin passive line
					(at 0 -35.56 0)
					(length 3.81)
					(name "E15"
						(effects
							(font
								(size 1.27 1.27)
							)
						)
					)
					(number "E15"
						(effects
							(font
								(size 1.27 1.27)
							)
						)
					)
				)
				(pin passive line
					(at 0 -38.1 0)
					(length 3.81)
					(name "E16"
						(effects
							(font
								(size 1.27 1.27)
							)
						)
					)
					(number "E16"
						(effects
							(font
								(size 1.27 1.27)
							)
						)
					)
				)
				(pin passive line
					(at 0 -40.64 0)
					(length 3.81)
					(name "E17"
						(effects
							(font
								(size 1.27 1.27)
							)
						)
					)
					(number "E17"
						(effects
							(font
								(size 1.27 1.27)
							)
						)
					)
				)
				(pin passive line
					(at 0 -43.18 0)
					(length 3.81)
					(name "E18"
						(effects
							(font
								(size 1.27 1.27)
							)
						)
					)
					(number "E18"
						(effects
							(font
								(size 1.27 1.27)
							)
						)
					)
				)
				(pin passive line
					(at 0 -45.72 0)
					(length 3.81)
					(name "E19"
						(effects
							(font
								(size 1.27 1.27)
							)
						)
					)
					(number "E19"
						(effects
							(font
								(size 1.27 1.27)
							)
						)
					)
				)
				(pin passive line
					(at 0 -48.26 0)
					(length 3.81)
					(name "E20"
						(effects
							(font
								(size 1.27 1.27)
							)
						)
					)
					(number "E20"
						(effects
							(font
								(size 1.27 1.27)
							)
						)
					)
				)
				(pin passive line
					(at 0 -50.8 0)
					(length 3.81)
					(name "E21"
						(effects
							(font
								(size 1.27 1.27)
							)
						)
					)
					(number "E21"
						(effects
							(font
								(size 1.27 1.27)
							)
						)
					)
				)
				(pin passive line
					(at 0 -53.34 0)
					(length 3.81)
					(name "E22"
						(effects
							(font
								(size 1.27 1.27)
							)
						)
					)
					(number "E22"
						(effects
							(font
								(size 1.27 1.27)
							)
						)
					)
				)
				(pin passive line
					(at 0 -55.88 0)
					(length 3.81)
					(name "E23"
						(effects
							(font
								(size 1.27 1.27)
							)
						)
					)
					(number "E23"
						(effects
							(font
								(size 1.27 1.27)
							)
						)
					)
				)
				(pin passive line
					(at 0 -58.42 0)
					(length 3.81)
					(name "E24"
						(effects
							(font
								(size 1.27 1.27)
							)
						)
					)
					(number "E24"
						(effects
							(font
								(size 1.27 1.27)
							)
						)
					)
				)
				(pin passive line
					(at 0 -60.96 0)
					(length 3.81)
					(name "E25"
						(effects
							(font
								(size 1.27 1.27)
							)
						)
					)
					(number "E25"
						(effects
							(font
								(size 1.27 1.27)
							)
						)
					)
				)
				(pin passive line
					(at 0 -63.5 0)
					(length 3.81)
					(name "E26"
						(effects
							(font
								(size 1.27 1.27)
							)
						)
					)
					(number "E26"
						(effects
							(font
								(size 1.27 1.27)
							)
						)
					)
				)
				(pin passive line
					(at 0 -66.04 0)
					(length 3.81)
					(name "E27"
						(effects
							(font
								(size 1.27 1.27)
							)
						)
					)
					(number "E27"
						(effects
							(font
								(size 1.27 1.27)
							)
						)
					)
				)
				(pin passive line
					(at 0 -68.58 0)
					(length 3.81)
					(name "E28"
						(effects
							(font
								(size 1.27 1.27)
							)
						)
					)
					(number "E28"
						(effects
							(font
								(size 1.27 1.27)
							)
						)
					)
				)
				(pin passive line
					(at 0 -71.12 0)
					(length 3.81)
					(name "E29"
						(effects
							(font
								(size 1.27 1.27)
							)
						)
					)
					(number "E29"
						(effects
							(font
								(size 1.27 1.27)
							)
						)
					)
				)
				(pin passive line
					(at 0 -73.66 0)
					(length 3.81)
					(name "E30"
						(effects
							(font
								(size 1.27 1.27)
							)
						)
					)
					(number "E30"
						(effects
							(font
								(size 1.27 1.27)
							)
						)
					)
				)
				(pin passive line
					(at 0 -76.2 0)
					(length 3.81)
					(name "E31"
						(effects
							(font
								(size 1.27 1.27)
							)
						)
					)
					(number "E31"
						(effects
							(font
								(size 1.27 1.27)
							)
						)
					)
				)
				(pin passive line
					(at 0 -78.74 0)
					(length 3.81)
					(name "E32"
						(effects
							(font
								(size 1.27 1.27)
							)
						)
					)
					(number "E32"
						(effects
							(font
								(size 1.27 1.27)
							)
						)
					)
				)
				(pin passive line
					(at 0 -81.28 0)
					(length 3.81)
					(name "E33"
						(effects
							(font
								(size 1.27 1.27)
							)
						)
					)
					(number "E33"
						(effects
							(font
								(size 1.27 1.27)
							)
						)
					)
				)
				(pin passive line
					(at 0 -83.82 0)
					(length 3.81)
					(name "E34"
						(effects
							(font
								(size 1.27 1.27)
							)
						)
					)
					(number "E34"
						(effects
							(font
								(size 1.27 1.27)
							)
						)
					)
				)
				(pin passive line
					(at 0 -86.36 0)
					(length 3.81)
					(name "E35"
						(effects
							(font
								(size 1.27 1.27)
							)
						)
					)
					(number "E35"
						(effects
							(font
								(size 1.27 1.27)
							)
						)
					)
				)
				(pin passive line
					(at 0 -88.9 0)
					(length 3.81)
					(name "E36"
						(effects
							(font
								(size 1.27 1.27)
							)
						)
					)
					(number "E36"
						(effects
							(font
								(size 1.27 1.27)
							)
						)
					)
				)
				(pin passive line
					(at 0 -91.44 0)
					(length 3.81)
					(name "E37"
						(effects
							(font
								(size 1.27 1.27)
							)
						)
					)
					(number "E37"
						(effects
							(font
								(size 1.27 1.27)
							)
						)
					)
				)
				(pin passive line
					(at 0 -93.98 0)
					(length 3.81)
					(name "E38"
						(effects
							(font
								(size 1.27 1.27)
							)
						)
					)
					(number "E38"
						(effects
							(font
								(size 1.27 1.27)
							)
						)
					)
				)
				(pin passive line
					(at 0 -96.52 0)
					(length 3.81)
					(name "E39"
						(effects
							(font
								(size 1.27 1.27)
							)
						)
					)
					(number "E39"
						(effects
							(font
								(size 1.27 1.27)
							)
						)
					)
				)
				(pin passive line
					(at 0 -99.06 0)
					(length 3.81)
					(name "E40"
						(effects
							(font
								(size 1.27 1.27)
							)
						)
					)
					(number "E40"
						(effects
							(font
								(size 1.27 1.27)
							)
						)
					)
				)
				(pin passive line
					(at 22.86 0 180)
					(length 3.81)
					(name "F01"
						(effects
							(font
								(size 1.27 1.27)
							)
						)
					)
					(number "F01"
						(effects
							(font
								(size 1.27 1.27)
							)
						)
					)
				)
				(pin passive line
					(at 22.86 -2.54 180)
					(length 3.81)
					(name "F02"
						(effects
							(font
								(size 1.27 1.27)
							)
						)
					)
					(number "F02"
						(effects
							(font
								(size 1.27 1.27)
							)
						)
					)
				)
				(pin passive line
					(at 22.86 -5.08 180)
					(length 3.81)
					(name "F03"
						(effects
							(font
								(size 1.27 1.27)
							)
						)
					)
					(number "F03"
						(effects
							(font
								(size 1.27 1.27)
							)
						)
					)
				)
				(pin passive line
					(at 22.86 -7.62 180)
					(length 3.81)
					(name "F04"
						(effects
							(font
								(size 1.27 1.27)
							)
						)
					)
					(number "F04"
						(effects
							(font
								(size 1.27 1.27)
							)
						)
					)
				)
				(pin passive line
					(at 22.86 -10.16 180)
					(length 3.81)
					(name "F05"
						(effects
							(font
								(size 1.27 1.27)
							)
						)
					)
					(number "F05"
						(effects
							(font
								(size 1.27 1.27)
							)
						)
					)
				)
				(pin passive line
					(at 22.86 -12.7 180)
					(length 3.81)
					(name "F06"
						(effects
							(font
								(size 1.27 1.27)
							)
						)
					)
					(number "F06"
						(effects
							(font
								(size 1.27 1.27)
							)
						)
					)
				)
				(pin passive line
					(at 22.86 -15.24 180)
					(length 3.81)
					(name "F07"
						(effects
							(font
								(size 1.27 1.27)
							)
						)
					)
					(number "F07"
						(effects
							(font
								(size 1.27 1.27)
							)
						)
					)
				)
				(pin passive line
					(at 22.86 -17.78 180)
					(length 3.81)
					(name "F08"
						(effects
							(font
								(size 1.27 1.27)
							)
						)
					)
					(number "F08"
						(effects
							(font
								(size 1.27 1.27)
							)
						)
					)
				)
				(pin passive line
					(at 22.86 -20.32 180)
					(length 3.81)
					(name "F09"
						(effects
							(font
								(size 1.27 1.27)
							)
						)
					)
					(number "F09"
						(effects
							(font
								(size 1.27 1.27)
							)
						)
					)
				)
				(pin passive line
					(at 22.86 -22.86 180)
					(length 3.81)
					(name "F10"
						(effects
							(font
								(size 1.27 1.27)
							)
						)
					)
					(number "F10"
						(effects
							(font
								(size 1.27 1.27)
							)
						)
					)
				)
				(pin passive line
					(at 22.86 -25.4 180)
					(length 3.81)
					(name "F11"
						(effects
							(font
								(size 1.27 1.27)
							)
						)
					)
					(number "F11"
						(effects
							(font
								(size 1.27 1.27)
							)
						)
					)
				)
				(pin passive line
					(at 22.86 -27.94 180)
					(length 3.81)
					(name "F12"
						(effects
							(font
								(size 1.27 1.27)
							)
						)
					)
					(number "F12"
						(effects
							(font
								(size 1.27 1.27)
							)
						)
					)
				)
				(pin passive line
					(at 22.86 -30.48 180)
					(length 3.81)
					(name "F13"
						(effects
							(font
								(size 1.27 1.27)
							)
						)
					)
					(number "F13"
						(effects
							(font
								(size 1.27 1.27)
							)
						)
					)
				)
				(pin passive line
					(at 22.86 -33.02 180)
					(length 3.81)
					(name "F14"
						(effects
							(font
								(size 1.27 1.27)
							)
						)
					)
					(number "F14"
						(effects
							(font
								(size 1.27 1.27)
							)
						)
					)
				)
				(pin passive line
					(at 22.86 -35.56 180)
					(length 3.81)
					(name "F15"
						(effects
							(font
								(size 1.27 1.27)
							)
						)
					)
					(number "F15"
						(effects
							(font
								(size 1.27 1.27)
							)
						)
					)
				)
				(pin passive line
					(at 22.86 -38.1 180)
					(length 3.81)
					(name "F16"
						(effects
							(font
								(size 1.27 1.27)
							)
						)
					)
					(number "F16"
						(effects
							(font
								(size 1.27 1.27)
							)
						)
					)
				)
				(pin passive line
					(at 22.86 -40.64 180)
					(length 3.81)
					(name "F17"
						(effects
							(font
								(size 1.27 1.27)
							)
						)
					)
					(number "F17"
						(effects
							(font
								(size 1.27 1.27)
							)
						)
					)
				)
				(pin passive line
					(at 22.86 -43.18 180)
					(length 3.81)
					(name "F18"
						(effects
							(font
								(size 1.27 1.27)
							)
						)
					)
					(number "F18"
						(effects
							(font
								(size 1.27 1.27)
							)
						)
					)
				)
				(pin passive line
					(at 22.86 -45.72 180)
					(length 3.81)
					(name "F19"
						(effects
							(font
								(size 1.27 1.27)
							)
						)
					)
					(number "F19"
						(effects
							(font
								(size 1.27 1.27)
							)
						)
					)
				)
				(pin passive line
					(at 22.86 -48.26 180)
					(length 3.81)
					(name "F20"
						(effects
							(font
								(size 1.27 1.27)
							)
						)
					)
					(number "F20"
						(effects
							(font
								(size 1.27 1.27)
							)
						)
					)
				)
				(pin passive line
					(at 22.86 -50.8 180)
					(length 3.81)
					(name "F21"
						(effects
							(font
								(size 1.27 1.27)
							)
						)
					)
					(number "F21"
						(effects
							(font
								(size 1.27 1.27)
							)
						)
					)
				)
				(pin passive line
					(at 22.86 -53.34 180)
					(length 3.81)
					(name "F22"
						(effects
							(font
								(size 1.27 1.27)
							)
						)
					)
					(number "F22"
						(effects
							(font
								(size 1.27 1.27)
							)
						)
					)
				)
				(pin passive line
					(at 22.86 -55.88 180)
					(length 3.81)
					(name "F23"
						(effects
							(font
								(size 1.27 1.27)
							)
						)
					)
					(number "F23"
						(effects
							(font
								(size 1.27 1.27)
							)
						)
					)
				)
				(pin passive line
					(at 22.86 -58.42 180)
					(length 3.81)
					(name "F24"
						(effects
							(font
								(size 1.27 1.27)
							)
						)
					)
					(number "F24"
						(effects
							(font
								(size 1.27 1.27)
							)
						)
					)
				)
				(pin passive line
					(at 22.86 -60.96 180)
					(length 3.81)
					(name "F25"
						(effects
							(font
								(size 1.27 1.27)
							)
						)
					)
					(number "F25"
						(effects
							(font
								(size 1.27 1.27)
							)
						)
					)
				)
				(pin passive line
					(at 22.86 -63.5 180)
					(length 3.81)
					(name "F26"
						(effects
							(font
								(size 1.27 1.27)
							)
						)
					)
					(number "F26"
						(effects
							(font
								(size 1.27 1.27)
							)
						)
					)
				)
				(pin passive line
					(at 22.86 -66.04 180)
					(length 3.81)
					(name "F27"
						(effects
							(font
								(size 1.27 1.27)
							)
						)
					)
					(number "F27"
						(effects
							(font
								(size 1.27 1.27)
							)
						)
					)
				)
				(pin passive line
					(at 22.86 -68.58 180)
					(length 3.81)
					(name "F28"
						(effects
							(font
								(size 1.27 1.27)
							)
						)
					)
					(number "F28"
						(effects
							(font
								(size 1.27 1.27)
							)
						)
					)
				)
				(pin passive line
					(at 22.86 -71.12 180)
					(length 3.81)
					(name "F29"
						(effects
							(font
								(size 1.27 1.27)
							)
						)
					)
					(number "F29"
						(effects
							(font
								(size 1.27 1.27)
							)
						)
					)
				)
				(pin passive line
					(at 22.86 -73.66 180)
					(length 3.81)
					(name "F30"
						(effects
							(font
								(size 1.27 1.27)
							)
						)
					)
					(number "F30"
						(effects
							(font
								(size 1.27 1.27)
							)
						)
					)
				)
				(pin passive line
					(at 22.86 -76.2 180)
					(length 3.81)
					(name "F31"
						(effects
							(font
								(size 1.27 1.27)
							)
						)
					)
					(number "F31"
						(effects
							(font
								(size 1.27 1.27)
							)
						)
					)
				)
				(pin passive line
					(at 22.86 -78.74 180)
					(length 3.81)
					(name "F32"
						(effects
							(font
								(size 1.27 1.27)
							)
						)
					)
					(number "F32"
						(effects
							(font
								(size 1.27 1.27)
							)
						)
					)
				)
				(pin passive line
					(at 22.86 -81.28 180)
					(length 3.81)
					(name "F33"
						(effects
							(font
								(size 1.27 1.27)
							)
						)
					)
					(number "F33"
						(effects
							(font
								(size 1.27 1.27)
							)
						)
					)
				)
				(pin passive line
					(at 22.86 -83.82 180)
					(length 3.81)
					(name "F34"
						(effects
							(font
								(size 1.27 1.27)
							)
						)
					)
					(number "F34"
						(effects
							(font
								(size 1.27 1.27)
							)
						)
					)
				)
				(pin passive line
					(at 22.86 -86.36 180)
					(length 3.81)
					(name "F35"
						(effects
							(font
								(size 1.27 1.27)
							)
						)
					)
					(number "F35"
						(effects
							(font
								(size 1.27 1.27)
							)
						)
					)
				)
				(pin passive line
					(at 22.86 -88.9 180)
					(length 3.81)
					(name "F36"
						(effects
							(font
								(size 1.27 1.27)
							)
						)
					)
					(number "F36"
						(effects
							(font
								(size 1.27 1.27)
							)
						)
					)
				)
				(pin passive line
					(at 22.86 -91.44 180)
					(length 3.81)
					(name "F37"
						(effects
							(font
								(size 1.27 1.27)
							)
						)
					)
					(number "F37"
						(effects
							(font
								(size 1.27 1.27)
							)
						)
					)
				)
				(pin passive line
					(at 22.86 -93.98 180)
					(length 3.81)
					(name "F38"
						(effects
							(font
								(size 1.27 1.27)
							)
						)
					)
					(number "F38"
						(effects
							(font
								(size 1.27 1.27)
							)
						)
					)
				)
				(pin passive line
					(at 22.86 -96.52 180)
					(length 3.81)
					(name "F39"
						(effects
							(font
								(size 1.27 1.27)
							)
						)
					)
					(number "F39"
						(effects
							(font
								(size 1.27 1.27)
							)
						)
					)
				)
				(pin passive line
					(at 22.86 -99.06 180)
					(length 3.81)
					(name "F40"
						(effects
							(font
								(size 1.27 1.27)
							)
						)
					)
					(number "F40"
						(effects
							(font
								(size 1.27 1.27)
							)
						)
					)
				)
			)
			(symbol "ASP-208571-01_mounting_holes_5_1"
				(rectangle
					(start 3.81 -101.6)
					(end 19.05 2.54)
					(stroke
						(width 0.254)
						(type default)
					)
					(fill
						(type background)
					)
				)
				(pin passive line
					(at 0 0 0)
					(length 3.81)
					(name "G01"
						(effects
							(font
								(size 1.27 1.27)
							)
						)
					)
					(number "G01"
						(effects
							(font
								(size 1.27 1.27)
							)
						)
					)
				)
				(pin passive line
					(at 0 -2.54 0)
					(length 3.81)
					(name "G02"
						(effects
							(font
								(size 1.27 1.27)
							)
						)
					)
					(number "G02"
						(effects
							(font
								(size 1.27 1.27)
							)
						)
					)
				)
				(pin passive line
					(at 0 -5.08 0)
					(length 3.81)
					(name "G03"
						(effects
							(font
								(size 1.27 1.27)
							)
						)
					)
					(number "G03"
						(effects
							(font
								(size 1.27 1.27)
							)
						)
					)
				)
				(pin passive line
					(at 0 -7.62 0)
					(length 3.81)
					(name "G04"
						(effects
							(font
								(size 1.27 1.27)
							)
						)
					)
					(number "G04"
						(effects
							(font
								(size 1.27 1.27)
							)
						)
					)
				)
				(pin passive line
					(at 0 -10.16 0)
					(length 3.81)
					(name "G05"
						(effects
							(font
								(size 1.27 1.27)
							)
						)
					)
					(number "G05"
						(effects
							(font
								(size 1.27 1.27)
							)
						)
					)
				)
				(pin passive line
					(at 0 -12.7 0)
					(length 3.81)
					(name "G06"
						(effects
							(font
								(size 1.27 1.27)
							)
						)
					)
					(number "G06"
						(effects
							(font
								(size 1.27 1.27)
							)
						)
					)
				)
				(pin passive line
					(at 0 -15.24 0)
					(length 3.81)
					(name "G07"
						(effects
							(font
								(size 1.27 1.27)
							)
						)
					)
					(number "G07"
						(effects
							(font
								(size 1.27 1.27)
							)
						)
					)
				)
				(pin passive line
					(at 0 -17.78 0)
					(length 3.81)
					(name "G08"
						(effects
							(font
								(size 1.27 1.27)
							)
						)
					)
					(number "G08"
						(effects
							(font
								(size 1.27 1.27)
							)
						)
					)
				)
				(pin passive line
					(at 0 -20.32 0)
					(length 3.81)
					(name "G09"
						(effects
							(font
								(size 1.27 1.27)
							)
						)
					)
					(number "G09"
						(effects
							(font
								(size 1.27 1.27)
							)
						)
					)
				)
				(pin passive line
					(at 0 -22.86 0)
					(length 3.81)
					(name "G10"
						(effects
							(font
								(size 1.27 1.27)
							)
						)
					)
					(number "G10"
						(effects
							(font
								(size 1.27 1.27)
							)
						)
					)
				)
				(pin passive line
					(at 0 -25.4 0)
					(length 3.81)
					(name "G11"
						(effects
							(font
								(size 1.27 1.27)
							)
						)
					)
					(number "G11"
						(effects
							(font
								(size 1.27 1.27)
							)
						)
					)
				)
				(pin passive line
					(at 0 -27.94 0)
					(length 3.81)
					(name "G12"
						(effects
							(font
								(size 1.27 1.27)
							)
						)
					)
					(number "G12"
						(effects
							(font
								(size 1.27 1.27)
							)
						)
					)
				)
				(pin passive line
					(at 0 -30.48 0)
					(length 3.81)
					(name "G13"
						(effects
							(font
								(size 1.27 1.27)
							)
						)
					)
					(number "G13"
						(effects
							(font
								(size 1.27 1.27)
							)
						)
					)
				)
				(pin passive line
					(at 0 -33.02 0)
					(length 3.81)
					(name "G14"
						(effects
							(font
								(size 1.27 1.27)
							)
						)
					)
					(number "G14"
						(effects
							(font
								(size 1.27 1.27)
							)
						)
					)
				)
				(pin passive line
					(at 0 -35.56 0)
					(length 3.81)
					(name "G15"
						(effects
							(font
								(size 1.27 1.27)
							)
						)
					)
					(number "G15"
						(effects
							(font
								(size 1.27 1.27)
							)
						)
					)
				)
				(pin passive line
					(at 0 -38.1 0)
					(length 3.81)
					(name "G16"
						(effects
							(font
								(size 1.27 1.27)
							)
						)
					)
					(number "G16"
						(effects
							(font
								(size 1.27 1.27)
							)
						)
					)
				)
				(pin passive line
					(at 0 -40.64 0)
					(length 3.81)
					(name "G17"
						(effects
							(font
								(size 1.27 1.27)
							)
						)
					)
					(number "G17"
						(effects
							(font
								(size 1.27 1.27)
							)
						)
					)
				)
				(pin passive line
					(at 0 -43.18 0)
					(length 3.81)
					(name "G18"
						(effects
							(font
								(size 1.27 1.27)
							)
						)
					)
					(number "G18"
						(effects
							(font
								(size 1.27 1.27)
							)
						)
					)
				)
				(pin passive line
					(at 0 -45.72 0)
					(length 3.81)
					(name "G19"
						(effects
							(font
								(size 1.27 1.27)
							)
						)
					)
					(number "G19"
						(effects
							(font
								(size 1.27 1.27)
							)
						)
					)
				)
				(pin passive line
					(at 0 -48.26 0)
					(length 3.81)
					(name "G20"
						(effects
							(font
								(size 1.27 1.27)
							)
						)
					)
					(number "G20"
						(effects
							(font
								(size 1.27 1.27)
							)
						)
					)
				)
				(pin passive line
					(at 0 -50.8 0)
					(length 3.81)
					(name "G21"
						(effects
							(font
								(size 1.27 1.27)
							)
						)
					)
					(number "G21"
						(effects
							(font
								(size 1.27 1.27)
							)
						)
					)
				)
				(pin passive line
					(at 0 -53.34 0)
					(length 3.81)
					(name "G22"
						(effects
							(font
								(size 1.27 1.27)
							)
						)
					)
					(number "G22"
						(effects
							(font
								(size 1.27 1.27)
							)
						)
					)
				)
				(pin passive line
					(at 0 -55.88 0)
					(length 3.81)
					(name "G23"
						(effects
							(font
								(size 1.27 1.27)
							)
						)
					)
					(number "G23"
						(effects
							(font
								(size 1.27 1.27)
							)
						)
					)
				)
				(pin passive line
					(at 0 -58.42 0)
					(length 3.81)
					(name "G24"
						(effects
							(font
								(size 1.27 1.27)
							)
						)
					)
					(number "G24"
						(effects
							(font
								(size 1.27 1.27)
							)
						)
					)
				)
				(pin passive line
					(at 0 -60.96 0)
					(length 3.81)
					(name "G25"
						(effects
							(font
								(size 1.27 1.27)
							)
						)
					)
					(number "G25"
						(effects
							(font
								(size 1.27 1.27)
							)
						)
					)
				)
				(pin passive line
					(at 0 -63.5 0)
					(length 3.81)
					(name "G26"
						(effects
							(font
								(size 1.27 1.27)
							)
						)
					)
					(number "G26"
						(effects
							(font
								(size 1.27 1.27)
							)
						)
					)
				)
				(pin passive line
					(at 0 -66.04 0)
					(length 3.81)
					(name "G27"
						(effects
							(font
								(size 1.27 1.27)
							)
						)
					)
					(number "G27"
						(effects
							(font
								(size 1.27 1.27)
							)
						)
					)
				)
				(pin passive line
					(at 0 -68.58 0)
					(length 3.81)
					(name "G28"
						(effects
							(font
								(size 1.27 1.27)
							)
						)
					)
					(number "G28"
						(effects
							(font
								(size 1.27 1.27)
							)
						)
					)
				)
				(pin passive line
					(at 0 -71.12 0)
					(length 3.81)
					(name "G29"
						(effects
							(font
								(size 1.27 1.27)
							)
						)
					)
					(number "G29"
						(effects
							(font
								(size 1.27 1.27)
							)
						)
					)
				)
				(pin passive line
					(at 0 -73.66 0)
					(length 3.81)
					(name "G30"
						(effects
							(font
								(size 1.27 1.27)
							)
						)
					)
					(number "G30"
						(effects
							(font
								(size 1.27 1.27)
							)
						)
					)
				)
				(pin passive line
					(at 0 -76.2 0)
					(length 3.81)
					(name "G31"
						(effects
							(font
								(size 1.27 1.27)
							)
						)
					)
					(number "G31"
						(effects
							(font
								(size 1.27 1.27)
							)
						)
					)
				)
				(pin passive line
					(at 0 -78.74 0)
					(length 3.81)
					(name "G32"
						(effects
							(font
								(size 1.27 1.27)
							)
						)
					)
					(number "G32"
						(effects
							(font
								(size 1.27 1.27)
							)
						)
					)
				)
				(pin passive line
					(at 0 -81.28 0)
					(length 3.81)
					(name "G33"
						(effects
							(font
								(size 1.27 1.27)
							)
						)
					)
					(number "G33"
						(effects
							(font
								(size 1.27 1.27)
							)
						)
					)
				)
				(pin passive line
					(at 0 -83.82 0)
					(length 3.81)
					(name "G34"
						(effects
							(font
								(size 1.27 1.27)
							)
						)
					)
					(number "G34"
						(effects
							(font
								(size 1.27 1.27)
							)
						)
					)
				)
				(pin passive line
					(at 0 -86.36 0)
					(length 3.81)
					(name "G35"
						(effects
							(font
								(size 1.27 1.27)
							)
						)
					)
					(number "G35"
						(effects
							(font
								(size 1.27 1.27)
							)
						)
					)
				)
				(pin passive line
					(at 0 -88.9 0)
					(length 3.81)
					(name "G36"
						(effects
							(font
								(size 1.27 1.27)
							)
						)
					)
					(number "G36"
						(effects
							(font
								(size 1.27 1.27)
							)
						)
					)
				)
				(pin passive line
					(at 0 -91.44 0)
					(length 3.81)
					(name "G37"
						(effects
							(font
								(size 1.27 1.27)
							)
						)
					)
					(number "G37"
						(effects
							(font
								(size 1.27 1.27)
							)
						)
					)
				)
				(pin passive line
					(at 0 -93.98 0)
					(length 3.81)
					(name "G38"
						(effects
							(font
								(size 1.27 1.27)
							)
						)
					)
					(number "G38"
						(effects
							(font
								(size 1.27 1.27)
							)
						)
					)
				)
				(pin passive line
					(at 0 -96.52 0)
					(length 3.81)
					(name "G39"
						(effects
							(font
								(size 1.27 1.27)
							)
						)
					)
					(number "G39"
						(effects
							(font
								(size 1.27 1.27)
							)
						)
					)
				)
				(pin passive line
					(at 0 -99.06 0)
					(length 3.81)
					(name "G40"
						(effects
							(font
								(size 1.27 1.27)
							)
						)
					)
					(number "G40"
						(effects
							(font
								(size 1.27 1.27)
							)
						)
					)
				)
				(pin passive line
					(at 22.86 0 180)
					(length 3.81)
					(name "H01"
						(effects
							(font
								(size 1.27 1.27)
							)
						)
					)
					(number "H01"
						(effects
							(font
								(size 1.27 1.27)
							)
						)
					)
				)
				(pin passive line
					(at 22.86 -2.54 180)
					(length 3.81)
					(name "H02"
						(effects
							(font
								(size 1.27 1.27)
							)
						)
					)
					(number "H02"
						(effects
							(font
								(size 1.27 1.27)
							)
						)
					)
				)
				(pin passive line
					(at 22.86 -5.08 180)
					(length 3.81)
					(name "H03"
						(effects
							(font
								(size 1.27 1.27)
							)
						)
					)
					(number "H03"
						(effects
							(font
								(size 1.27 1.27)
							)
						)
					)
				)
				(pin passive line
					(at 22.86 -7.62 180)
					(length 3.81)
					(name "H04"
						(effects
							(font
								(size 1.27 1.27)
							)
						)
					)
					(number "H04"
						(effects
							(font
								(size 1.27 1.27)
							)
						)
					)
				)
				(pin passive line
					(at 22.86 -10.16 180)
					(length 3.81)
					(name "H05"
						(effects
							(font
								(size 1.27 1.27)
							)
						)
					)
					(number "H05"
						(effects
							(font
								(size 1.27 1.27)
							)
						)
					)
				)
				(pin passive line
					(at 22.86 -12.7 180)
					(length 3.81)
					(name "H06"
						(effects
							(font
								(size 1.27 1.27)
							)
						)
					)
					(number "H06"
						(effects
							(font
								(size 1.27 1.27)
							)
						)
					)
				)
				(pin passive line
					(at 22.86 -15.24 180)
					(length 3.81)
					(name "H07"
						(effects
							(font
								(size 1.27 1.27)
							)
						)
					)
					(number "H07"
						(effects
							(font
								(size 1.27 1.27)
							)
						)
					)
				)
				(pin passive line
					(at 22.86 -17.78 180)
					(length 3.81)
					(name "H08"
						(effects
							(font
								(size 1.27 1.27)
							)
						)
					)
					(number "H08"
						(effects
							(font
								(size 1.27 1.27)
							)
						)
					)
				)
				(pin passive line
					(at 22.86 -20.32 180)
					(length 3.81)
					(name "H09"
						(effects
							(font
								(size 1.27 1.27)
							)
						)
					)
					(number "H09"
						(effects
							(font
								(size 1.27 1.27)
							)
						)
					)
				)
				(pin passive line
					(at 22.86 -22.86 180)
					(length 3.81)
					(name "H10"
						(effects
							(font
								(size 1.27 1.27)
							)
						)
					)
					(number "H10"
						(effects
							(font
								(size 1.27 1.27)
							)
						)
					)
				)
				(pin passive line
					(at 22.86 -25.4 180)
					(length 3.81)
					(name "H11"
						(effects
							(font
								(size 1.27 1.27)
							)
						)
					)
					(number "H11"
						(effects
							(font
								(size 1.27 1.27)
							)
						)
					)
				)
				(pin passive line
					(at 22.86 -27.94 180)
					(length 3.81)
					(name "H12"
						(effects
							(font
								(size 1.27 1.27)
							)
						)
					)
					(number "H12"
						(effects
							(font
								(size 1.27 1.27)
							)
						)
					)
				)
				(pin passive line
					(at 22.86 -30.48 180)
					(length 3.81)
					(name "H13"
						(effects
							(font
								(size 1.27 1.27)
							)
						)
					)
					(number "H13"
						(effects
							(font
								(size 1.27 1.27)
							)
						)
					)
				)
				(pin passive line
					(at 22.86 -33.02 180)
					(length 3.81)
					(name "H14"
						(effects
							(font
								(size 1.27 1.27)
							)
						)
					)
					(number "H14"
						(effects
							(font
								(size 1.27 1.27)
							)
						)
					)
				)
				(pin passive line
					(at 22.86 -35.56 180)
					(length 3.81)
					(name "H15"
						(effects
							(font
								(size 1.27 1.27)
							)
						)
					)
					(number "H15"
						(effects
							(font
								(size 1.27 1.27)
							)
						)
					)
				)
				(pin passive line
					(at 22.86 -38.1 180)
					(length 3.81)
					(name "H16"
						(effects
							(font
								(size 1.27 1.27)
							)
						)
					)
					(number "H16"
						(effects
							(font
								(size 1.27 1.27)
							)
						)
					)
				)
				(pin passive line
					(at 22.86 -40.64 180)
					(length 3.81)
					(name "H17"
						(effects
							(font
								(size 1.27 1.27)
							)
						)
					)
					(number "H17"
						(effects
							(font
								(size 1.27 1.27)
							)
						)
					)
				)
				(pin passive line
					(at 22.86 -43.18 180)
					(length 3.81)
					(name "H18"
						(effects
							(font
								(size 1.27 1.27)
							)
						)
					)
					(number "H18"
						(effects
							(font
								(size 1.27 1.27)
							)
						)
					)
				)
				(pin passive line
					(at 22.86 -45.72 180)
					(length 3.81)
					(name "H19"
						(effects
							(font
								(size 1.27 1.27)
							)
						)
					)
					(number "H19"
						(effects
							(font
								(size 1.27 1.27)
							)
						)
					)
				)
				(pin passive line
					(at 22.86 -48.26 180)
					(length 3.81)
					(name "H20"
						(effects
							(font
								(size 1.27 1.27)
							)
						)
					)
					(number "H20"
						(effects
							(font
								(size 1.27 1.27)
							)
						)
					)
				)
				(pin passive line
					(at 22.86 -50.8 180)
					(length 3.81)
					(name "H21"
						(effects
							(font
								(size 1.27 1.27)
							)
						)
					)
					(number "H21"
						(effects
							(font
								(size 1.27 1.27)
							)
						)
					)
				)
				(pin passive line
					(at 22.86 -53.34 180)
					(length 3.81)
					(name "H22"
						(effects
							(font
								(size 1.27 1.27)
							)
						)
					)
					(number "H22"
						(effects
							(font
								(size 1.27 1.27)
							)
						)
					)
				)
				(pin passive line
					(at 22.86 -55.88 180)
					(length 3.81)
					(name "H23"
						(effects
							(font
								(size 1.27 1.27)
							)
						)
					)
					(number "H23"
						(effects
							(font
								(size 1.27 1.27)
							)
						)
					)
				)
				(pin passive line
					(at 22.86 -58.42 180)
					(length 3.81)
					(name "H24"
						(effects
							(font
								(size 1.27 1.27)
							)
						)
					)
					(number "H24"
						(effects
							(font
								(size 1.27 1.27)
							)
						)
					)
				)
				(pin passive line
					(at 22.86 -60.96 180)
					(length 3.81)
					(name "H25"
						(effects
							(font
								(size 1.27 1.27)
							)
						)
					)
					(number "H25"
						(effects
							(font
								(size 1.27 1.27)
							)
						)
					)
				)
				(pin passive line
					(at 22.86 -63.5 180)
					(length 3.81)
					(name "H26"
						(effects
							(font
								(size 1.27 1.27)
							)
						)
					)
					(number "H26"
						(effects
							(font
								(size 1.27 1.27)
							)
						)
					)
				)
				(pin passive line
					(at 22.86 -66.04 180)
					(length 3.81)
					(name "H27"
						(effects
							(font
								(size 1.27 1.27)
							)
						)
					)
					(number "H27"
						(effects
							(font
								(size 1.27 1.27)
							)
						)
					)
				)
				(pin passive line
					(at 22.86 -68.58 180)
					(length 3.81)
					(name "H28"
						(effects
							(font
								(size 1.27 1.27)
							)
						)
					)
					(number "H28"
						(effects
							(font
								(size 1.27 1.27)
							)
						)
					)
				)
				(pin passive line
					(at 22.86 -71.12 180)
					(length 3.81)
					(name "H29"
						(effects
							(font
								(size 1.27 1.27)
							)
						)
					)
					(number "H29"
						(effects
							(font
								(size 1.27 1.27)
							)
						)
					)
				)
				(pin passive line
					(at 22.86 -73.66 180)
					(length 3.81)
					(name "H30"
						(effects
							(font
								(size 1.27 1.27)
							)
						)
					)
					(number "H30"
						(effects
							(font
								(size 1.27 1.27)
							)
						)
					)
				)
				(pin passive line
					(at 22.86 -76.2 180)
					(length 3.81)
					(name "H31"
						(effects
							(font
								(size 1.27 1.27)
							)
						)
					)
					(number "H31"
						(effects
							(font
								(size 1.27 1.27)
							)
						)
					)
				)
				(pin passive line
					(at 22.86 -78.74 180)
					(length 3.81)
					(name "H32"
						(effects
							(font
								(size 1.27 1.27)
							)
						)
					)
					(number "H32"
						(effects
							(font
								(size 1.27 1.27)
							)
						)
					)
				)
				(pin passive line
					(at 22.86 -81.28 180)
					(length 3.81)
					(name "H33"
						(effects
							(font
								(size 1.27 1.27)
							)
						)
					)
					(number "H33"
						(effects
							(font
								(size 1.27 1.27)
							)
						)
					)
				)
				(pin passive line
					(at 22.86 -83.82 180)
					(length 3.81)
					(name "H34"
						(effects
							(font
								(size 1.27 1.27)
							)
						)
					)
					(number "H34"
						(effects
							(font
								(size 1.27 1.27)
							)
						)
					)
				)
				(pin passive line
					(at 22.86 -86.36 180)
					(length 3.81)
					(name "H35"
						(effects
							(font
								(size 1.27 1.27)
							)
						)
					)
					(number "H35"
						(effects
							(font
								(size 1.27 1.27)
							)
						)
					)
				)
				(pin passive line
					(at 22.86 -88.9 180)
					(length 3.81)
					(name "H36"
						(effects
							(font
								(size 1.27 1.27)
							)
						)
					)
					(number "H36"
						(effects
							(font
								(size 1.27 1.27)
							)
						)
					)
				)
				(pin passive line
					(at 22.86 -91.44 180)
					(length 3.81)
					(name "H37"
						(effects
							(font
								(size 1.27 1.27)
							)
						)
					)
					(number "H37"
						(effects
							(font
								(size 1.27 1.27)
							)
						)
					)
				)
				(pin passive line
					(at 22.86 -93.98 180)
					(length 3.81)
					(name "H38"
						(effects
							(font
								(size 1.27 1.27)
							)
						)
					)
					(number "H38"
						(effects
							(font
								(size 1.27 1.27)
							)
						)
					)
				)
				(pin passive line
					(at 22.86 -96.52 180)
					(length 3.81)
					(name "H39"
						(effects
							(font
								(size 1.27 1.27)
							)
						)
					)
					(number "H39"
						(effects
							(font
								(size 1.27 1.27)
							)
						)
					)
				)
				(pin passive line
					(at 22.86 -99.06 180)
					(length 3.81)
					(name "H40"
						(effects
							(font
								(size 1.27 1.27)
							)
						)
					)
					(number "H40"
						(effects
							(font
								(size 1.27 1.27)
							)
						)
					)
				)
			)
			(symbol "ASP-208571-01_mounting_holes_6_1"
				(rectangle
					(start 3.81 -101.6)
					(end 19.05 2.54)
					(stroke
						(width 0.254)
						(type default)
					)
					(fill
						(type background)
					)
				)
				(pin passive line
					(at 0 0 0)
					(length 3.81)
					(name "J01"
						(effects
							(font
								(size 1.27 1.27)
							)
						)
					)
					(number "J01"
						(effects
							(font
								(size 1.27 1.27)
							)
						)
					)
				)
				(pin passive line
					(at 0 -2.54 0)
					(length 3.81)
					(name "J02"
						(effects
							(font
								(size 1.27 1.27)
							)
						)
					)
					(number "J02"
						(effects
							(font
								(size 1.27 1.27)
							)
						)
					)
				)
				(pin passive line
					(at 0 -5.08 0)
					(length 3.81)
					(name "J03"
						(effects
							(font
								(size 1.27 1.27)
							)
						)
					)
					(number "J03"
						(effects
							(font
								(size 1.27 1.27)
							)
						)
					)
				)
				(pin passive line
					(at 0 -7.62 0)
					(length 3.81)
					(name "J04"
						(effects
							(font
								(size 1.27 1.27)
							)
						)
					)
					(number "J04"
						(effects
							(font
								(size 1.27 1.27)
							)
						)
					)
				)
				(pin passive line
					(at 0 -10.16 0)
					(length 3.81)
					(name "J05"
						(effects
							(font
								(size 1.27 1.27)
							)
						)
					)
					(number "J05"
						(effects
							(font
								(size 1.27 1.27)
							)
						)
					)
				)
				(pin passive line
					(at 0 -12.7 0)
					(length 3.81)
					(name "J06"
						(effects
							(font
								(size 1.27 1.27)
							)
						)
					)
					(number "J06"
						(effects
							(font
								(size 1.27 1.27)
							)
						)
					)
				)
				(pin passive line
					(at 0 -15.24 0)
					(length 3.81)
					(name "J07"
						(effects
							(font
								(size 1.27 1.27)
							)
						)
					)
					(number "J07"
						(effects
							(font
								(size 1.27 1.27)
							)
						)
					)
				)
				(pin passive line
					(at 0 -17.78 0)
					(length 3.81)
					(name "J08"
						(effects
							(font
								(size 1.27 1.27)
							)
						)
					)
					(number "J08"
						(effects
							(font
								(size 1.27 1.27)
							)
						)
					)
				)
				(pin passive line
					(at 0 -20.32 0)
					(length 3.81)
					(name "J09"
						(effects
							(font
								(size 1.27 1.27)
							)
						)
					)
					(number "J09"
						(effects
							(font
								(size 1.27 1.27)
							)
						)
					)
				)
				(pin passive line
					(at 0 -22.86 0)
					(length 3.81)
					(name "J10"
						(effects
							(font
								(size 1.27 1.27)
							)
						)
					)
					(number "J10"
						(effects
							(font
								(size 1.27 1.27)
							)
						)
					)
				)
				(pin passive line
					(at 0 -25.4 0)
					(length 3.81)
					(name "J11"
						(effects
							(font
								(size 1.27 1.27)
							)
						)
					)
					(number "J11"
						(effects
							(font
								(size 1.27 1.27)
							)
						)
					)
				)
				(pin passive line
					(at 0 -27.94 0)
					(length 3.81)
					(name "J12"
						(effects
							(font
								(size 1.27 1.27)
							)
						)
					)
					(number "J12"
						(effects
							(font
								(size 1.27 1.27)
							)
						)
					)
				)
				(pin passive line
					(at 0 -30.48 0)
					(length 3.81)
					(name "J13"
						(effects
							(font
								(size 1.27 1.27)
							)
						)
					)
					(number "J13"
						(effects
							(font
								(size 1.27 1.27)
							)
						)
					)
				)
				(pin passive line
					(at 0 -33.02 0)
					(length 3.81)
					(name "J14"
						(effects
							(font
								(size 1.27 1.27)
							)
						)
					)
					(number "J14"
						(effects
							(font
								(size 1.27 1.27)
							)
						)
					)
				)
				(pin passive line
					(at 0 -35.56 0)
					(length 3.81)
					(name "J15"
						(effects
							(font
								(size 1.27 1.27)
							)
						)
					)
					(number "J15"
						(effects
							(font
								(size 1.27 1.27)
							)
						)
					)
				)
				(pin passive line
					(at 0 -38.1 0)
					(length 3.81)
					(name "J16"
						(effects
							(font
								(size 1.27 1.27)
							)
						)
					)
					(number "J16"
						(effects
							(font
								(size 1.27 1.27)
							)
						)
					)
				)
				(pin passive line
					(at 0 -40.64 0)
					(length 3.81)
					(name "J17"
						(effects
							(font
								(size 1.27 1.27)
							)
						)
					)
					(number "J17"
						(effects
							(font
								(size 1.27 1.27)
							)
						)
					)
				)
				(pin passive line
					(at 0 -43.18 0)
					(length 3.81)
					(name "J18"
						(effects
							(font
								(size 1.27 1.27)
							)
						)
					)
					(number "J18"
						(effects
							(font
								(size 1.27 1.27)
							)
						)
					)
				)
				(pin passive line
					(at 0 -45.72 0)
					(length 3.81)
					(name "J19"
						(effects
							(font
								(size 1.27 1.27)
							)
						)
					)
					(number "J19"
						(effects
							(font
								(size 1.27 1.27)
							)
						)
					)
				)
				(pin passive line
					(at 0 -48.26 0)
					(length 3.81)
					(name "J20"
						(effects
							(font
								(size 1.27 1.27)
							)
						)
					)
					(number "J20"
						(effects
							(font
								(size 1.27 1.27)
							)
						)
					)
				)
				(pin passive line
					(at 0 -50.8 0)
					(length 3.81)
					(name "J21"
						(effects
							(font
								(size 1.27 1.27)
							)
						)
					)
					(number "J21"
						(effects
							(font
								(size 1.27 1.27)
							)
						)
					)
				)
				(pin passive line
					(at 0 -53.34 0)
					(length 3.81)
					(name "J22"
						(effects
							(font
								(size 1.27 1.27)
							)
						)
					)
					(number "J22"
						(effects
							(font
								(size 1.27 1.27)
							)
						)
					)
				)
				(pin passive line
					(at 0 -55.88 0)
					(length 3.81)
					(name "J23"
						(effects
							(font
								(size 1.27 1.27)
							)
						)
					)
					(number "J23"
						(effects
							(font
								(size 1.27 1.27)
							)
						)
					)
				)
				(pin passive line
					(at 0 -58.42 0)
					(length 3.81)
					(name "J24"
						(effects
							(font
								(size 1.27 1.27)
							)
						)
					)
					(number "J24"
						(effects
							(font
								(size 1.27 1.27)
							)
						)
					)
				)
				(pin passive line
					(at 0 -60.96 0)
					(length 3.81)
					(name "J25"
						(effects
							(font
								(size 1.27 1.27)
							)
						)
					)
					(number "J25"
						(effects
							(font
								(size 1.27 1.27)
							)
						)
					)
				)
				(pin passive line
					(at 0 -63.5 0)
					(length 3.81)
					(name "J26"
						(effects
							(font
								(size 1.27 1.27)
							)
						)
					)
					(number "J26"
						(effects
							(font
								(size 1.27 1.27)
							)
						)
					)
				)
				(pin passive line
					(at 0 -66.04 0)
					(length 3.81)
					(name "J27"
						(effects
							(font
								(size 1.27 1.27)
							)
						)
					)
					(number "J27"
						(effects
							(font
								(size 1.27 1.27)
							)
						)
					)
				)
				(pin passive line
					(at 0 -68.58 0)
					(length 3.81)
					(name "J28"
						(effects
							(font
								(size 1.27 1.27)
							)
						)
					)
					(number "J28"
						(effects
							(font
								(size 1.27 1.27)
							)
						)
					)
				)
				(pin passive line
					(at 0 -71.12 0)
					(length 3.81)
					(name "J29"
						(effects
							(font
								(size 1.27 1.27)
							)
						)
					)
					(number "J29"
						(effects
							(font
								(size 1.27 1.27)
							)
						)
					)
				)
				(pin passive line
					(at 0 -73.66 0)
					(length 3.81)
					(name "J30"
						(effects
							(font
								(size 1.27 1.27)
							)
						)
					)
					(number "J30"
						(effects
							(font
								(size 1.27 1.27)
							)
						)
					)
				)
				(pin passive line
					(at 0 -76.2 0)
					(length 3.81)
					(name "J31"
						(effects
							(font
								(size 1.27 1.27)
							)
						)
					)
					(number "J31"
						(effects
							(font
								(size 1.27 1.27)
							)
						)
					)
				)
				(pin passive line
					(at 0 -78.74 0)
					(length 3.81)
					(name "J32"
						(effects
							(font
								(size 1.27 1.27)
							)
						)
					)
					(number "J32"
						(effects
							(font
								(size 1.27 1.27)
							)
						)
					)
				)
				(pin passive line
					(at 0 -81.28 0)
					(length 3.81)
					(name "J33"
						(effects
							(font
								(size 1.27 1.27)
							)
						)
					)
					(number "J33"
						(effects
							(font
								(size 1.27 1.27)
							)
						)
					)
				)
				(pin passive line
					(at 0 -83.82 0)
					(length 3.81)
					(name "J34"
						(effects
							(font
								(size 1.27 1.27)
							)
						)
					)
					(number "J34"
						(effects
							(font
								(size 1.27 1.27)
							)
						)
					)
				)
				(pin passive line
					(at 0 -86.36 0)
					(length 3.81)
					(name "J35"
						(effects
							(font
								(size 1.27 1.27)
							)
						)
					)
					(number "J35"
						(effects
							(font
								(size 1.27 1.27)
							)
						)
					)
				)
				(pin passive line
					(at 0 -88.9 0)
					(length 3.81)
					(name "J36"
						(effects
							(font
								(size 1.27 1.27)
							)
						)
					)
					(number "J36"
						(effects
							(font
								(size 1.27 1.27)
							)
						)
					)
				)
				(pin passive line
					(at 0 -91.44 0)
					(length 3.81)
					(name "J37"
						(effects
							(font
								(size 1.27 1.27)
							)
						)
					)
					(number "J37"
						(effects
							(font
								(size 1.27 1.27)
							)
						)
					)
				)
				(pin passive line
					(at 0 -93.98 0)
					(length 3.81)
					(name "J38"
						(effects
							(font
								(size 1.27 1.27)
							)
						)
					)
					(number "J38"
						(effects
							(font
								(size 1.27 1.27)
							)
						)
					)
				)
				(pin passive line
					(at 0 -96.52 0)
					(length 3.81)
					(name "J39"
						(effects
							(font
								(size 1.27 1.27)
							)
						)
					)
					(number "J39"
						(effects
							(font
								(size 1.27 1.27)
							)
						)
					)
				)
				(pin passive line
					(at 0 -99.06 0)
					(length 3.81)
					(name "J40"
						(effects
							(font
								(size 1.27 1.27)
							)
						)
					)
					(number "J40"
						(effects
							(font
								(size 1.27 1.27)
							)
						)
					)
				)
				(pin passive line
					(at 22.86 0 180)
					(length 3.81)
					(name "K01"
						(effects
							(font
								(size 1.27 1.27)
							)
						)
					)
					(number "K01"
						(effects
							(font
								(size 1.27 1.27)
							)
						)
					)
				)
				(pin passive line
					(at 22.86 -2.54 180)
					(length 3.81)
					(name "K02"
						(effects
							(font
								(size 1.27 1.27)
							)
						)
					)
					(number "K02"
						(effects
							(font
								(size 1.27 1.27)
							)
						)
					)
				)
				(pin passive line
					(at 22.86 -5.08 180)
					(length 3.81)
					(name "K03"
						(effects
							(font
								(size 1.27 1.27)
							)
						)
					)
					(number "K03"
						(effects
							(font
								(size 1.27 1.27)
							)
						)
					)
				)
				(pin passive line
					(at 22.86 -7.62 180)
					(length 3.81)
					(name "K04"
						(effects
							(font
								(size 1.27 1.27)
							)
						)
					)
					(number "K04"
						(effects
							(font
								(size 1.27 1.27)
							)
						)
					)
				)
				(pin passive line
					(at 22.86 -10.16 180)
					(length 3.81)
					(name "K05"
						(effects
							(font
								(size 1.27 1.27)
							)
						)
					)
					(number "K05"
						(effects
							(font
								(size 1.27 1.27)
							)
						)
					)
				)
				(pin passive line
					(at 22.86 -12.7 180)
					(length 3.81)
					(name "K06"
						(effects
							(font
								(size 1.27 1.27)
							)
						)
					)
					(number "K06"
						(effects
							(font
								(size 1.27 1.27)
							)
						)
					)
				)
				(pin passive line
					(at 22.86 -15.24 180)
					(length 3.81)
					(name "K07"
						(effects
							(font
								(size 1.27 1.27)
							)
						)
					)
					(number "K07"
						(effects
							(font
								(size 1.27 1.27)
							)
						)
					)
				)
				(pin passive line
					(at 22.86 -17.78 180)
					(length 3.81)
					(name "K08"
						(effects
							(font
								(size 1.27 1.27)
							)
						)
					)
					(number "K08"
						(effects
							(font
								(size 1.27 1.27)
							)
						)
					)
				)
				(pin passive line
					(at 22.86 -20.32 180)
					(length 3.81)
					(name "K09"
						(effects
							(font
								(size 1.27 1.27)
							)
						)
					)
					(number "K09"
						(effects
							(font
								(size 1.27 1.27)
							)
						)
					)
				)
				(pin passive line
					(at 22.86 -22.86 180)
					(length 3.81)
					(name "K10"
						(effects
							(font
								(size 1.27 1.27)
							)
						)
					)
					(number "K10"
						(effects
							(font
								(size 1.27 1.27)
							)
						)
					)
				)
				(pin passive line
					(at 22.86 -25.4 180)
					(length 3.81)
					(name "K11"
						(effects
							(font
								(size 1.27 1.27)
							)
						)
					)
					(number "K11"
						(effects
							(font
								(size 1.27 1.27)
							)
						)
					)
				)
				(pin passive line
					(at 22.86 -27.94 180)
					(length 3.81)
					(name "K12"
						(effects
							(font
								(size 1.27 1.27)
							)
						)
					)
					(number "K12"
						(effects
							(font
								(size 1.27 1.27)
							)
						)
					)
				)
				(pin passive line
					(at 22.86 -30.48 180)
					(length 3.81)
					(name "K13"
						(effects
							(font
								(size 1.27 1.27)
							)
						)
					)
					(number "K13"
						(effects
							(font
								(size 1.27 1.27)
							)
						)
					)
				)
				(pin passive line
					(at 22.86 -33.02 180)
					(length 3.81)
					(name "K14"
						(effects
							(font
								(size 1.27 1.27)
							)
						)
					)
					(number "K14"
						(effects
							(font
								(size 1.27 1.27)
							)
						)
					)
				)
				(pin passive line
					(at 22.86 -35.56 180)
					(length 3.81)
					(name "K15"
						(effects
							(font
								(size 1.27 1.27)
							)
						)
					)
					(number "K15"
						(effects
							(font
								(size 1.27 1.27)
							)
						)
					)
				)
				(pin passive line
					(at 22.86 -38.1 180)
					(length 3.81)
					(name "K16"
						(effects
							(font
								(size 1.27 1.27)
							)
						)
					)
					(number "K16"
						(effects
							(font
								(size 1.27 1.27)
							)
						)
					)
				)
				(pin passive line
					(at 22.86 -40.64 180)
					(length 3.81)
					(name "K17"
						(effects
							(font
								(size 1.27 1.27)
							)
						)
					)
					(number "K17"
						(effects
							(font
								(size 1.27 1.27)
							)
						)
					)
				)
				(pin passive line
					(at 22.86 -43.18 180)
					(length 3.81)
					(name "K18"
						(effects
							(font
								(size 1.27 1.27)
							)
						)
					)
					(number "K18"
						(effects
							(font
								(size 1.27 1.27)
							)
						)
					)
				)
				(pin passive line
					(at 22.86 -45.72 180)
					(length 3.81)
					(name "K19"
						(effects
							(font
								(size 1.27 1.27)
							)
						)
					)
					(number "K19"
						(effects
							(font
								(size 1.27 1.27)
							)
						)
					)
				)
				(pin passive line
					(at 22.86 -48.26 180)
					(length 3.81)
					(name "K20"
						(effects
							(font
								(size 1.27 1.27)
							)
						)
					)
					(number "K20"
						(effects
							(font
								(size 1.27 1.27)
							)
						)
					)
				)
				(pin passive line
					(at 22.86 -50.8 180)
					(length 3.81)
					(name "K21"
						(effects
							(font
								(size 1.27 1.27)
							)
						)
					)
					(number "K21"
						(effects
							(font
								(size 1.27 1.27)
							)
						)
					)
				)
				(pin passive line
					(at 22.86 -53.34 180)
					(length 3.81)
					(name "K22"
						(effects
							(font
								(size 1.27 1.27)
							)
						)
					)
					(number "K22"
						(effects
							(font
								(size 1.27 1.27)
							)
						)
					)
				)
				(pin passive line
					(at 22.86 -55.88 180)
					(length 3.81)
					(name "K23"
						(effects
							(font
								(size 1.27 1.27)
							)
						)
					)
					(number "K23"
						(effects
							(font
								(size 1.27 1.27)
							)
						)
					)
				)
				(pin passive line
					(at 22.86 -58.42 180)
					(length 3.81)
					(name "K24"
						(effects
							(font
								(size 1.27 1.27)
							)
						)
					)
					(number "K24"
						(effects
							(font
								(size 1.27 1.27)
							)
						)
					)
				)
				(pin passive line
					(at 22.86 -60.96 180)
					(length 3.81)
					(name "K25"
						(effects
							(font
								(size 1.27 1.27)
							)
						)
					)
					(number "K25"
						(effects
							(font
								(size 1.27 1.27)
							)
						)
					)
				)
				(pin passive line
					(at 22.86 -63.5 180)
					(length 3.81)
					(name "K26"
						(effects
							(font
								(size 1.27 1.27)
							)
						)
					)
					(number "K26"
						(effects
							(font
								(size 1.27 1.27)
							)
						)
					)
				)
				(pin passive line
					(at 22.86 -66.04 180)
					(length 3.81)
					(name "K27"
						(effects
							(font
								(size 1.27 1.27)
							)
						)
					)
					(number "K27"
						(effects
							(font
								(size 1.27 1.27)
							)
						)
					)
				)
				(pin passive line
					(at 22.86 -68.58 180)
					(length 3.81)
					(name "K28"
						(effects
							(font
								(size 1.27 1.27)
							)
						)
					)
					(number "K28"
						(effects
							(font
								(size 1.27 1.27)
							)
						)
					)
				)
				(pin passive line
					(at 22.86 -71.12 180)
					(length 3.81)
					(name "K29"
						(effects
							(font
								(size 1.27 1.27)
							)
						)
					)
					(number "K29"
						(effects
							(font
								(size 1.27 1.27)
							)
						)
					)
				)
				(pin passive line
					(at 22.86 -73.66 180)
					(length 3.81)
					(name "K30"
						(effects
							(font
								(size 1.27 1.27)
							)
						)
					)
					(number "K30"
						(effects
							(font
								(size 1.27 1.27)
							)
						)
					)
				)
				(pin passive line
					(at 22.86 -76.2 180)
					(length 3.81)
					(name "K31"
						(effects
							(font
								(size 1.27 1.27)
							)
						)
					)
					(number "K31"
						(effects
							(font
								(size 1.27 1.27)
							)
						)
					)
				)
				(pin passive line
					(at 22.86 -78.74 180)
					(length 3.81)
					(name "K32"
						(effects
							(font
								(size 1.27 1.27)
							)
						)
					)
					(number "K32"
						(effects
							(font
								(size 1.27 1.27)
							)
						)
					)
				)
				(pin passive line
					(at 22.86 -81.28 180)
					(length 3.81)
					(name "K33"
						(effects
							(font
								(size 1.27 1.27)
							)
						)
					)
					(number "K33"
						(effects
							(font
								(size 1.27 1.27)
							)
						)
					)
				)
				(pin passive line
					(at 22.86 -83.82 180)
					(length 3.81)
					(name "K34"
						(effects
							(font
								(size 1.27 1.27)
							)
						)
					)
					(number "K34"
						(effects
							(font
								(size 1.27 1.27)
							)
						)
					)
				)
				(pin passive line
					(at 22.86 -86.36 180)
					(length 3.81)
					(name "K35"
						(effects
							(font
								(size 1.27 1.27)
							)
						)
					)
					(number "K35"
						(effects
							(font
								(size 1.27 1.27)
							)
						)
					)
				)
				(pin passive line
					(at 22.86 -88.9 180)
					(length 3.81)
					(name "K36"
						(effects
							(font
								(size 1.27 1.27)
							)
						)
					)
					(number "K36"
						(effects
							(font
								(size 1.27 1.27)
							)
						)
					)
				)
				(pin passive line
					(at 22.86 -91.44 180)
					(length 3.81)
					(name "K37"
						(effects
							(font
								(size 1.27 1.27)
							)
						)
					)
					(number "K37"
						(effects
							(font
								(size 1.27 1.27)
							)
						)
					)
				)
				(pin passive line
					(at 22.86 -93.98 180)
					(length 3.81)
					(name "K38"
						(effects
							(font
								(size 1.27 1.27)
							)
						)
					)
					(number "K38"
						(effects
							(font
								(size 1.27 1.27)
							)
						)
					)
				)
				(pin passive line
					(at 22.86 -96.52 180)
					(length 3.81)
					(name "K39"
						(effects
							(font
								(size 1.27 1.27)
							)
						)
					)
					(number "K39"
						(effects
							(font
								(size 1.27 1.27)
							)
						)
					)
				)
				(pin passive line
					(at 22.86 -99.06 180)
					(length 3.81)
					(name "K40"
						(effects
							(font
								(size 1.27 1.27)
							)
						)
					)
					(number "K40"
						(effects
							(font
								(size 1.27 1.27)
							)
						)
					)
				)
			)
			(symbol "ASP-208571-01_mounting_holes_7_1"
				(rectangle
					(start 3.81 -101.6)
					(end 19.05 2.54)
					(stroke
						(width 0.254)
						(type default)
					)
					(fill
						(type background)
					)
				)
				(pin passive line
					(at 0 0 0)
					(length 3.81)
					(name "L01"
						(effects
							(font
								(size 1.27 1.27)
							)
						)
					)
					(number "L01"
						(effects
							(font
								(size 1.27 1.27)
							)
						)
					)
				)
				(pin passive line
					(at 0 -2.54 0)
					(length 3.81)
					(name "L02"
						(effects
							(font
								(size 1.27 1.27)
							)
						)
					)
					(number "L02"
						(effects
							(font
								(size 1.27 1.27)
							)
						)
					)
				)
				(pin passive line
					(at 0 -5.08 0)
					(length 3.81)
					(name "L03"
						(effects
							(font
								(size 1.27 1.27)
							)
						)
					)
					(number "L03"
						(effects
							(font
								(size 1.27 1.27)
							)
						)
					)
				)
				(pin passive line
					(at 0 -7.62 0)
					(length 3.81)
					(name "L04"
						(effects
							(font
								(size 1.27 1.27)
							)
						)
					)
					(number "L04"
						(effects
							(font
								(size 1.27 1.27)
							)
						)
					)
				)
				(pin passive line
					(at 0 -10.16 0)
					(length 3.81)
					(name "L05"
						(effects
							(font
								(size 1.27 1.27)
							)
						)
					)
					(number "L05"
						(effects
							(font
								(size 1.27 1.27)
							)
						)
					)
				)
				(pin passive line
					(at 0 -12.7 0)
					(length 3.81)
					(name "L06"
						(effects
							(font
								(size 1.27 1.27)
							)
						)
					)
					(number "L06"
						(effects
							(font
								(size 1.27 1.27)
							)
						)
					)
				)
				(pin passive line
					(at 0 -15.24 0)
					(length 3.81)
					(name "L07"
						(effects
							(font
								(size 1.27 1.27)
							)
						)
					)
					(number "L07"
						(effects
							(font
								(size 1.27 1.27)
							)
						)
					)
				)
				(pin passive line
					(at 0 -17.78 0)
					(length 3.81)
					(name "L08"
						(effects
							(font
								(size 1.27 1.27)
							)
						)
					)
					(number "L08"
						(effects
							(font
								(size 1.27 1.27)
							)
						)
					)
				)
				(pin passive line
					(at 0 -20.32 0)
					(length 3.81)
					(name "L09"
						(effects
							(font
								(size 1.27 1.27)
							)
						)
					)
					(number "L09"
						(effects
							(font
								(size 1.27 1.27)
							)
						)
					)
				)
				(pin passive line
					(at 0 -22.86 0)
					(length 3.81)
					(name "L10"
						(effects
							(font
								(size 1.27 1.27)
							)
						)
					)
					(number "L10"
						(effects
							(font
								(size 1.27 1.27)
							)
						)
					)
				)
				(pin passive line
					(at 0 -25.4 0)
					(length 3.81)
					(name "L11"
						(effects
							(font
								(size 1.27 1.27)
							)
						)
					)
					(number "L11"
						(effects
							(font
								(size 1.27 1.27)
							)
						)
					)
				)
				(pin passive line
					(at 0 -27.94 0)
					(length 3.81)
					(name "L12"
						(effects
							(font
								(size 1.27 1.27)
							)
						)
					)
					(number "L12"
						(effects
							(font
								(size 1.27 1.27)
							)
						)
					)
				)
				(pin passive line
					(at 0 -30.48 0)
					(length 3.81)
					(name "L13"
						(effects
							(font
								(size 1.27 1.27)
							)
						)
					)
					(number "L13"
						(effects
							(font
								(size 1.27 1.27)
							)
						)
					)
				)
				(pin passive line
					(at 0 -33.02 0)
					(length 3.81)
					(name "L14"
						(effects
							(font
								(size 1.27 1.27)
							)
						)
					)
					(number "L14"
						(effects
							(font
								(size 1.27 1.27)
							)
						)
					)
				)
				(pin passive line
					(at 0 -35.56 0)
					(length 3.81)
					(name "L15"
						(effects
							(font
								(size 1.27 1.27)
							)
						)
					)
					(number "L15"
						(effects
							(font
								(size 1.27 1.27)
							)
						)
					)
				)
				(pin passive line
					(at 0 -38.1 0)
					(length 3.81)
					(name "L16"
						(effects
							(font
								(size 1.27 1.27)
							)
						)
					)
					(number "L16"
						(effects
							(font
								(size 1.27 1.27)
							)
						)
					)
				)
				(pin passive line
					(at 0 -40.64 0)
					(length 3.81)
					(name "L17"
						(effects
							(font
								(size 1.27 1.27)
							)
						)
					)
					(number "L17"
						(effects
							(font
								(size 1.27 1.27)
							)
						)
					)
				)
				(pin passive line
					(at 0 -43.18 0)
					(length 3.81)
					(name "L18"
						(effects
							(font
								(size 1.27 1.27)
							)
						)
					)
					(number "L18"
						(effects
							(font
								(size 1.27 1.27)
							)
						)
					)
				)
				(pin passive line
					(at 0 -45.72 0)
					(length 3.81)
					(name "L19"
						(effects
							(font
								(size 1.27 1.27)
							)
						)
					)
					(number "L19"
						(effects
							(font
								(size 1.27 1.27)
							)
						)
					)
				)
				(pin passive line
					(at 0 -48.26 0)
					(length 3.81)
					(name "L20"
						(effects
							(font
								(size 1.27 1.27)
							)
						)
					)
					(number "L20"
						(effects
							(font
								(size 1.27 1.27)
							)
						)
					)
				)
				(pin passive line
					(at 0 -50.8 0)
					(length 3.81)
					(name "L21"
						(effects
							(font
								(size 1.27 1.27)
							)
						)
					)
					(number "L21"
						(effects
							(font
								(size 1.27 1.27)
							)
						)
					)
				)
				(pin passive line
					(at 0 -53.34 0)
					(length 3.81)
					(name "L22"
						(effects
							(font
								(size 1.27 1.27)
							)
						)
					)
					(number "L22"
						(effects
							(font
								(size 1.27 1.27)
							)
						)
					)
				)
				(pin passive line
					(at 0 -55.88 0)
					(length 3.81)
					(name "L23"
						(effects
							(font
								(size 1.27 1.27)
							)
						)
					)
					(number "L23"
						(effects
							(font
								(size 1.27 1.27)
							)
						)
					)
				)
				(pin passive line
					(at 0 -58.42 0)
					(length 3.81)
					(name "L24"
						(effects
							(font
								(size 1.27 1.27)
							)
						)
					)
					(number "L24"
						(effects
							(font
								(size 1.27 1.27)
							)
						)
					)
				)
				(pin passive line
					(at 0 -60.96 0)
					(length 3.81)
					(name "L25"
						(effects
							(font
								(size 1.27 1.27)
							)
						)
					)
					(number "L25"
						(effects
							(font
								(size 1.27 1.27)
							)
						)
					)
				)
				(pin passive line
					(at 0 -63.5 0)
					(length 3.81)
					(name "L26"
						(effects
							(font
								(size 1.27 1.27)
							)
						)
					)
					(number "L26"
						(effects
							(font
								(size 1.27 1.27)
							)
						)
					)
				)
				(pin passive line
					(at 0 -66.04 0)
					(length 3.81)
					(name "L27"
						(effects
							(font
								(size 1.27 1.27)
							)
						)
					)
					(number "L27"
						(effects
							(font
								(size 1.27 1.27)
							)
						)
					)
				)
				(pin passive line
					(at 0 -68.58 0)
					(length 3.81)
					(name "L28"
						(effects
							(font
								(size 1.27 1.27)
							)
						)
					)
					(number "L28"
						(effects
							(font
								(size 1.27 1.27)
							)
						)
					)
				)
				(pin passive line
					(at 0 -71.12 0)
					(length 3.81)
					(name "L29"
						(effects
							(font
								(size 1.27 1.27)
							)
						)
					)
					(number "L29"
						(effects
							(font
								(size 1.27 1.27)
							)
						)
					)
				)
				(pin passive line
					(at 0 -73.66 0)
					(length 3.81)
					(name "L30"
						(effects
							(font
								(size 1.27 1.27)
							)
						)
					)
					(number "L30"
						(effects
							(font
								(size 1.27 1.27)
							)
						)
					)
				)
				(pin passive line
					(at 0 -76.2 0)
					(length 3.81)
					(name "L31"
						(effects
							(font
								(size 1.27 1.27)
							)
						)
					)
					(number "L31"
						(effects
							(font
								(size 1.27 1.27)
							)
						)
					)
				)
				(pin passive line
					(at 0 -78.74 0)
					(length 3.81)
					(name "L32"
						(effects
							(font
								(size 1.27 1.27)
							)
						)
					)
					(number "L32"
						(effects
							(font
								(size 1.27 1.27)
							)
						)
					)
				)
				(pin passive line
					(at 0 -81.28 0)
					(length 3.81)
					(name "L33"
						(effects
							(font
								(size 1.27 1.27)
							)
						)
					)
					(number "L33"
						(effects
							(font
								(size 1.27 1.27)
							)
						)
					)
				)
				(pin passive line
					(at 0 -83.82 0)
					(length 3.81)
					(name "L34"
						(effects
							(font
								(size 1.27 1.27)
							)
						)
					)
					(number "L34"
						(effects
							(font
								(size 1.27 1.27)
							)
						)
					)
				)
				(pin passive line
					(at 0 -86.36 0)
					(length 3.81)
					(name "L35"
						(effects
							(font
								(size 1.27 1.27)
							)
						)
					)
					(number "L35"
						(effects
							(font
								(size 1.27 1.27)
							)
						)
					)
				)
				(pin passive line
					(at 0 -88.9 0)
					(length 3.81)
					(name "L36"
						(effects
							(font
								(size 1.27 1.27)
							)
						)
					)
					(number "L36"
						(effects
							(font
								(size 1.27 1.27)
							)
						)
					)
				)
				(pin passive line
					(at 0 -91.44 0)
					(length 3.81)
					(name "L37"
						(effects
							(font
								(size 1.27 1.27)
							)
						)
					)
					(number "L37"
						(effects
							(font
								(size 1.27 1.27)
							)
						)
					)
				)
				(pin passive line
					(at 0 -93.98 0)
					(length 3.81)
					(name "L38"
						(effects
							(font
								(size 1.27 1.27)
							)
						)
					)
					(number "L38"
						(effects
							(font
								(size 1.27 1.27)
							)
						)
					)
				)
				(pin passive line
					(at 0 -96.52 0)
					(length 3.81)
					(name "L39"
						(effects
							(font
								(size 1.27 1.27)
							)
						)
					)
					(number "L39"
						(effects
							(font
								(size 1.27 1.27)
							)
						)
					)
				)
				(pin passive line
					(at 0 -99.06 0)
					(length 3.81)
					(name "L40"
						(effects
							(font
								(size 1.27 1.27)
							)
						)
					)
					(number "L40"
						(effects
							(font
								(size 1.27 1.27)
							)
						)
					)
				)
				(pin passive line
					(at 22.86 0 180)
					(length 3.81)
					(name "M01"
						(effects
							(font
								(size 1.27 1.27)
							)
						)
					)
					(number "M01"
						(effects
							(font
								(size 1.27 1.27)
							)
						)
					)
				)
				(pin passive line
					(at 22.86 -2.54 180)
					(length 3.81)
					(name "M02"
						(effects
							(font
								(size 1.27 1.27)
							)
						)
					)
					(number "M02"
						(effects
							(font
								(size 1.27 1.27)
							)
						)
					)
				)
				(pin passive line
					(at 22.86 -5.08 180)
					(length 3.81)
					(name "M03"
						(effects
							(font
								(size 1.27 1.27)
							)
						)
					)
					(number "M03"
						(effects
							(font
								(size 1.27 1.27)
							)
						)
					)
				)
				(pin passive line
					(at 22.86 -7.62 180)
					(length 3.81)
					(name "M04"
						(effects
							(font
								(size 1.27 1.27)
							)
						)
					)
					(number "M04"
						(effects
							(font
								(size 1.27 1.27)
							)
						)
					)
				)
				(pin passive line
					(at 22.86 -10.16 180)
					(length 3.81)
					(name "M05"
						(effects
							(font
								(size 1.27 1.27)
							)
						)
					)
					(number "M05"
						(effects
							(font
								(size 1.27 1.27)
							)
						)
					)
				)
				(pin passive line
					(at 22.86 -12.7 180)
					(length 3.81)
					(name "M06"
						(effects
							(font
								(size 1.27 1.27)
							)
						)
					)
					(number "M06"
						(effects
							(font
								(size 1.27 1.27)
							)
						)
					)
				)
				(pin passive line
					(at 22.86 -15.24 180)
					(length 3.81)
					(name "M07"
						(effects
							(font
								(size 1.27 1.27)
							)
						)
					)
					(number "M07"
						(effects
							(font
								(size 1.27 1.27)
							)
						)
					)
				)
				(pin passive line
					(at 22.86 -17.78 180)
					(length 3.81)
					(name "M08"
						(effects
							(font
								(size 1.27 1.27)
							)
						)
					)
					(number "M08"
						(effects
							(font
								(size 1.27 1.27)
							)
						)
					)
				)
				(pin passive line
					(at 22.86 -20.32 180)
					(length 3.81)
					(name "M09"
						(effects
							(font
								(size 1.27 1.27)
							)
						)
					)
					(number "M09"
						(effects
							(font
								(size 1.27 1.27)
							)
						)
					)
				)
				(pin passive line
					(at 22.86 -22.86 180)
					(length 3.81)
					(name "M10"
						(effects
							(font
								(size 1.27 1.27)
							)
						)
					)
					(number "M10"
						(effects
							(font
								(size 1.27 1.27)
							)
						)
					)
				)
				(pin passive line
					(at 22.86 -25.4 180)
					(length 3.81)
					(name "M11"
						(effects
							(font
								(size 1.27 1.27)
							)
						)
					)
					(number "M11"
						(effects
							(font
								(size 1.27 1.27)
							)
						)
					)
				)
				(pin passive line
					(at 22.86 -27.94 180)
					(length 3.81)
					(name "M12"
						(effects
							(font
								(size 1.27 1.27)
							)
						)
					)
					(number "M12"
						(effects
							(font
								(size 1.27 1.27)
							)
						)
					)
				)
				(pin passive line
					(at 22.86 -30.48 180)
					(length 3.81)
					(name "M13"
						(effects
							(font
								(size 1.27 1.27)
							)
						)
					)
					(number "M13"
						(effects
							(font
								(size 1.27 1.27)
							)
						)
					)
				)
				(pin passive line
					(at 22.86 -33.02 180)
					(length 3.81)
					(name "M14"
						(effects
							(font
								(size 1.27 1.27)
							)
						)
					)
					(number "M14"
						(effects
							(font
								(size 1.27 1.27)
							)
						)
					)
				)
				(pin passive line
					(at 22.86 -35.56 180)
					(length 3.81)
					(name "M15"
						(effects
							(font
								(size 1.27 1.27)
							)
						)
					)
					(number "M15"
						(effects
							(font
								(size 1.27 1.27)
							)
						)
					)
				)
				(pin passive line
					(at 22.86 -38.1 180)
					(length 3.81)
					(name "M16"
						(effects
							(font
								(size 1.27 1.27)
							)
						)
					)
					(number "M16"
						(effects
							(font
								(size 1.27 1.27)
							)
						)
					)
				)
				(pin passive line
					(at 22.86 -40.64 180)
					(length 3.81)
					(name "M17"
						(effects
							(font
								(size 1.27 1.27)
							)
						)
					)
					(number "M17"
						(effects
							(font
								(size 1.27 1.27)
							)
						)
					)
				)
				(pin passive line
					(at 22.86 -43.18 180)
					(length 3.81)
					(name "M18"
						(effects
							(font
								(size 1.27 1.27)
							)
						)
					)
					(number "M18"
						(effects
							(font
								(size 1.27 1.27)
							)
						)
					)
				)
				(pin passive line
					(at 22.86 -45.72 180)
					(length 3.81)
					(name "M19"
						(effects
							(font
								(size 1.27 1.27)
							)
						)
					)
					(number "M19"
						(effects
							(font
								(size 1.27 1.27)
							)
						)
					)
				)
				(pin passive line
					(at 22.86 -48.26 180)
					(length 3.81)
					(name "M20"
						(effects
							(font
								(size 1.27 1.27)
							)
						)
					)
					(number "M20"
						(effects
							(font
								(size 1.27 1.27)
							)
						)
					)
				)
				(pin passive line
					(at 22.86 -50.8 180)
					(length 3.81)
					(name "M21"
						(effects
							(font
								(size 1.27 1.27)
							)
						)
					)
					(number "M21"
						(effects
							(font
								(size 1.27 1.27)
							)
						)
					)
				)
				(pin passive line
					(at 22.86 -53.34 180)
					(length 3.81)
					(name "M22"
						(effects
							(font
								(size 1.27 1.27)
							)
						)
					)
					(number "M22"
						(effects
							(font
								(size 1.27 1.27)
							)
						)
					)
				)
				(pin passive line
					(at 22.86 -55.88 180)
					(length 3.81)
					(name "M23"
						(effects
							(font
								(size 1.27 1.27)
							)
						)
					)
					(number "M23"
						(effects
							(font
								(size 1.27 1.27)
							)
						)
					)
				)
				(pin passive line
					(at 22.86 -58.42 180)
					(length 3.81)
					(name "M24"
						(effects
							(font
								(size 1.27 1.27)
							)
						)
					)
					(number "M24"
						(effects
							(font
								(size 1.27 1.27)
							)
						)
					)
				)
				(pin passive line
					(at 22.86 -60.96 180)
					(length 3.81)
					(name "M25"
						(effects
							(font
								(size 1.27 1.27)
							)
						)
					)
					(number "M25"
						(effects
							(font
								(size 1.27 1.27)
							)
						)
					)
				)
				(pin passive line
					(at 22.86 -63.5 180)
					(length 3.81)
					(name "M26"
						(effects
							(font
								(size 1.27 1.27)
							)
						)
					)
					(number "M26"
						(effects
							(font
								(size 1.27 1.27)
							)
						)
					)
				)
				(pin passive line
					(at 22.86 -66.04 180)
					(length 3.81)
					(name "M27"
						(effects
							(font
								(size 1.27 1.27)
							)
						)
					)
					(number "M27"
						(effects
							(font
								(size 1.27 1.27)
							)
						)
					)
				)
				(pin passive line
					(at 22.86 -68.58 180)
					(length 3.81)
					(name "M28"
						(effects
							(font
								(size 1.27 1.27)
							)
						)
					)
					(number "M28"
						(effects
							(font
								(size 1.27 1.27)
							)
						)
					)
				)
				(pin passive line
					(at 22.86 -71.12 180)
					(length 3.81)
					(name "M29"
						(effects
							(font
								(size 1.27 1.27)
							)
						)
					)
					(number "M29"
						(effects
							(font
								(size 1.27 1.27)
							)
						)
					)
				)
				(pin passive line
					(at 22.86 -73.66 180)
					(length 3.81)
					(name "M30"
						(effects
							(font
								(size 1.27 1.27)
							)
						)
					)
					(number "M30"
						(effects
							(font
								(size 1.27 1.27)
							)
						)
					)
				)
				(pin passive line
					(at 22.86 -76.2 180)
					(length 3.81)
					(name "M31"
						(effects
							(font
								(size 1.27 1.27)
							)
						)
					)
					(number "M31"
						(effects
							(font
								(size 1.27 1.27)
							)
						)
					)
				)
				(pin passive line
					(at 22.86 -78.74 180)
					(length 3.81)
					(name "M32"
						(effects
							(font
								(size 1.27 1.27)
							)
						)
					)
					(number "M32"
						(effects
							(font
								(size 1.27 1.27)
							)
						)
					)
				)
				(pin passive line
					(at 22.86 -81.28 180)
					(length 3.81)
					(name "M33"
						(effects
							(font
								(size 1.27 1.27)
							)
						)
					)
					(number "M33"
						(effects
							(font
								(size 1.27 1.27)
							)
						)
					)
				)
				(pin passive line
					(at 22.86 -83.82 180)
					(length 3.81)
					(name "M34"
						(effects
							(font
								(size 1.27 1.27)
							)
						)
					)
					(number "M34"
						(effects
							(font
								(size 1.27 1.27)
							)
						)
					)
				)
				(pin passive line
					(at 22.86 -86.36 180)
					(length 3.81)
					(name "M35"
						(effects
							(font
								(size 1.27 1.27)
							)
						)
					)
					(number "M35"
						(effects
							(font
								(size 1.27 1.27)
							)
						)
					)
				)
				(pin passive line
					(at 22.86 -88.9 180)
					(length 3.81)
					(name "M36"
						(effects
							(font
								(size 1.27 1.27)
							)
						)
					)
					(number "M36"
						(effects
							(font
								(size 1.27 1.27)
							)
						)
					)
				)
				(pin passive line
					(at 22.86 -91.44 180)
					(length 3.81)
					(name "M37"
						(effects
							(font
								(size 1.27 1.27)
							)
						)
					)
					(number "M37"
						(effects
							(font
								(size 1.27 1.27)
							)
						)
					)
				)
				(pin passive line
					(at 22.86 -93.98 180)
					(length 3.81)
					(name "M38"
						(effects
							(font
								(size 1.27 1.27)
							)
						)
					)
					(number "M38"
						(effects
							(font
								(size 1.27 1.27)
							)
						)
					)
				)
				(pin passive line
					(at 22.86 -96.52 180)
					(length 3.81)
					(name "M39"
						(effects
							(font
								(size 1.27 1.27)
							)
						)
					)
					(number "M39"
						(effects
							(font
								(size 1.27 1.27)
							)
						)
					)
				)
				(pin passive line
					(at 22.86 -99.06 180)
					(length 3.81)
					(name "M40"
						(effects
							(font
								(size 1.27 1.27)
							)
						)
					)
					(number "M40"
						(effects
							(font
								(size 1.27 1.27)
							)
						)
					)
				)
			)
		)
	(symbol "antmicroB2BConnectors:Hermaphroditic_Molex_203456-0003_CUSTOM_Jetson_AGX_Thor_H8mm"
			(exclude_from_sim no)
			(in_bom yes)
			(on_board yes)
			(property "Reference" "J"
				(at 72.39 -2.54 0)
				(effects
					(font
						(size 1.27 1.27)
						(thickness 0.15)
					)
					(justify left bottom)
				)
			)
			(property "Value" "Hermaphroditic_Molex_203456-0003_CUSTOM_Jetson_AGX_Thor_H8mm"
				(at 72.39 -7.62 0)
				(effects
					(font
						(size 1.27 1.27)
						(thickness 0.15)
					)
					(justify left bottom)
					(hide yes)
				)
			)
			(property "Footprint" "antmicro-footprints:Conn_Hermaphroditic_Molex_203456-0003_mirrored"
				(at 72.39 -10.16 0)
				(effects
					(font
						(size 1.27 1.27)
						(thickness 0.15)
					)
					(justify left bottom)
					(hide yes)
				)
			)
			(property "Datasheet" "https://www.molex.com/content/dam/molex/molex-dot-com/products/automated/en-us/salesdrawingpdf/203/203456/2034560003_sd.pdf?inline"
				(at 72.39 -12.7 0)
				(effects
					(font
						(size 1.27 1.27)
						(thickness 0.15)
					)
					(justify left bottom)
					(hide yes)
				)
			)
			(property "Description" "Mirror Mezz Hermaphroditic Connector, 5.50mm Connector Height, BGA-Attach Mounting, 7 Pair, 11 Row, 699 Circuits, 0.76µm Gold Plating, without Pegs"
				(at 72.39 -25.4 0)
				(effects
					(font
						(size 1.27 1.27)
						(thickness 0.15)
					)
					(justify left bottom)
					(hide yes)
				)
			)
			(property "MPN" "203456-0003"
				(at 72.39 -5.08 0)
				(effects
					(font
						(size 1.27 1.27)
						(thickness 0.15)
					)
					(justify left bottom)
				)
			)
			(property "Manufacturer" "Molex"
				(at 72.39 -17.78 0)
				(effects
					(font
						(size 1.27 1.27)
						(thickness 0.15)
					)
					(justify left bottom)
					(hide yes)
				)
			)
			(property "Author" "Antmicro"
				(at 72.39 -20.32 0)
				(effects
					(font
						(size 1.27 1.27)
						(thickness 0.15)
					)
					(justify left bottom)
					(hide yes)
				)
			)
			(property "License" "Apache-2.0"
				(at 72.39 -22.86 0)
				(effects
					(font
						(size 1.27 1.27)
						(thickness 0.15)
					)
					(justify left bottom)
					(hide yes)
				)
			)
			(property "ki_locked" ""
				(at 0 0 0)
				(effects
					(font
						(size 1.27 1.27)
					)
				)
			)
			(property "ki_keywords" "CONNECTOR, B2B"
				(at 0 0 0)
				(effects
					(font
						(size 1.27 1.27)
					)
					(hide yes)
				)
			)
			(symbol "Hermaphroditic_Molex_203456-0003_CUSTOM_Jetson_AGX_Thor_H8mm_1_1"
				(rectangle
					(start 3.81 2.54)
					(end 53.34 -53.34)
					(stroke
						(width 0.254)
						(type default)
					)
					(fill
						(type background)
					)
				)
				(pin power_in line
					(at 0 0 0)
					(length 3.81)
					(name "SYS_VIN_HV"
						(effects
							(font
								(size 1.27 1.27)
							)
						)
					)
					(number "B3"
						(effects
							(font
								(size 1.27 1.27)
							)
						)
					)
				)
				(pin passive line
					(at 0 0 0)
					(length 3.81)
					(hide yes)
					(name "SYS_VIN_HV"
						(effects
							(font
								(size 1.27 1.27)
							)
						)
					)
					(number "B63"
						(effects
							(font
								(size 1.27 1.27)
							)
						)
					)
				)
				(pin passive line
					(at 0 0 0)
					(length 3.81)
					(hide yes)
					(name "SYS_VIN_HV"
						(effects
							(font
								(size 1.27 1.27)
							)
						)
					)
					(number "C1"
						(effects
							(font
								(size 1.27 1.27)
							)
						)
					)
				)
				(pin passive line
					(at 0 0 0)
					(length 3.81)
					(hide yes)
					(name "SYS_VIN_HV"
						(effects
							(font
								(size 1.27 1.27)
							)
						)
					)
					(number "C2"
						(effects
							(font
								(size 1.27 1.27)
							)
						)
					)
				)
				(pin passive line
					(at 0 0 0)
					(length 3.81)
					(hide yes)
					(name "SYS_VIN_HV"
						(effects
							(font
								(size 1.27 1.27)
							)
						)
					)
					(number "C63"
						(effects
							(font
								(size 1.27 1.27)
							)
						)
					)
				)
				(pin passive line
					(at 0 0 0)
					(length 3.81)
					(hide yes)
					(name "SYS_VIN_HV"
						(effects
							(font
								(size 1.27 1.27)
							)
						)
					)
					(number "C64"
						(effects
							(font
								(size 1.27 1.27)
							)
						)
					)
				)
				(pin passive line
					(at 0 0 0)
					(length 3.81)
					(hide yes)
					(name "SYS_VIN_HV"
						(effects
							(font
								(size 1.27 1.27)
							)
						)
					)
					(number "C65"
						(effects
							(font
								(size 1.27 1.27)
							)
						)
					)
				)
				(pin passive line
					(at 0 0 0)
					(length 3.81)
					(hide yes)
					(name "SYS_VIN_HV"
						(effects
							(font
								(size 1.27 1.27)
							)
						)
					)
					(number "D1"
						(effects
							(font
								(size 1.27 1.27)
							)
						)
					)
				)
				(pin passive line
					(at 0 0 0)
					(length 3.81)
					(hide yes)
					(name "SYS_VIN_HV"
						(effects
							(font
								(size 1.27 1.27)
							)
						)
					)
					(number "D2"
						(effects
							(font
								(size 1.27 1.27)
							)
						)
					)
				)
				(pin passive line
					(at 0 0 0)
					(length 3.81)
					(hide yes)
					(name "SYS_VIN_HV"
						(effects
							(font
								(size 1.27 1.27)
							)
						)
					)
					(number "D3"
						(effects
							(font
								(size 1.27 1.27)
							)
						)
					)
				)
				(pin passive line
					(at 0 0 0)
					(length 3.81)
					(hide yes)
					(name "SYS_VIN_HV"
						(effects
							(font
								(size 1.27 1.27)
							)
						)
					)
					(number "D64"
						(effects
							(font
								(size 1.27 1.27)
							)
						)
					)
				)
				(pin passive line
					(at 0 0 0)
					(length 3.81)
					(hide yes)
					(name "SYS_VIN_HV"
						(effects
							(font
								(size 1.27 1.27)
							)
						)
					)
					(number "D65"
						(effects
							(font
								(size 1.27 1.27)
							)
						)
					)
				)
				(pin passive line
					(at 0 0 0)
					(length 3.81)
					(hide yes)
					(name "SYS_VIN_HV"
						(effects
							(font
								(size 1.27 1.27)
							)
						)
					)
					(number "E1"
						(effects
							(font
								(size 1.27 1.27)
							)
						)
					)
				)
				(pin passive line
					(at 0 0 0)
					(length 3.81)
					(hide yes)
					(name "SYS_VIN_HV"
						(effects
							(font
								(size 1.27 1.27)
							)
						)
					)
					(number "E2"
						(effects
							(font
								(size 1.27 1.27)
							)
						)
					)
				)
				(pin passive line
					(at 0 0 0)
					(length 3.81)
					(hide yes)
					(name "SYS_VIN_HV"
						(effects
							(font
								(size 1.27 1.27)
							)
						)
					)
					(number "E63"
						(effects
							(font
								(size 1.27 1.27)
							)
						)
					)
				)
				(pin passive line
					(at 0 0 0)
					(length 3.81)
					(hide yes)
					(name "SYS_VIN_HV"
						(effects
							(font
								(size 1.27 1.27)
							)
						)
					)
					(number "E64"
						(effects
							(font
								(size 1.27 1.27)
							)
						)
					)
				)
				(pin passive line
					(at 0 0 0)
					(length 3.81)
					(hide yes)
					(name "SYS_VIN_HV"
						(effects
							(font
								(size 1.27 1.27)
							)
						)
					)
					(number "E65"
						(effects
							(font
								(size 1.27 1.27)
							)
						)
					)
				)
				(pin passive line
					(at 0 0 0)
					(length 3.81)
					(hide yes)
					(name "SYS_VIN_HV"
						(effects
							(font
								(size 1.27 1.27)
							)
						)
					)
					(number "F1"
						(effects
							(font
								(size 1.27 1.27)
							)
						)
					)
				)
				(pin passive line
					(at 0 0 0)
					(length 3.81)
					(hide yes)
					(name "SYS_VIN_HV"
						(effects
							(font
								(size 1.27 1.27)
							)
						)
					)
					(number "F2"
						(effects
							(font
								(size 1.27 1.27)
							)
						)
					)
				)
				(pin passive line
					(at 0 0 0)
					(length 3.81)
					(hide yes)
					(name "SYS_VIN_HV"
						(effects
							(font
								(size 1.27 1.27)
							)
						)
					)
					(number "F3"
						(effects
							(font
								(size 1.27 1.27)
							)
						)
					)
				)
				(pin passive line
					(at 0 0 0)
					(length 3.81)
					(hide yes)
					(name "SYS_VIN_HV"
						(effects
							(font
								(size 1.27 1.27)
							)
						)
					)
					(number "F63"
						(effects
							(font
								(size 1.27 1.27)
							)
						)
					)
				)
				(pin passive line
					(at 0 0 0)
					(length 3.81)
					(hide yes)
					(name "SYS_VIN_HV"
						(effects
							(font
								(size 1.27 1.27)
							)
						)
					)
					(number "F64"
						(effects
							(font
								(size 1.27 1.27)
							)
						)
					)
				)
				(pin passive line
					(at 0 0 0)
					(length 3.81)
					(hide yes)
					(name "SYS_VIN_HV"
						(effects
							(font
								(size 1.27 1.27)
							)
						)
					)
					(number "F65"
						(effects
							(font
								(size 1.27 1.27)
							)
						)
					)
				)
				(pin passive line
					(at 0 0 0)
					(length 3.81)
					(hide yes)
					(name "SYS_VIN_HV"
						(effects
							(font
								(size 1.27 1.27)
							)
						)
					)
					(number "G1"
						(effects
							(font
								(size 1.27 1.27)
							)
						)
					)
				)
				(pin passive line
					(at 0 0 0)
					(length 3.81)
					(hide yes)
					(name "SYS_VIN_HV"
						(effects
							(font
								(size 1.27 1.27)
							)
						)
					)
					(number "G2"
						(effects
							(font
								(size 1.27 1.27)
							)
						)
					)
				)
				(pin passive line
					(at 0 0 0)
					(length 3.81)
					(hide yes)
					(name "SYS_VIN_HV"
						(effects
							(font
								(size 1.27 1.27)
							)
						)
					)
					(number "G63"
						(effects
							(font
								(size 1.27 1.27)
							)
						)
					)
				)
				(pin passive line
					(at 0 0 0)
					(length 3.81)
					(hide yes)
					(name "SYS_VIN_HV"
						(effects
							(font
								(size 1.27 1.27)
							)
						)
					)
					(number "G64"
						(effects
							(font
								(size 1.27 1.27)
							)
						)
					)
				)
				(pin passive line
					(at 0 0 0)
					(length 3.81)
					(hide yes)
					(name "SYS_VIN_HV"
						(effects
							(font
								(size 1.27 1.27)
							)
						)
					)
					(number "G65"
						(effects
							(font
								(size 1.27 1.27)
							)
						)
					)
				)
				(pin passive line
					(at 0 0 0)
					(length 3.81)
					(hide yes)
					(name "SYS_VIN_HV"
						(effects
							(font
								(size 1.27 1.27)
							)
						)
					)
					(number "H1"
						(effects
							(font
								(size 1.27 1.27)
							)
						)
					)
				)
				(pin passive line
					(at 0 0 0)
					(length 3.81)
					(hide yes)
					(name "SYS_VIN_HV"
						(effects
							(font
								(size 1.27 1.27)
							)
						)
					)
					(number "H2"
						(effects
							(font
								(size 1.27 1.27)
							)
						)
					)
				)
				(pin passive line
					(at 0 0 0)
					(length 3.81)
					(hide yes)
					(name "SYS_VIN_HV"
						(effects
							(font
								(size 1.27 1.27)
							)
						)
					)
					(number "H3"
						(effects
							(font
								(size 1.27 1.27)
							)
						)
					)
				)
				(pin passive line
					(at 0 0 0)
					(length 3.81)
					(hide yes)
					(name "SYS_VIN_HV"
						(effects
							(font
								(size 1.27 1.27)
							)
						)
					)
					(number "H64"
						(effects
							(font
								(size 1.27 1.27)
							)
						)
					)
				)
				(pin passive line
					(at 0 0 0)
					(length 3.81)
					(hide yes)
					(name "SYS_VIN_HV"
						(effects
							(font
								(size 1.27 1.27)
							)
						)
					)
					(number "H65"
						(effects
							(font
								(size 1.27 1.27)
							)
						)
					)
				)
				(pin passive line
					(at 0 0 0)
					(length 3.81)
					(hide yes)
					(name "SYS_VIN_HV"
						(effects
							(font
								(size 1.27 1.27)
							)
						)
					)
					(number "J1"
						(effects
							(font
								(size 1.27 1.27)
							)
						)
					)
				)
				(pin passive line
					(at 0 0 0)
					(length 3.81)
					(hide yes)
					(name "SYS_VIN_HV"
						(effects
							(font
								(size 1.27 1.27)
							)
						)
					)
					(number "J2"
						(effects
							(font
								(size 1.27 1.27)
							)
						)
					)
				)
				(pin passive line
					(at 0 0 0)
					(length 3.81)
					(hide yes)
					(name "SYS_VIN_HV"
						(effects
							(font
								(size 1.27 1.27)
							)
						)
					)
					(number "J63"
						(effects
							(font
								(size 1.27 1.27)
							)
						)
					)
				)
				(pin passive line
					(at 0 0 0)
					(length 3.81)
					(hide yes)
					(name "SYS_VIN_HV"
						(effects
							(font
								(size 1.27 1.27)
							)
						)
					)
					(number "J64"
						(effects
							(font
								(size 1.27 1.27)
							)
						)
					)
				)
				(pin passive line
					(at 0 0 0)
					(length 3.81)
					(hide yes)
					(name "SYS_VIN_HV"
						(effects
							(font
								(size 1.27 1.27)
							)
						)
					)
					(number "J65"
						(effects
							(font
								(size 1.27 1.27)
							)
						)
					)
				)
				(pin passive line
					(at 0 0 0)
					(length 3.81)
					(hide yes)
					(name "SYS_VIN_HV"
						(effects
							(font
								(size 1.27 1.27)
							)
						)
					)
					(number "K3"
						(effects
							(font
								(size 1.27 1.27)
							)
						)
					)
				)
				(pin power_in line
					(at 0 -2.54 0)
					(length 3.81)
					(name "SYS_VIN_MV"
						(effects
							(font
								(size 1.27 1.27)
							)
						)
					)
					(number "L22"
						(effects
							(font
								(size 1.27 1.27)
							)
						)
					)
				)
				(pin passive line
					(at 0 -2.54 0)
					(length 3.81)
					(hide yes)
					(name "SYS_VIN_MV"
						(effects
							(font
								(size 1.27 1.27)
							)
						)
					)
					(number "L23"
						(effects
							(font
								(size 1.27 1.27)
							)
						)
					)
				)
				(pin passive line
					(at 0 -2.54 0)
					(length 3.81)
					(hide yes)
					(name "SYS_VIN_MV"
						(effects
							(font
								(size 1.27 1.27)
							)
						)
					)
					(number "L26"
						(effects
							(font
								(size 1.27 1.27)
							)
						)
					)
				)
				(pin passive line
					(at 0 -2.54 0)
					(length 3.81)
					(hide yes)
					(name "SYS_VIN_MV"
						(effects
							(font
								(size 1.27 1.27)
							)
						)
					)
					(number "L27"
						(effects
							(font
								(size 1.27 1.27)
							)
						)
					)
				)
				(pin passive line
					(at 0 -2.54 0)
					(length 3.81)
					(hide yes)
					(name "SYS_VIN_MV"
						(effects
							(font
								(size 1.27 1.27)
							)
						)
					)
					(number "L30"
						(effects
							(font
								(size 1.27 1.27)
							)
						)
					)
				)
				(pin passive line
					(at 0 -2.54 0)
					(length 3.81)
					(hide yes)
					(name "SYS_VIN_MV"
						(effects
							(font
								(size 1.27 1.27)
							)
						)
					)
					(number "L31"
						(effects
							(font
								(size 1.27 1.27)
							)
						)
					)
				)
				(pin passive line
					(at 0 -2.54 0)
					(length 3.81)
					(hide yes)
					(name "SYS_VIN_MV"
						(effects
							(font
								(size 1.27 1.27)
							)
						)
					)
					(number "L34"
						(effects
							(font
								(size 1.27 1.27)
							)
						)
					)
				)
				(pin passive line
					(at 0 -2.54 0)
					(length 3.81)
					(hide yes)
					(name "SYS_VIN_MV"
						(effects
							(font
								(size 1.27 1.27)
							)
						)
					)
					(number "L35"
						(effects
							(font
								(size 1.27 1.27)
							)
						)
					)
				)
				(pin passive line
					(at 0 -2.54 0)
					(length 3.81)
					(hide yes)
					(name "SYS_VIN_MV"
						(effects
							(font
								(size 1.27 1.27)
							)
						)
					)
					(number "L38"
						(effects
							(font
								(size 1.27 1.27)
							)
						)
					)
				)
				(pin passive line
					(at 0 -2.54 0)
					(length 3.81)
					(hide yes)
					(name "SYS_VIN_MV"
						(effects
							(font
								(size 1.27 1.27)
							)
						)
					)
					(number "L39"
						(effects
							(font
								(size 1.27 1.27)
							)
						)
					)
				)
				(pin power_in line
					(at 0 -5.08 0)
					(length 3.81)
					(name "SYS_VIN_SV"
						(effects
							(font
								(size 1.27 1.27)
							)
						)
					)
					(number "L53"
						(effects
							(font
								(size 1.27 1.27)
							)
						)
					)
				)
				(pin power_in line
					(at 0 -7.62 0)
					(length 3.81)
					(name "PMIC_BBATT"
						(effects
							(font
								(size 1.27 1.27)
							)
						)
					)
					(number "D37"
						(effects
							(font
								(size 1.27 1.27)
							)
						)
					)
				)
				(pin input line
					(at 0 -10.16 0)
					(length 3.81)
					(name "POWER_INT_N"
						(effects
							(font
								(size 1.27 1.27)
							)
						)
					)
					(number "B10"
						(effects
							(font
								(size 1.27 1.27)
							)
						)
					)
				)
				(pin output line
					(at 0 -15.24 0)
					(length 3.81)
					(name "MODULE_POWER_GOOD"
						(effects
							(font
								(size 1.27 1.27)
							)
						)
					)
					(number "L59"
						(effects
							(font
								(size 1.27 1.27)
							)
						)
					)
				)
				(pin bidirectional line
					(at 0 -17.78 0)
					(length 3.81)
					(name "SYS_RESET_N"
						(effects
							(font
								(size 1.27 1.27)
							)
						)
					)
					(number "L60"
						(effects
							(font
								(size 1.27 1.27)
							)
						)
					)
				)
				(pin bidirectional line
					(at 0 -20.32 0)
					(length 3.81)
					(name "VDDIN_PWR_BAD_N"
						(effects
							(font
								(size 1.27 1.27)
							)
						)
					)
					(number "L55"
						(effects
							(font
								(size 1.27 1.27)
							)
						)
					)
				)
				(pin passive line
					(at 0 -24.13 0)
					(length 3.81)
					(name "PRSNT0"
						(effects
							(font
								(size 1.27 1.27)
							)
						)
					)
					(number "A3"
						(effects
							(font
								(size 1.27 1.27)
							)
						)
					)
					(alternate "GND_LOOP_0" passive line)
				)
				(pin passive line
					(at 0 -26.67 0)
					(length 3.81)
					(name "PRSNT1"
						(effects
							(font
								(size 1.27 1.27)
							)
						)
					)
					(number "L63"
						(effects
							(font
								(size 1.27 1.27)
							)
						)
					)
				)
				(pin passive line
					(at 0 -30.48 0)
					(length 3.81)
					(name "MID0"
						(effects
							(font
								(size 1.27 1.27)
							)
						)
					)
					(number "K40"
						(effects
							(font
								(size 1.27 1.27)
							)
						)
					)
				)
				(pin passive line
					(at 0 -33.02 0)
					(length 3.81)
					(name "MID1"
						(effects
							(font
								(size 1.27 1.27)
							)
						)
					)
					(number "H40"
						(effects
							(font
								(size 1.27 1.27)
							)
						)
					)
				)
				(pin input line
					(at 0 -38.1 0)
					(length 3.81)
					(name "MV_LSW_MON"
						(effects
							(font
								(size 1.27 1.27)
							)
						)
					)
					(number "L42"
						(effects
							(font
								(size 1.27 1.27)
							)
						)
					)
				)
				(pin input line
					(at 0 -41.91 0)
					(length 3.81)
					(name "VM_INT_N"
						(effects
							(font
								(size 1.27 1.27)
							)
						)
					)
					(number "L47"
						(effects
							(font
								(size 1.27 1.27)
							)
						)
					)
				)
				(pin passive line
					(at 0 -44.45 0)
					(length 3.81)
					(name "GPIO39"
						(effects
							(font
								(size 1.27 1.27)
							)
						)
					)
					(number "C55"
						(effects
							(font
								(size 1.27 1.27)
							)
						)
					)
					(alternate "BOOT_CHAIN_0" passive line)
				)
				(pin passive line
					(at 0 -46.99 0)
					(length 3.81)
					(name "GPIO31"
						(effects
							(font
								(size 1.27 1.27)
							)
						)
					)
					(number "H60"
						(effects
							(font
								(size 1.27 1.27)
							)
						)
					)
					(alternate "IST_REQ_N" passive line)
				)
				(pin passive line
					(at 0 -50.8 0)
					(length 3.81)
					(hide yes)
					(name "GND"
						(effects
							(font
								(size 1.27 1.27)
							)
						)
					)
					(number "A12"
						(effects
							(font
								(size 1.27 1.27)
							)
						)
					)
				)
				(pin passive line
					(at 0 -50.8 0)
					(length 3.81)
					(hide yes)
					(name "GND"
						(effects
							(font
								(size 1.27 1.27)
							)
						)
					)
					(number "A13"
						(effects
							(font
								(size 1.27 1.27)
							)
						)
					)
				)
				(pin passive line
					(at 0 -50.8 0)
					(length 3.81)
					(hide yes)
					(name "GND"
						(effects
							(font
								(size 1.27 1.27)
							)
						)
					)
					(number "A16"
						(effects
							(font
								(size 1.27 1.27)
							)
						)
					)
				)
				(pin passive line
					(at 0 -50.8 0)
					(length 3.81)
					(hide yes)
					(name "GND"
						(effects
							(font
								(size 1.27 1.27)
							)
						)
					)
					(number "A17"
						(effects
							(font
								(size 1.27 1.27)
							)
						)
					)
				)
				(pin passive line
					(at 0 -50.8 0)
					(length 3.81)
					(hide yes)
					(name "GND"
						(effects
							(font
								(size 1.27 1.27)
							)
						)
					)
					(number "A20"
						(effects
							(font
								(size 1.27 1.27)
							)
						)
					)
				)
				(pin passive line
					(at 0 -50.8 0)
					(length 3.81)
					(hide yes)
					(name "GND"
						(effects
							(font
								(size 1.27 1.27)
							)
						)
					)
					(number "A21"
						(effects
							(font
								(size 1.27 1.27)
							)
						)
					)
				)
				(pin passive line
					(at 0 -50.8 0)
					(length 3.81)
					(hide yes)
					(name "GND"
						(effects
							(font
								(size 1.27 1.27)
							)
						)
					)
					(number "A24"
						(effects
							(font
								(size 1.27 1.27)
							)
						)
					)
				)
				(pin passive line
					(at 0 -50.8 0)
					(length 3.81)
					(hide yes)
					(name "GND"
						(effects
							(font
								(size 1.27 1.27)
							)
						)
					)
					(number "A25"
						(effects
							(font
								(size 1.27 1.27)
							)
						)
					)
				)
				(pin passive line
					(at 0 -50.8 0)
					(length 3.81)
					(hide yes)
					(name "GND"
						(effects
							(font
								(size 1.27 1.27)
							)
						)
					)
					(number "A28"
						(effects
							(font
								(size 1.27 1.27)
							)
						)
					)
				)
				(pin passive line
					(at 0 -50.8 0)
					(length 3.81)
					(hide yes)
					(name "GND"
						(effects
							(font
								(size 1.27 1.27)
							)
						)
					)
					(number "A29"
						(effects
							(font
								(size 1.27 1.27)
							)
						)
					)
				)
				(pin passive line
					(at 0 -50.8 0)
					(length 3.81)
					(hide yes)
					(name "GND"
						(effects
							(font
								(size 1.27 1.27)
							)
						)
					)
					(number "A32"
						(effects
							(font
								(size 1.27 1.27)
							)
						)
					)
				)
				(pin passive line
					(at 0 -50.8 0)
					(length 3.81)
					(hide yes)
					(name "GND"
						(effects
							(font
								(size 1.27 1.27)
							)
						)
					)
					(number "A33"
						(effects
							(font
								(size 1.27 1.27)
							)
						)
					)
				)
				(pin passive line
					(at 0 -50.8 0)
					(length 3.81)
					(hide yes)
					(name "GND"
						(effects
							(font
								(size 1.27 1.27)
							)
						)
					)
					(number "A36"
						(effects
							(font
								(size 1.27 1.27)
							)
						)
					)
				)
				(pin passive line
					(at 0 -50.8 0)
					(length 3.81)
					(hide yes)
					(name "GND"
						(effects
							(font
								(size 1.27 1.27)
							)
						)
					)
					(number "A37"
						(effects
							(font
								(size 1.27 1.27)
							)
						)
					)
				)
				(pin passive line
					(at 0 -50.8 0)
					(length 3.81)
					(hide yes)
					(name "GND"
						(effects
							(font
								(size 1.27 1.27)
							)
						)
					)
					(number "A40"
						(effects
							(font
								(size 1.27 1.27)
							)
						)
					)
				)
				(pin passive line
					(at 0 -50.8 0)
					(length 3.81)
					(hide yes)
					(name "GND"
						(effects
							(font
								(size 1.27 1.27)
							)
						)
					)
					(number "A43"
						(effects
							(font
								(size 1.27 1.27)
							)
						)
					)
				)
				(pin passive line
					(at 0 -50.8 0)
					(length 3.81)
					(hide yes)
					(name "GND"
						(effects
							(font
								(size 1.27 1.27)
							)
						)
					)
					(number "A46"
						(effects
							(font
								(size 1.27 1.27)
							)
						)
					)
				)
				(pin passive line
					(at 0 -50.8 0)
					(length 3.81)
					(hide yes)
					(name "GND"
						(effects
							(font
								(size 1.27 1.27)
							)
						)
					)
					(number "A49"
						(effects
							(font
								(size 1.27 1.27)
							)
						)
					)
				)
				(pin passive line
					(at 0 -50.8 0)
					(length 3.81)
					(hide yes)
					(name "GND"
						(effects
							(font
								(size 1.27 1.27)
							)
						)
					)
					(number "A52"
						(effects
							(font
								(size 1.27 1.27)
							)
						)
					)
				)
				(pin passive line
					(at 0 -50.8 0)
					(length 3.81)
					(hide yes)
					(name "GND"
						(effects
							(font
								(size 1.27 1.27)
							)
						)
					)
					(number "A63"
						(effects
							(font
								(size 1.27 1.27)
							)
						)
					)
				)
				(pin passive line
					(at 0 -50.8 0)
					(length 3.81)
					(hide yes)
					(name "GND"
						(effects
							(font
								(size 1.27 1.27)
							)
						)
					)
					(number "A9"
						(effects
							(font
								(size 1.27 1.27)
							)
						)
					)
				)
				(pin passive line
					(at 0 -50.8 0)
					(length 3.81)
					(hide yes)
					(name "GND"
						(effects
							(font
								(size 1.27 1.27)
							)
						)
					)
					(number "B11"
						(effects
							(font
								(size 1.27 1.27)
							)
						)
					)
				)
				(pin passive line
					(at 0 -50.8 0)
					(length 3.81)
					(hide yes)
					(name "GND"
						(effects
							(font
								(size 1.27 1.27)
							)
						)
					)
					(number "B14"
						(effects
							(font
								(size 1.27 1.27)
							)
						)
					)
				)
				(pin passive line
					(at 0 -50.8 0)
					(length 3.81)
					(hide yes)
					(name "GND"
						(effects
							(font
								(size 1.27 1.27)
							)
						)
					)
					(number "B15"
						(effects
							(font
								(size 1.27 1.27)
							)
						)
					)
				)
				(pin passive line
					(at 0 -50.8 0)
					(length 3.81)
					(hide yes)
					(name "GND"
						(effects
							(font
								(size 1.27 1.27)
							)
						)
					)
					(number "B18"
						(effects
							(font
								(size 1.27 1.27)
							)
						)
					)
				)
				(pin passive line
					(at 0 -50.8 0)
					(length 3.81)
					(hide yes)
					(name "GND"
						(effects
							(font
								(size 1.27 1.27)
							)
						)
					)
					(number "B19"
						(effects
							(font
								(size 1.27 1.27)
							)
						)
					)
				)
				(pin passive line
					(at 0 -50.8 0)
					(length 3.81)
					(hide yes)
					(name "GND"
						(effects
							(font
								(size 1.27 1.27)
							)
						)
					)
					(number "B22"
						(effects
							(font
								(size 1.27 1.27)
							)
						)
					)
				)
				(pin passive line
					(at 0 -50.8 0)
					(length 3.81)
					(hide yes)
					(name "GND"
						(effects
							(font
								(size 1.27 1.27)
							)
						)
					)
					(number "B23"
						(effects
							(font
								(size 1.27 1.27)
							)
						)
					)
				)
				(pin passive line
					(at 0 -50.8 0)
					(length 3.81)
					(hide yes)
					(name "GND"
						(effects
							(font
								(size 1.27 1.27)
							)
						)
					)
					(number "B26"
						(effects
							(font
								(size 1.27 1.27)
							)
						)
					)
				)
				(pin passive line
					(at 0 -50.8 0)
					(length 3.81)
					(hide yes)
					(name "GND"
						(effects
							(font
								(size 1.27 1.27)
							)
						)
					)
					(number "B27"
						(effects
							(font
								(size 1.27 1.27)
							)
						)
					)
				)
				(pin passive line
					(at 0 -50.8 0)
					(length 3.81)
					(hide yes)
					(name "GND"
						(effects
							(font
								(size 1.27 1.27)
							)
						)
					)
					(number "B30"
						(effects
							(font
								(size 1.27 1.27)
							)
						)
					)
				)
				(pin power_in line
					(at 0 -50.8 0)
					(length 3.81)
					(name "GND"
						(effects
							(font
								(size 1.27 1.27)
							)
						)
					)
					(number "B31"
						(effects
							(font
								(size 1.27 1.27)
							)
						)
					)
				)
				(pin passive line
					(at 0 -50.8 0)
					(length 3.81)
					(hide yes)
					(name "GND"
						(effects
							(font
								(size 1.27 1.27)
							)
						)
					)
					(number "B34"
						(effects
							(font
								(size 1.27 1.27)
							)
						)
					)
				)
				(pin passive line
					(at 0 -50.8 0)
					(length 3.81)
					(hide yes)
					(name "GND"
						(effects
							(font
								(size 1.27 1.27)
							)
						)
					)
					(number "B35"
						(effects
							(font
								(size 1.27 1.27)
							)
						)
					)
				)
				(pin passive line
					(at 0 -50.8 0)
					(length 3.81)
					(hide yes)
					(name "GND"
						(effects
							(font
								(size 1.27 1.27)
							)
						)
					)
					(number "B38"
						(effects
							(font
								(size 1.27 1.27)
							)
						)
					)
				)
				(pin passive line
					(at 0 -50.8 0)
					(length 3.81)
					(hide yes)
					(name "GND"
						(effects
							(font
								(size 1.27 1.27)
							)
						)
					)
					(number "B39"
						(effects
							(font
								(size 1.27 1.27)
							)
						)
					)
				)
				(pin passive line
					(at 0 -50.8 0)
					(length 3.81)
					(hide yes)
					(name "GND"
						(effects
							(font
								(size 1.27 1.27)
							)
						)
					)
					(number "B4"
						(effects
							(font
								(size 1.27 1.27)
							)
						)
					)
				)
				(pin passive line
					(at 0 -50.8 0)
					(length 3.81)
					(hide yes)
					(name "GND"
						(effects
							(font
								(size 1.27 1.27)
							)
						)
					)
					(number "B41"
						(effects
							(font
								(size 1.27 1.27)
							)
						)
					)
				)
				(pin passive line
					(at 0 -50.8 0)
					(length 3.81)
					(hide yes)
					(name "GND"
						(effects
							(font
								(size 1.27 1.27)
							)
						)
					)
					(number "B44"
						(effects
							(font
								(size 1.27 1.27)
							)
						)
					)
				)
				(pin passive line
					(at 0 -50.8 0)
					(length 3.81)
					(hide yes)
					(name "GND"
						(effects
							(font
								(size 1.27 1.27)
							)
						)
					)
					(number "B47"
						(effects
							(font
								(size 1.27 1.27)
							)
						)
					)
				)
				(pin passive line
					(at 0 -50.8 0)
					(length 3.81)
					(hide yes)
					(name "GND"
						(effects
							(font
								(size 1.27 1.27)
							)
						)
					)
					(number "B50"
						(effects
							(font
								(size 1.27 1.27)
							)
						)
					)
				)
				(pin passive line
					(at 0 -50.8 0)
					(length 3.81)
					(hide yes)
					(name "GND"
						(effects
							(font
								(size 1.27 1.27)
							)
						)
					)
					(number "B53"
						(effects
							(font
								(size 1.27 1.27)
							)
						)
					)
				)
				(pin passive line
					(at 0 -50.8 0)
					(length 3.81)
					(hide yes)
					(name "GND"
						(effects
							(font
								(size 1.27 1.27)
							)
						)
					)
					(number "B57"
						(effects
							(font
								(size 1.27 1.27)
							)
						)
					)
				)
				(pin passive line
					(at 0 -50.8 0)
					(length 3.81)
					(hide yes)
					(name "GND"
						(effects
							(font
								(size 1.27 1.27)
							)
						)
					)
					(number "B7"
						(effects
							(font
								(size 1.27 1.27)
							)
						)
					)
				)
				(pin passive line
					(at 0 -50.8 0)
					(length 3.81)
					(hide yes)
					(name "GND"
						(effects
							(font
								(size 1.27 1.27)
							)
						)
					)
					(number "C12"
						(effects
							(font
								(size 1.27 1.27)
							)
						)
					)
				)
				(pin passive line
					(at 0 -50.8 0)
					(length 3.81)
					(hide yes)
					(name "GND"
						(effects
							(font
								(size 1.27 1.27)
							)
						)
					)
					(number "C13"
						(effects
							(font
								(size 1.27 1.27)
							)
						)
					)
				)
				(pin passive line
					(at 0 -50.8 0)
					(length 3.81)
					(hide yes)
					(name "GND"
						(effects
							(font
								(size 1.27 1.27)
							)
						)
					)
					(number "C16"
						(effects
							(font
								(size 1.27 1.27)
							)
						)
					)
				)
				(pin passive line
					(at 0 -50.8 0)
					(length 3.81)
					(hide yes)
					(name "GND"
						(effects
							(font
								(size 1.27 1.27)
							)
						)
					)
					(number "C17"
						(effects
							(font
								(size 1.27 1.27)
							)
						)
					)
				)
				(pin passive line
					(at 0 -50.8 0)
					(length 3.81)
					(hide yes)
					(name "GND"
						(effects
							(font
								(size 1.27 1.27)
							)
						)
					)
					(number "C20"
						(effects
							(font
								(size 1.27 1.27)
							)
						)
					)
				)
				(pin passive line
					(at 0 -50.8 0)
					(length 3.81)
					(hide yes)
					(name "GND"
						(effects
							(font
								(size 1.27 1.27)
							)
						)
					)
					(number "C21"
						(effects
							(font
								(size 1.27 1.27)
							)
						)
					)
				)
				(pin passive line
					(at 0 -50.8 0)
					(length 3.81)
					(hide yes)
					(name "GND"
						(effects
							(font
								(size 1.27 1.27)
							)
						)
					)
					(number "C24"
						(effects
							(font
								(size 1.27 1.27)
							)
						)
					)
				)
				(pin passive line
					(at 0 -50.8 0)
					(length 3.81)
					(hide yes)
					(name "GND"
						(effects
							(font
								(size 1.27 1.27)
							)
						)
					)
					(number "C25"
						(effects
							(font
								(size 1.27 1.27)
							)
						)
					)
				)
				(pin passive line
					(at 0 -50.8 0)
					(length 3.81)
					(hide yes)
					(name "GND"
						(effects
							(font
								(size 1.27 1.27)
							)
						)
					)
					(number "C28"
						(effects
							(font
								(size 1.27 1.27)
							)
						)
					)
				)
				(pin passive line
					(at 0 -50.8 0)
					(length 3.81)
					(hide yes)
					(name "GND"
						(effects
							(font
								(size 1.27 1.27)
							)
						)
					)
					(number "C29"
						(effects
							(font
								(size 1.27 1.27)
							)
						)
					)
				)
				(pin passive line
					(at 0 -50.8 0)
					(length 3.81)
					(hide yes)
					(name "GND"
						(effects
							(font
								(size 1.27 1.27)
							)
						)
					)
					(number "C3"
						(effects
							(font
								(size 1.27 1.27)
							)
						)
					)
				)
				(pin passive line
					(at 0 -50.8 0)
					(length 3.81)
					(hide yes)
					(name "GND"
						(effects
							(font
								(size 1.27 1.27)
							)
						)
					)
					(number "C32"
						(effects
							(font
								(size 1.27 1.27)
							)
						)
					)
				)
				(pin passive line
					(at 0 -50.8 0)
					(length 3.81)
					(hide yes)
					(name "GND"
						(effects
							(font
								(size 1.27 1.27)
							)
						)
					)
					(number "C33"
						(effects
							(font
								(size 1.27 1.27)
							)
						)
					)
				)
				(pin passive line
					(at 0 -50.8 0)
					(length 3.81)
					(hide yes)
					(name "GND"
						(effects
							(font
								(size 1.27 1.27)
							)
						)
					)
					(number "C36"
						(effects
							(font
								(size 1.27 1.27)
							)
						)
					)
				)
				(pin passive line
					(at 0 -50.8 0)
					(length 3.81)
					(hide yes)
					(name "GND"
						(effects
							(font
								(size 1.27 1.27)
							)
						)
					)
					(number "C37"
						(effects
							(font
								(size 1.27 1.27)
							)
						)
					)
				)
				(pin passive line
					(at 0 -50.8 0)
					(length 3.81)
					(hide yes)
					(name "GND"
						(effects
							(font
								(size 1.27 1.27)
							)
						)
					)
					(number "C40"
						(effects
							(font
								(size 1.27 1.27)
							)
						)
					)
				)
				(pin passive line
					(at 0 -50.8 0)
					(length 3.81)
					(hide yes)
					(name "GND"
						(effects
							(font
								(size 1.27 1.27)
							)
						)
					)
					(number "C43"
						(effects
							(font
								(size 1.27 1.27)
							)
						)
					)
				)
				(pin passive line
					(at 0 -50.8 0)
					(length 3.81)
					(hide yes)
					(name "GND"
						(effects
							(font
								(size 1.27 1.27)
							)
						)
					)
					(number "C46"
						(effects
							(font
								(size 1.27 1.27)
							)
						)
					)
				)
				(pin passive line
					(at 0 -50.8 0)
					(length 3.81)
					(hide yes)
					(name "GND"
						(effects
							(font
								(size 1.27 1.27)
							)
						)
					)
					(number "C49"
						(effects
							(font
								(size 1.27 1.27)
							)
						)
					)
				)
				(pin passive line
					(at 0 -50.8 0)
					(length 3.81)
					(hide yes)
					(name "GND"
						(effects
							(font
								(size 1.27 1.27)
							)
						)
					)
					(number "C52"
						(effects
							(font
								(size 1.27 1.27)
							)
						)
					)
				)
				(pin passive line
					(at 0 -50.8 0)
					(length 3.81)
					(hide yes)
					(name "GND"
						(effects
							(font
								(size 1.27 1.27)
							)
						)
					)
					(number "C62"
						(effects
							(font
								(size 1.27 1.27)
							)
						)
					)
				)
				(pin passive line
					(at 0 -50.8 0)
					(length 3.81)
					(hide yes)
					(name "GND"
						(effects
							(font
								(size 1.27 1.27)
							)
						)
					)
					(number "C9"
						(effects
							(font
								(size 1.27 1.27)
							)
						)
					)
				)
				(pin passive line
					(at 0 -50.8 0)
					(length 3.81)
					(hide yes)
					(name "GND"
						(effects
							(font
								(size 1.27 1.27)
							)
						)
					)
					(number "D11"
						(effects
							(font
								(size 1.27 1.27)
							)
						)
					)
				)
				(pin passive line
					(at 0 -50.8 0)
					(length 3.81)
					(hide yes)
					(name "GND"
						(effects
							(font
								(size 1.27 1.27)
							)
						)
					)
					(number "D14"
						(effects
							(font
								(size 1.27 1.27)
							)
						)
					)
				)
				(pin passive line
					(at 0 -50.8 0)
					(length 3.81)
					(hide yes)
					(name "GND"
						(effects
							(font
								(size 1.27 1.27)
							)
						)
					)
					(number "D15"
						(effects
							(font
								(size 1.27 1.27)
							)
						)
					)
				)
				(pin passive line
					(at 0 -50.8 0)
					(length 3.81)
					(hide yes)
					(name "GND"
						(effects
							(font
								(size 1.27 1.27)
							)
						)
					)
					(number "D18"
						(effects
							(font
								(size 1.27 1.27)
							)
						)
					)
				)
				(pin passive line
					(at 0 -50.8 0)
					(length 3.81)
					(hide yes)
					(name "GND"
						(effects
							(font
								(size 1.27 1.27)
							)
						)
					)
					(number "D19"
						(effects
							(font
								(size 1.27 1.27)
							)
						)
					)
				)
				(pin passive line
					(at 0 -50.8 0)
					(length 3.81)
					(hide yes)
					(name "GND"
						(effects
							(font
								(size 1.27 1.27)
							)
						)
					)
					(number "D22"
						(effects
							(font
								(size 1.27 1.27)
							)
						)
					)
				)
				(pin passive line
					(at 0 -50.8 0)
					(length 3.81)
					(hide yes)
					(name "GND"
						(effects
							(font
								(size 1.27 1.27)
							)
						)
					)
					(number "D23"
						(effects
							(font
								(size 1.27 1.27)
							)
						)
					)
				)
				(pin passive line
					(at 0 -50.8 0)
					(length 3.81)
					(hide yes)
					(name "GND"
						(effects
							(font
								(size 1.27 1.27)
							)
						)
					)
					(number "D26"
						(effects
							(font
								(size 1.27 1.27)
							)
						)
					)
				)
				(pin passive line
					(at 0 -50.8 0)
					(length 3.81)
					(hide yes)
					(name "GND"
						(effects
							(font
								(size 1.27 1.27)
							)
						)
					)
					(number "D27"
						(effects
							(font
								(size 1.27 1.27)
							)
						)
					)
				)
				(pin passive line
					(at 0 -50.8 0)
					(length 3.81)
					(hide yes)
					(name "GND"
						(effects
							(font
								(size 1.27 1.27)
							)
						)
					)
					(number "D30"
						(effects
							(font
								(size 1.27 1.27)
							)
						)
					)
				)
				(pin passive line
					(at 0 -50.8 0)
					(length 3.81)
					(hide yes)
					(name "GND"
						(effects
							(font
								(size 1.27 1.27)
							)
						)
					)
					(number "D31"
						(effects
							(font
								(size 1.27 1.27)
							)
						)
					)
				)
				(pin passive line
					(at 0 -50.8 0)
					(length 3.81)
					(hide yes)
					(name "GND"
						(effects
							(font
								(size 1.27 1.27)
							)
						)
					)
					(number "D34"
						(effects
							(font
								(size 1.27 1.27)
							)
						)
					)
				)
				(pin passive line
					(at 0 -50.8 0)
					(length 3.81)
					(hide yes)
					(name "GND"
						(effects
							(font
								(size 1.27 1.27)
							)
						)
					)
					(number "D35"
						(effects
							(font
								(size 1.27 1.27)
							)
						)
					)
				)
				(pin passive line
					(at 0 -50.8 0)
					(length 3.81)
					(hide yes)
					(name "GND"
						(effects
							(font
								(size 1.27 1.27)
							)
						)
					)
					(number "D38"
						(effects
							(font
								(size 1.27 1.27)
							)
						)
					)
				)
				(pin passive line
					(at 0 -50.8 0)
					(length 3.81)
					(hide yes)
					(name "GND"
						(effects
							(font
								(size 1.27 1.27)
							)
						)
					)
					(number "D39"
						(effects
							(font
								(size 1.27 1.27)
							)
						)
					)
				)
				(pin passive line
					(at 0 -50.8 0)
					(length 3.81)
					(hide yes)
					(name "GND"
						(effects
							(font
								(size 1.27 1.27)
							)
						)
					)
					(number "D4"
						(effects
							(font
								(size 1.27 1.27)
							)
						)
					)
				)
				(pin passive line
					(at 0 -50.8 0)
					(length 3.81)
					(hide yes)
					(name "GND"
						(effects
							(font
								(size 1.27 1.27)
							)
						)
					)
					(number "D41"
						(effects
							(font
								(size 1.27 1.27)
							)
						)
					)
				)
				(pin passive line
					(at 0 -50.8 0)
					(length 3.81)
					(hide yes)
					(name "GND"
						(effects
							(font
								(size 1.27 1.27)
							)
						)
					)
					(number "D44"
						(effects
							(font
								(size 1.27 1.27)
							)
						)
					)
				)
				(pin passive line
					(at 0 -50.8 0)
					(length 3.81)
					(hide yes)
					(name "GND"
						(effects
							(font
								(size 1.27 1.27)
							)
						)
					)
					(number "D47"
						(effects
							(font
								(size 1.27 1.27)
							)
						)
					)
				)
				(pin passive line
					(at 0 -50.8 0)
					(length 3.81)
					(hide yes)
					(name "GND"
						(effects
							(font
								(size 1.27 1.27)
							)
						)
					)
					(number "D50"
						(effects
							(font
								(size 1.27 1.27)
							)
						)
					)
				)
				(pin passive line
					(at 0 -50.8 0)
					(length 3.81)
					(hide yes)
					(name "GND"
						(effects
							(font
								(size 1.27 1.27)
							)
						)
					)
					(number "D53"
						(effects
							(font
								(size 1.27 1.27)
							)
						)
					)
				)
				(pin passive line
					(at 0 -50.8 0)
					(length 3.81)
					(hide yes)
					(name "GND"
						(effects
							(font
								(size 1.27 1.27)
							)
						)
					)
					(number "D57"
						(effects
							(font
								(size 1.27 1.27)
							)
						)
					)
				)
				(pin passive line
					(at 0 -50.8 0)
					(length 3.81)
					(hide yes)
					(name "GND"
						(effects
							(font
								(size 1.27 1.27)
							)
						)
					)
					(number "D63"
						(effects
							(font
								(size 1.27 1.27)
							)
						)
					)
				)
				(pin passive line
					(at 0 -50.8 0)
					(length 3.81)
					(hide yes)
					(name "GND"
						(effects
							(font
								(size 1.27 1.27)
							)
						)
					)
					(number "D7"
						(effects
							(font
								(size 1.27 1.27)
							)
						)
					)
				)
				(pin passive line
					(at 0 -50.8 0)
					(length 3.81)
					(hide yes)
					(name "GND"
						(effects
							(font
								(size 1.27 1.27)
							)
						)
					)
					(number "E12"
						(effects
							(font
								(size 1.27 1.27)
							)
						)
					)
				)
				(pin passive line
					(at 0 -50.8 0)
					(length 3.81)
					(hide yes)
					(name "GND"
						(effects
							(font
								(size 1.27 1.27)
							)
						)
					)
					(number "E13"
						(effects
							(font
								(size 1.27 1.27)
							)
						)
					)
				)
				(pin passive line
					(at 0 -50.8 0)
					(length 3.81)
					(hide yes)
					(name "GND"
						(effects
							(font
								(size 1.27 1.27)
							)
						)
					)
					(number "E16"
						(effects
							(font
								(size 1.27 1.27)
							)
						)
					)
				)
				(pin passive line
					(at 0 -50.8 0)
					(length 3.81)
					(hide yes)
					(name "GND"
						(effects
							(font
								(size 1.27 1.27)
							)
						)
					)
					(number "E17"
						(effects
							(font
								(size 1.27 1.27)
							)
						)
					)
				)
				(pin passive line
					(at 0 -50.8 0)
					(length 3.81)
					(hide yes)
					(name "GND"
						(effects
							(font
								(size 1.27 1.27)
							)
						)
					)
					(number "E20"
						(effects
							(font
								(size 1.27 1.27)
							)
						)
					)
				)
				(pin passive line
					(at 0 -50.8 0)
					(length 3.81)
					(hide yes)
					(name "GND"
						(effects
							(font
								(size 1.27 1.27)
							)
						)
					)
					(number "E21"
						(effects
							(font
								(size 1.27 1.27)
							)
						)
					)
				)
				(pin passive line
					(at 0 -50.8 0)
					(length 3.81)
					(hide yes)
					(name "GND"
						(effects
							(font
								(size 1.27 1.27)
							)
						)
					)
					(number "E24"
						(effects
							(font
								(size 1.27 1.27)
							)
						)
					)
				)
				(pin passive line
					(at 0 -50.8 0)
					(length 3.81)
					(hide yes)
					(name "GND"
						(effects
							(font
								(size 1.27 1.27)
							)
						)
					)
					(number "E25"
						(effects
							(font
								(size 1.27 1.27)
							)
						)
					)
				)
				(pin passive line
					(at 0 -50.8 0)
					(length 3.81)
					(hide yes)
					(name "GND"
						(effects
							(font
								(size 1.27 1.27)
							)
						)
					)
					(number "E28"
						(effects
							(font
								(size 1.27 1.27)
							)
						)
					)
				)
				(pin passive line
					(at 0 -50.8 0)
					(length 3.81)
					(hide yes)
					(name "GND"
						(effects
							(font
								(size 1.27 1.27)
							)
						)
					)
					(number "E29"
						(effects
							(font
								(size 1.27 1.27)
							)
						)
					)
				)
				(pin passive line
					(at 0 -50.8 0)
					(length 3.81)
					(hide yes)
					(name "GND"
						(effects
							(font
								(size 1.27 1.27)
							)
						)
					)
					(number "E3"
						(effects
							(font
								(size 1.27 1.27)
							)
						)
					)
				)
				(pin passive line
					(at 0 -50.8 0)
					(length 3.81)
					(hide yes)
					(name "GND"
						(effects
							(font
								(size 1.27 1.27)
							)
						)
					)
					(number "E32"
						(effects
							(font
								(size 1.27 1.27)
							)
						)
					)
				)
				(pin passive line
					(at 0 -50.8 0)
					(length 3.81)
					(hide yes)
					(name "GND"
						(effects
							(font
								(size 1.27 1.27)
							)
						)
					)
					(number "E33"
						(effects
							(font
								(size 1.27 1.27)
							)
						)
					)
				)
				(pin passive line
					(at 0 -50.8 0)
					(length 3.81)
					(hide yes)
					(name "GND"
						(effects
							(font
								(size 1.27 1.27)
							)
						)
					)
					(number "E36"
						(effects
							(font
								(size 1.27 1.27)
							)
						)
					)
				)
				(pin passive line
					(at 0 -50.8 0)
					(length 3.81)
					(hide yes)
					(name "GND"
						(effects
							(font
								(size 1.27 1.27)
							)
						)
					)
					(number "E37"
						(effects
							(font
								(size 1.27 1.27)
							)
						)
					)
				)
				(pin passive line
					(at 0 -50.8 0)
					(length 3.81)
					(hide yes)
					(name "GND"
						(effects
							(font
								(size 1.27 1.27)
							)
						)
					)
					(number "E40"
						(effects
							(font
								(size 1.27 1.27)
							)
						)
					)
				)
				(pin passive line
					(at 0 -50.8 0)
					(length 3.81)
					(hide yes)
					(name "GND"
						(effects
							(font
								(size 1.27 1.27)
							)
						)
					)
					(number "E43"
						(effects
							(font
								(size 1.27 1.27)
							)
						)
					)
				)
				(pin passive line
					(at 0 -50.8 0)
					(length 3.81)
					(hide yes)
					(name "GND"
						(effects
							(font
								(size 1.27 1.27)
							)
						)
					)
					(number "E46"
						(effects
							(font
								(size 1.27 1.27)
							)
						)
					)
				)
				(pin passive line
					(at 0 -50.8 0)
					(length 3.81)
					(hide yes)
					(name "GND"
						(effects
							(font
								(size 1.27 1.27)
							)
						)
					)
					(number "E49"
						(effects
							(font
								(size 1.27 1.27)
							)
						)
					)
				)
				(pin passive line
					(at 0 -50.8 0)
					(length 3.81)
					(hide yes)
					(name "GND"
						(effects
							(font
								(size 1.27 1.27)
							)
						)
					)
					(number "E52"
						(effects
							(font
								(size 1.27 1.27)
							)
						)
					)
				)
				(pin passive line
					(at 0 -50.8 0)
					(length 3.81)
					(hide yes)
					(name "GND"
						(effects
							(font
								(size 1.27 1.27)
							)
						)
					)
					(number "E57"
						(effects
							(font
								(size 1.27 1.27)
							)
						)
					)
				)
				(pin passive line
					(at 0 -50.8 0)
					(length 3.81)
					(hide yes)
					(name "GND"
						(effects
							(font
								(size 1.27 1.27)
							)
						)
					)
					(number "E62"
						(effects
							(font
								(size 1.27 1.27)
							)
						)
					)
				)
				(pin passive line
					(at 0 -50.8 0)
					(length 3.81)
					(hide yes)
					(name "GND"
						(effects
							(font
								(size 1.27 1.27)
							)
						)
					)
					(number "E9"
						(effects
							(font
								(size 1.27 1.27)
							)
						)
					)
				)
				(pin passive line
					(at 0 -50.8 0)
					(length 3.81)
					(hide yes)
					(name "GND"
						(effects
							(font
								(size 1.27 1.27)
							)
						)
					)
					(number "F11"
						(effects
							(font
								(size 1.27 1.27)
							)
						)
					)
				)
				(pin passive line
					(at 0 -50.8 0)
					(length 3.81)
					(hide yes)
					(name "GND"
						(effects
							(font
								(size 1.27 1.27)
							)
						)
					)
					(number "F14"
						(effects
							(font
								(size 1.27 1.27)
							)
						)
					)
				)
				(pin passive line
					(at 0 -50.8 0)
					(length 3.81)
					(hide yes)
					(name "GND"
						(effects
							(font
								(size 1.27 1.27)
							)
						)
					)
					(number "F15"
						(effects
							(font
								(size 1.27 1.27)
							)
						)
					)
				)
				(pin passive line
					(at 0 -50.8 0)
					(length 3.81)
					(hide yes)
					(name "GND"
						(effects
							(font
								(size 1.27 1.27)
							)
						)
					)
					(number "F18"
						(effects
							(font
								(size 1.27 1.27)
							)
						)
					)
				)
				(pin passive line
					(at 0 -50.8 0)
					(length 3.81)
					(hide yes)
					(name "GND"
						(effects
							(font
								(size 1.27 1.27)
							)
						)
					)
					(number "F19"
						(effects
							(font
								(size 1.27 1.27)
							)
						)
					)
				)
				(pin passive line
					(at 0 -50.8 0)
					(length 3.81)
					(hide yes)
					(name "GND"
						(effects
							(font
								(size 1.27 1.27)
							)
						)
					)
					(number "F22"
						(effects
							(font
								(size 1.27 1.27)
							)
						)
					)
				)
				(pin passive line
					(at 0 -50.8 0)
					(length 3.81)
					(hide yes)
					(name "GND"
						(effects
							(font
								(size 1.27 1.27)
							)
						)
					)
					(number "F23"
						(effects
							(font
								(size 1.27 1.27)
							)
						)
					)
				)
				(pin passive line
					(at 0 -50.8 0)
					(length 3.81)
					(hide yes)
					(name "GND"
						(effects
							(font
								(size 1.27 1.27)
							)
						)
					)
					(number "F26"
						(effects
							(font
								(size 1.27 1.27)
							)
						)
					)
				)
				(pin passive line
					(at 0 -50.8 0)
					(length 3.81)
					(hide yes)
					(name "GND"
						(effects
							(font
								(size 1.27 1.27)
							)
						)
					)
					(number "F27"
						(effects
							(font
								(size 1.27 1.27)
							)
						)
					)
				)
				(pin passive line
					(at 0 -50.8 0)
					(length 3.81)
					(hide yes)
					(name "GND"
						(effects
							(font
								(size 1.27 1.27)
							)
						)
					)
					(number "F30"
						(effects
							(font
								(size 1.27 1.27)
							)
						)
					)
				)
				(pin passive line
					(at 0 -50.8 0)
					(length 3.81)
					(hide yes)
					(name "GND"
						(effects
							(font
								(size 1.27 1.27)
							)
						)
					)
					(number "F31"
						(effects
							(font
								(size 1.27 1.27)
							)
						)
					)
				)
				(pin passive line
					(at 0 -50.8 0)
					(length 3.81)
					(hide yes)
					(name "GND"
						(effects
							(font
								(size 1.27 1.27)
							)
						)
					)
					(number "F34"
						(effects
							(font
								(size 1.27 1.27)
							)
						)
					)
				)
				(pin passive line
					(at 0 -50.8 0)
					(length 3.81)
					(hide yes)
					(name "GND"
						(effects
							(font
								(size 1.27 1.27)
							)
						)
					)
					(number "F35"
						(effects
							(font
								(size 1.27 1.27)
							)
						)
					)
				)
				(pin passive line
					(at 0 -50.8 0)
					(length 3.81)
					(hide yes)
					(name "GND"
						(effects
							(font
								(size 1.27 1.27)
							)
						)
					)
					(number "F38"
						(effects
							(font
								(size 1.27 1.27)
							)
						)
					)
				)
				(pin passive line
					(at 0 -50.8 0)
					(length 3.81)
					(hide yes)
					(name "GND"
						(effects
							(font
								(size 1.27 1.27)
							)
						)
					)
					(number "F39"
						(effects
							(font
								(size 1.27 1.27)
							)
						)
					)
				)
				(pin passive line
					(at 0 -50.8 0)
					(length 3.81)
					(hide yes)
					(name "GND"
						(effects
							(font
								(size 1.27 1.27)
							)
						)
					)
					(number "F4"
						(effects
							(font
								(size 1.27 1.27)
							)
						)
					)
				)
				(pin passive line
					(at 0 -50.8 0)
					(length 3.81)
					(hide yes)
					(name "GND"
						(effects
							(font
								(size 1.27 1.27)
							)
						)
					)
					(number "F41"
						(effects
							(font
								(size 1.27 1.27)
							)
						)
					)
				)
				(pin passive line
					(at 0 -50.8 0)
					(length 3.81)
					(hide yes)
					(name "GND"
						(effects
							(font
								(size 1.27 1.27)
							)
						)
					)
					(number "F44"
						(effects
							(font
								(size 1.27 1.27)
							)
						)
					)
				)
				(pin passive line
					(at 0 -50.8 0)
					(length 3.81)
					(hide yes)
					(name "GND"
						(effects
							(font
								(size 1.27 1.27)
							)
						)
					)
					(number "F47"
						(effects
							(font
								(size 1.27 1.27)
							)
						)
					)
				)
				(pin passive line
					(at 0 -50.8 0)
					(length 3.81)
					(hide yes)
					(name "GND"
						(effects
							(font
								(size 1.27 1.27)
							)
						)
					)
					(number "F50"
						(effects
							(font
								(size 1.27 1.27)
							)
						)
					)
				)
				(pin passive line
					(at 0 -50.8 0)
					(length 3.81)
					(hide yes)
					(name "GND"
						(effects
							(font
								(size 1.27 1.27)
							)
						)
					)
					(number "F57"
						(effects
							(font
								(size 1.27 1.27)
							)
						)
					)
				)
				(pin passive line
					(at 0 -50.8 0)
					(length 3.81)
					(hide yes)
					(name "GND"
						(effects
							(font
								(size 1.27 1.27)
							)
						)
					)
					(number "F62"
						(effects
							(font
								(size 1.27 1.27)
							)
						)
					)
				)
				(pin passive line
					(at 0 -50.8 0)
					(length 3.81)
					(hide yes)
					(name "GND"
						(effects
							(font
								(size 1.27 1.27)
							)
						)
					)
					(number "F7"
						(effects
							(font
								(size 1.27 1.27)
							)
						)
					)
				)
				(pin passive line
					(at 0 -50.8 0)
					(length 3.81)
					(hide yes)
					(name "GND"
						(effects
							(font
								(size 1.27 1.27)
							)
						)
					)
					(number "G12"
						(effects
							(font
								(size 1.27 1.27)
							)
						)
					)
				)
				(pin passive line
					(at 0 -50.8 0)
					(length 3.81)
					(hide yes)
					(name "GND"
						(effects
							(font
								(size 1.27 1.27)
							)
						)
					)
					(number "G13"
						(effects
							(font
								(size 1.27 1.27)
							)
						)
					)
				)
				(pin passive line
					(at 0 -50.8 0)
					(length 3.81)
					(hide yes)
					(name "GND"
						(effects
							(font
								(size 1.27 1.27)
							)
						)
					)
					(number "G16"
						(effects
							(font
								(size 1.27 1.27)
							)
						)
					)
				)
				(pin passive line
					(at 0 -50.8 0)
					(length 3.81)
					(hide yes)
					(name "GND"
						(effects
							(font
								(size 1.27 1.27)
							)
						)
					)
					(number "G17"
						(effects
							(font
								(size 1.27 1.27)
							)
						)
					)
				)
				(pin passive line
					(at 0 -50.8 0)
					(length 3.81)
					(hide yes)
					(name "GND"
						(effects
							(font
								(size 1.27 1.27)
							)
						)
					)
					(number "G20"
						(effects
							(font
								(size 1.27 1.27)
							)
						)
					)
				)
				(pin passive line
					(at 0 -50.8 0)
					(length 3.81)
					(hide yes)
					(name "GND"
						(effects
							(font
								(size 1.27 1.27)
							)
						)
					)
					(number "G21"
						(effects
							(font
								(size 1.27 1.27)
							)
						)
					)
				)
				(pin passive line
					(at 0 -50.8 0)
					(length 3.81)
					(hide yes)
					(name "GND"
						(effects
							(font
								(size 1.27 1.27)
							)
						)
					)
					(number "G24"
						(effects
							(font
								(size 1.27 1.27)
							)
						)
					)
				)
				(pin passive line
					(at 0 -50.8 0)
					(length 3.81)
					(hide yes)
					(name "GND"
						(effects
							(font
								(size 1.27 1.27)
							)
						)
					)
					(number "G25"
						(effects
							(font
								(size 1.27 1.27)
							)
						)
					)
				)
				(pin passive line
					(at 0 -50.8 0)
					(length 3.81)
					(hide yes)
					(name "GND"
						(effects
							(font
								(size 1.27 1.27)
							)
						)
					)
					(number "G28"
						(effects
							(font
								(size 1.27 1.27)
							)
						)
					)
				)
				(pin passive line
					(at 0 -50.8 0)
					(length 3.81)
					(hide yes)
					(name "GND"
						(effects
							(font
								(size 1.27 1.27)
							)
						)
					)
					(number "G29"
						(effects
							(font
								(size 1.27 1.27)
							)
						)
					)
				)
				(pin passive line
					(at 0 -50.8 0)
					(length 3.81)
					(hide yes)
					(name "GND"
						(effects
							(font
								(size 1.27 1.27)
							)
						)
					)
					(number "G3"
						(effects
							(font
								(size 1.27 1.27)
							)
						)
					)
				)
				(pin passive line
					(at 0 -50.8 0)
					(length 3.81)
					(hide yes)
					(name "GND"
						(effects
							(font
								(size 1.27 1.27)
							)
						)
					)
					(number "G32"
						(effects
							(font
								(size 1.27 1.27)
							)
						)
					)
				)
				(pin passive line
					(at 0 -50.8 0)
					(length 3.81)
					(hide yes)
					(name "GND"
						(effects
							(font
								(size 1.27 1.27)
							)
						)
					)
					(number "G33"
						(effects
							(font
								(size 1.27 1.27)
							)
						)
					)
				)
				(pin passive line
					(at 0 -50.8 0)
					(length 3.81)
					(hide yes)
					(name "GND"
						(effects
							(font
								(size 1.27 1.27)
							)
						)
					)
					(number "G36"
						(effects
							(font
								(size 1.27 1.27)
							)
						)
					)
				)
				(pin passive line
					(at 0 -50.8 0)
					(length 3.81)
					(hide yes)
					(name "GND"
						(effects
							(font
								(size 1.27 1.27)
							)
						)
					)
					(number "G37"
						(effects
							(font
								(size 1.27 1.27)
							)
						)
					)
				)
				(pin passive line
					(at 0 -50.8 0)
					(length 3.81)
					(hide yes)
					(name "GND"
						(effects
							(font
								(size 1.27 1.27)
							)
						)
					)
					(number "G40"
						(effects
							(font
								(size 1.27 1.27)
							)
						)
					)
				)
				(pin passive line
					(at 0 -50.8 0)
					(length 3.81)
					(hide yes)
					(name "GND"
						(effects
							(font
								(size 1.27 1.27)
							)
						)
					)
					(number "G43"
						(effects
							(font
								(size 1.27 1.27)
							)
						)
					)
				)
				(pin passive line
					(at 0 -50.8 0)
					(length 3.81)
					(hide yes)
					(name "GND"
						(effects
							(font
								(size 1.27 1.27)
							)
						)
					)
					(number "G46"
						(effects
							(font
								(size 1.27 1.27)
							)
						)
					)
				)
				(pin passive line
					(at 0 -50.8 0)
					(length 3.81)
					(hide yes)
					(name "GND"
						(effects
							(font
								(size 1.27 1.27)
							)
						)
					)
					(number "G49"
						(effects
							(font
								(size 1.27 1.27)
							)
						)
					)
				)
				(pin passive line
					(at 0 -50.8 0)
					(length 3.81)
					(hide yes)
					(name "GND"
						(effects
							(font
								(size 1.27 1.27)
							)
						)
					)
					(number "G52"
						(effects
							(font
								(size 1.27 1.27)
							)
						)
					)
				)
				(pin passive line
					(at 0 -50.8 0)
					(length 3.81)
					(hide yes)
					(name "GND"
						(effects
							(font
								(size 1.27 1.27)
							)
						)
					)
					(number "G57"
						(effects
							(font
								(size 1.27 1.27)
							)
						)
					)
				)
				(pin passive line
					(at 0 -50.8 0)
					(length 3.81)
					(hide yes)
					(name "GND"
						(effects
							(font
								(size 1.27 1.27)
							)
						)
					)
					(number "G62"
						(effects
							(font
								(size 1.27 1.27)
							)
						)
					)
				)
				(pin passive line
					(at 0 -50.8 0)
					(length 3.81)
					(hide yes)
					(name "GND"
						(effects
							(font
								(size 1.27 1.27)
							)
						)
					)
					(number "G9"
						(effects
							(font
								(size 1.27 1.27)
							)
						)
					)
				)
				(pin passive line
					(at 0 -50.8 0)
					(length 3.81)
					(hide yes)
					(name "GND"
						(effects
							(font
								(size 1.27 1.27)
							)
						)
					)
					(number "H11"
						(effects
							(font
								(size 1.27 1.27)
							)
						)
					)
				)
				(pin passive line
					(at 0 -50.8 0)
					(length 3.81)
					(hide yes)
					(name "GND"
						(effects
							(font
								(size 1.27 1.27)
							)
						)
					)
					(number "H14"
						(effects
							(font
								(size 1.27 1.27)
							)
						)
					)
				)
				(pin passive line
					(at 0 -50.8 0)
					(length 3.81)
					(hide yes)
					(name "GND"
						(effects
							(font
								(size 1.27 1.27)
							)
						)
					)
					(number "H15"
						(effects
							(font
								(size 1.27 1.27)
							)
						)
					)
				)
				(pin passive line
					(at 0 -50.8 0)
					(length 3.81)
					(hide yes)
					(name "GND"
						(effects
							(font
								(size 1.27 1.27)
							)
						)
					)
					(number "H18"
						(effects
							(font
								(size 1.27 1.27)
							)
						)
					)
				)
				(pin passive line
					(at 0 -50.8 0)
					(length 3.81)
					(hide yes)
					(name "GND"
						(effects
							(font
								(size 1.27 1.27)
							)
						)
					)
					(number "H19"
						(effects
							(font
								(size 1.27 1.27)
							)
						)
					)
				)
				(pin passive line
					(at 0 -50.8 0)
					(length 3.81)
					(hide yes)
					(name "GND"
						(effects
							(font
								(size 1.27 1.27)
							)
						)
					)
					(number "H22"
						(effects
							(font
								(size 1.27 1.27)
							)
						)
					)
				)
				(pin passive line
					(at 0 -50.8 0)
					(length 3.81)
					(hide yes)
					(name "GND"
						(effects
							(font
								(size 1.27 1.27)
							)
						)
					)
					(number "H23"
						(effects
							(font
								(size 1.27 1.27)
							)
						)
					)
				)
				(pin passive line
					(at 0 -50.8 0)
					(length 3.81)
					(hide yes)
					(name "GND"
						(effects
							(font
								(size 1.27 1.27)
							)
						)
					)
					(number "H26"
						(effects
							(font
								(size 1.27 1.27)
							)
						)
					)
				)
				(pin passive line
					(at 0 -50.8 0)
					(length 3.81)
					(hide yes)
					(name "GND"
						(effects
							(font
								(size 1.27 1.27)
							)
						)
					)
					(number "H27"
						(effects
							(font
								(size 1.27 1.27)
							)
						)
					)
				)
				(pin passive line
					(at 0 -50.8 0)
					(length 3.81)
					(hide yes)
					(name "GND"
						(effects
							(font
								(size 1.27 1.27)
							)
						)
					)
					(number "H30"
						(effects
							(font
								(size 1.27 1.27)
							)
						)
					)
				)
				(pin passive line
					(at 0 -50.8 0)
					(length 3.81)
					(hide yes)
					(name "GND"
						(effects
							(font
								(size 1.27 1.27)
							)
						)
					)
					(number "H31"
						(effects
							(font
								(size 1.27 1.27)
							)
						)
					)
				)
				(pin passive line
					(at 0 -50.8 0)
					(length 3.81)
					(hide yes)
					(name "GND"
						(effects
							(font
								(size 1.27 1.27)
							)
						)
					)
					(number "H34"
						(effects
							(font
								(size 1.27 1.27)
							)
						)
					)
				)
				(pin passive line
					(at 0 -50.8 0)
					(length 3.81)
					(hide yes)
					(name "GND"
						(effects
							(font
								(size 1.27 1.27)
							)
						)
					)
					(number "H35"
						(effects
							(font
								(size 1.27 1.27)
							)
						)
					)
				)
				(pin passive line
					(at 0 -50.8 0)
					(length 3.81)
					(hide yes)
					(name "GND"
						(effects
							(font
								(size 1.27 1.27)
							)
						)
					)
					(number "H38"
						(effects
							(font
								(size 1.27 1.27)
							)
						)
					)
				)
				(pin passive line
					(at 0 -50.8 0)
					(length 3.81)
					(hide yes)
					(name "GND"
						(effects
							(font
								(size 1.27 1.27)
							)
						)
					)
					(number "H39"
						(effects
							(font
								(size 1.27 1.27)
							)
						)
					)
				)
				(pin passive line
					(at 0 -50.8 0)
					(length 3.81)
					(hide yes)
					(name "GND"
						(effects
							(font
								(size 1.27 1.27)
							)
						)
					)
					(number "H4"
						(effects
							(font
								(size 1.27 1.27)
							)
						)
					)
				)
				(pin passive line
					(at 0 -50.8 0)
					(length 3.81)
					(hide yes)
					(name "GND"
						(effects
							(font
								(size 1.27 1.27)
							)
						)
					)
					(number "H41"
						(effects
							(font
								(size 1.27 1.27)
							)
						)
					)
				)
				(pin passive line
					(at 0 -50.8 0)
					(length 3.81)
					(hide yes)
					(name "GND"
						(effects
							(font
								(size 1.27 1.27)
							)
						)
					)
					(number "H44"
						(effects
							(font
								(size 1.27 1.27)
							)
						)
					)
				)
				(pin passive line
					(at 0 -50.8 0)
					(length 3.81)
					(hide yes)
					(name "GND"
						(effects
							(font
								(size 1.27 1.27)
							)
						)
					)
					(number "H47"
						(effects
							(font
								(size 1.27 1.27)
							)
						)
					)
				)
				(pin passive line
					(at 0 -50.8 0)
					(length 3.81)
					(hide yes)
					(name "GND"
						(effects
							(font
								(size 1.27 1.27)
							)
						)
					)
					(number "H50"
						(effects
							(font
								(size 1.27 1.27)
							)
						)
					)
				)
				(pin passive line
					(at 0 -50.8 0)
					(length 3.81)
					(hide yes)
					(name "GND"
						(effects
							(font
								(size 1.27 1.27)
							)
						)
					)
					(number "H56"
						(effects
							(font
								(size 1.27 1.27)
							)
						)
					)
				)
				(pin passive line
					(at 0 -50.8 0)
					(length 3.81)
					(hide yes)
					(name "GND"
						(effects
							(font
								(size 1.27 1.27)
							)
						)
					)
					(number "H63"
						(effects
							(font
								(size 1.27 1.27)
							)
						)
					)
				)
				(pin passive line
					(at 0 -50.8 0)
					(length 3.81)
					(hide yes)
					(name "GND"
						(effects
							(font
								(size 1.27 1.27)
							)
						)
					)
					(number "H7"
						(effects
							(font
								(size 1.27 1.27)
							)
						)
					)
				)
				(pin passive line
					(at 0 -50.8 0)
					(length 3.81)
					(hide yes)
					(name "GND"
						(effects
							(font
								(size 1.27 1.27)
							)
						)
					)
					(number "J12"
						(effects
							(font
								(size 1.27 1.27)
							)
						)
					)
				)
				(pin passive line
					(at 0 -50.8 0)
					(length 3.81)
					(hide yes)
					(name "GND"
						(effects
							(font
								(size 1.27 1.27)
							)
						)
					)
					(number "J13"
						(effects
							(font
								(size 1.27 1.27)
							)
						)
					)
				)
				(pin passive line
					(at 0 -50.8 0)
					(length 3.81)
					(hide yes)
					(name "GND"
						(effects
							(font
								(size 1.27 1.27)
							)
						)
					)
					(number "J16"
						(effects
							(font
								(size 1.27 1.27)
							)
						)
					)
				)
				(pin passive line
					(at 0 -50.8 0)
					(length 3.81)
					(hide yes)
					(name "GND"
						(effects
							(font
								(size 1.27 1.27)
							)
						)
					)
					(number "J17"
						(effects
							(font
								(size 1.27 1.27)
							)
						)
					)
				)
				(pin passive line
					(at 0 -50.8 0)
					(length 3.81)
					(hide yes)
					(name "GND"
						(effects
							(font
								(size 1.27 1.27)
							)
						)
					)
					(number "J20"
						(effects
							(font
								(size 1.27 1.27)
							)
						)
					)
				)
				(pin passive line
					(at 0 -50.8 0)
					(length 3.81)
					(hide yes)
					(name "GND"
						(effects
							(font
								(size 1.27 1.27)
							)
						)
					)
					(number "J21"
						(effects
							(font
								(size 1.27 1.27)
							)
						)
					)
				)
				(pin passive line
					(at 0 -50.8 0)
					(length 3.81)
					(hide yes)
					(name "GND"
						(effects
							(font
								(size 1.27 1.27)
							)
						)
					)
					(number "J24"
						(effects
							(font
								(size 1.27 1.27)
							)
						)
					)
				)
				(pin passive line
					(at 0 -50.8 0)
					(length 3.81)
					(hide yes)
					(name "GND"
						(effects
							(font
								(size 1.27 1.27)
							)
						)
					)
					(number "J25"
						(effects
							(font
								(size 1.27 1.27)
							)
						)
					)
				)
				(pin passive line
					(at 0 -50.8 0)
					(length 3.81)
					(hide yes)
					(name "GND"
						(effects
							(font
								(size 1.27 1.27)
							)
						)
					)
					(number "J28"
						(effects
							(font
								(size 1.27 1.27)
							)
						)
					)
				)
				(pin passive line
					(at 0 -50.8 0)
					(length 3.81)
					(hide yes)
					(name "GND"
						(effects
							(font
								(size 1.27 1.27)
							)
						)
					)
					(number "J29"
						(effects
							(font
								(size 1.27 1.27)
							)
						)
					)
				)
				(pin passive line
					(at 0 -50.8 0)
					(length 3.81)
					(hide yes)
					(name "GND"
						(effects
							(font
								(size 1.27 1.27)
							)
						)
					)
					(number "J3"
						(effects
							(font
								(size 1.27 1.27)
							)
						)
					)
				)
				(pin passive line
					(at 0 -50.8 0)
					(length 3.81)
					(hide yes)
					(name "GND"
						(effects
							(font
								(size 1.27 1.27)
							)
						)
					)
					(number "J32"
						(effects
							(font
								(size 1.27 1.27)
							)
						)
					)
				)
				(pin passive line
					(at 0 -50.8 0)
					(length 3.81)
					(hide yes)
					(name "GND"
						(effects
							(font
								(size 1.27 1.27)
							)
						)
					)
					(number "J33"
						(effects
							(font
								(size 1.27 1.27)
							)
						)
					)
				)
				(pin passive line
					(at 0 -50.8 0)
					(length 3.81)
					(hide yes)
					(name "GND"
						(effects
							(font
								(size 1.27 1.27)
							)
						)
					)
					(number "J36"
						(effects
							(font
								(size 1.27 1.27)
							)
						)
					)
				)
				(pin passive line
					(at 0 -50.8 0)
					(length 3.81)
					(hide yes)
					(name "GND"
						(effects
							(font
								(size 1.27 1.27)
							)
						)
					)
					(number "J37"
						(effects
							(font
								(size 1.27 1.27)
							)
						)
					)
				)
				(pin passive line
					(at 0 -50.8 0)
					(length 3.81)
					(hide yes)
					(name "GND"
						(effects
							(font
								(size 1.27 1.27)
							)
						)
					)
					(number "J40"
						(effects
							(font
								(size 1.27 1.27)
							)
						)
					)
				)
				(pin passive line
					(at 0 -50.8 0)
					(length 3.81)
					(hide yes)
					(name "GND"
						(effects
							(font
								(size 1.27 1.27)
							)
						)
					)
					(number "J43"
						(effects
							(font
								(size 1.27 1.27)
							)
						)
					)
				)
				(pin passive line
					(at 0 -50.8 0)
					(length 3.81)
					(hide yes)
					(name "GND"
						(effects
							(font
								(size 1.27 1.27)
							)
						)
					)
					(number "J46"
						(effects
							(font
								(size 1.27 1.27)
							)
						)
					)
				)
				(pin passive line
					(at 0 -50.8 0)
					(length 3.81)
					(hide yes)
					(name "GND"
						(effects
							(font
								(size 1.27 1.27)
							)
						)
					)
					(number "J49"
						(effects
							(font
								(size 1.27 1.27)
							)
						)
					)
				)
				(pin passive line
					(at 0 -50.8 0)
					(length 3.81)
					(hide yes)
					(name "GND"
						(effects
							(font
								(size 1.27 1.27)
							)
						)
					)
					(number "J56"
						(effects
							(font
								(size 1.27 1.27)
							)
						)
					)
				)
				(pin passive line
					(at 0 -50.8 0)
					(length 3.81)
					(hide yes)
					(name "GND"
						(effects
							(font
								(size 1.27 1.27)
							)
						)
					)
					(number "J62"
						(effects
							(font
								(size 1.27 1.27)
							)
						)
					)
				)
				(pin passive line
					(at 0 -50.8 0)
					(length 3.81)
					(hide yes)
					(name "GND"
						(effects
							(font
								(size 1.27 1.27)
							)
						)
					)
					(number "J8"
						(effects
							(font
								(size 1.27 1.27)
							)
						)
					)
				)
				(pin passive line
					(at 0 -50.8 0)
					(length 3.81)
					(hide yes)
					(name "GND"
						(effects
							(font
								(size 1.27 1.27)
							)
						)
					)
					(number "K11"
						(effects
							(font
								(size 1.27 1.27)
							)
						)
					)
				)
				(pin passive line
					(at 0 -50.8 0)
					(length 3.81)
					(hide yes)
					(name "GND"
						(effects
							(font
								(size 1.27 1.27)
							)
						)
					)
					(number "K14"
						(effects
							(font
								(size 1.27 1.27)
							)
						)
					)
				)
				(pin passive line
					(at 0 -50.8 0)
					(length 3.81)
					(hide yes)
					(name "GND"
						(effects
							(font
								(size 1.27 1.27)
							)
						)
					)
					(number "K15"
						(effects
							(font
								(size 1.27 1.27)
							)
						)
					)
				)
				(pin passive line
					(at 0 -50.8 0)
					(length 3.81)
					(hide yes)
					(name "GND"
						(effects
							(font
								(size 1.27 1.27)
							)
						)
					)
					(number "K18"
						(effects
							(font
								(size 1.27 1.27)
							)
						)
					)
				)
				(pin passive line
					(at 0 -50.8 0)
					(length 3.81)
					(hide yes)
					(name "GND"
						(effects
							(font
								(size 1.27 1.27)
							)
						)
					)
					(number "K19"
						(effects
							(font
								(size 1.27 1.27)
							)
						)
					)
				)
				(pin passive line
					(at 0 -50.8 0)
					(length 3.81)
					(hide yes)
					(name "GND"
						(effects
							(font
								(size 1.27 1.27)
							)
						)
					)
					(number "K22"
						(effects
							(font
								(size 1.27 1.27)
							)
						)
					)
				)
				(pin passive line
					(at 0 -50.8 0)
					(length 3.81)
					(hide yes)
					(name "GND"
						(effects
							(font
								(size 1.27 1.27)
							)
						)
					)
					(number "K23"
						(effects
							(font
								(size 1.27 1.27)
							)
						)
					)
				)
				(pin passive line
					(at 0 -50.8 0)
					(length 3.81)
					(hide yes)
					(name "GND"
						(effects
							(font
								(size 1.27 1.27)
							)
						)
					)
					(number "K26"
						(effects
							(font
								(size 1.27 1.27)
							)
						)
					)
				)
				(pin passive line
					(at 0 -50.8 0)
					(length 3.81)
					(hide yes)
					(name "GND"
						(effects
							(font
								(size 1.27 1.27)
							)
						)
					)
					(number "K27"
						(effects
							(font
								(size 1.27 1.27)
							)
						)
					)
				)
				(pin passive line
					(at 0 -50.8 0)
					(length 3.81)
					(hide yes)
					(name "GND"
						(effects
							(font
								(size 1.27 1.27)
							)
						)
					)
					(number "K30"
						(effects
							(font
								(size 1.27 1.27)
							)
						)
					)
				)
				(pin passive line
					(at 0 -50.8 0)
					(length 3.81)
					(hide yes)
					(name "GND"
						(effects
							(font
								(size 1.27 1.27)
							)
						)
					)
					(number "K31"
						(effects
							(font
								(size 1.27 1.27)
							)
						)
					)
				)
				(pin passive line
					(at 0 -50.8 0)
					(length 3.81)
					(hide yes)
					(name "GND"
						(effects
							(font
								(size 1.27 1.27)
							)
						)
					)
					(number "K34"
						(effects
							(font
								(size 1.27 1.27)
							)
						)
					)
				)
				(pin passive line
					(at 0 -50.8 0)
					(length 3.81)
					(hide yes)
					(name "GND"
						(effects
							(font
								(size 1.27 1.27)
							)
						)
					)
					(number "K35"
						(effects
							(font
								(size 1.27 1.27)
							)
						)
					)
				)
				(pin passive line
					(at 0 -50.8 0)
					(length 3.81)
					(hide yes)
					(name "GND"
						(effects
							(font
								(size 1.27 1.27)
							)
						)
					)
					(number "K38"
						(effects
							(font
								(size 1.27 1.27)
							)
						)
					)
				)
				(pin passive line
					(at 0 -50.8 0)
					(length 3.81)
					(hide yes)
					(name "GND"
						(effects
							(font
								(size 1.27 1.27)
							)
						)
					)
					(number "K39"
						(effects
							(font
								(size 1.27 1.27)
							)
						)
					)
				)
				(pin passive line
					(at 0 -50.8 0)
					(length 3.81)
					(hide yes)
					(name "GND"
						(effects
							(font
								(size 1.27 1.27)
							)
						)
					)
					(number "K4"
						(effects
							(font
								(size 1.27 1.27)
							)
						)
					)
				)
				(pin passive line
					(at 0 -50.8 0)
					(length 3.81)
					(hide yes)
					(name "GND"
						(effects
							(font
								(size 1.27 1.27)
							)
						)
					)
					(number "K41"
						(effects
							(font
								(size 1.27 1.27)
							)
						)
					)
				)
				(pin passive line
					(at 0 -50.8 0)
					(length 3.81)
					(hide yes)
					(name "GND"
						(effects
							(font
								(size 1.27 1.27)
							)
						)
					)
					(number "K42"
						(effects
							(font
								(size 1.27 1.27)
							)
						)
					)
				)
				(pin passive line
					(at 0 -50.8 0)
					(length 3.81)
					(hide yes)
					(name "GND"
						(effects
							(font
								(size 1.27 1.27)
							)
						)
					)
					(number "K45"
						(effects
							(font
								(size 1.27 1.27)
							)
						)
					)
				)
				(pin passive line
					(at 0 -50.8 0)
					(length 3.81)
					(hide yes)
					(name "GND"
						(effects
							(font
								(size 1.27 1.27)
							)
						)
					)
					(number "K48"
						(effects
							(font
								(size 1.27 1.27)
							)
						)
					)
				)
				(pin passive line
					(at 0 -50.8 0)
					(length 3.81)
					(hide yes)
					(name "GND"
						(effects
							(font
								(size 1.27 1.27)
							)
						)
					)
					(number "K55"
						(effects
							(font
								(size 1.27 1.27)
							)
						)
					)
				)
				(pin passive line
					(at 0 -50.8 0)
					(length 3.81)
					(hide yes)
					(name "GND"
						(effects
							(font
								(size 1.27 1.27)
							)
						)
					)
					(number "K63"
						(effects
							(font
								(size 1.27 1.27)
							)
						)
					)
				)
				(pin passive line
					(at 0 -50.8 0)
					(length 3.81)
					(hide yes)
					(name "GND"
						(effects
							(font
								(size 1.27 1.27)
							)
						)
					)
					(number "K8"
						(effects
							(font
								(size 1.27 1.27)
							)
						)
					)
				)
				(pin passive line
					(at 0 -50.8 0)
					(length 3.81)
					(hide yes)
					(name "GND"
						(effects
							(font
								(size 1.27 1.27)
							)
						)
					)
					(number "L12"
						(effects
							(font
								(size 1.27 1.27)
							)
						)
					)
				)
				(pin passive line
					(at 0 -50.8 0)
					(length 3.81)
					(hide yes)
					(name "GND"
						(effects
							(font
								(size 1.27 1.27)
							)
						)
					)
					(number "L13"
						(effects
							(font
								(size 1.27 1.27)
							)
						)
					)
				)
				(pin passive line
					(at 0 -50.8 0)
					(length 3.81)
					(hide yes)
					(name "GND"
						(effects
							(font
								(size 1.27 1.27)
							)
						)
					)
					(number "L16"
						(effects
							(font
								(size 1.27 1.27)
							)
						)
					)
				)
				(pin passive line
					(at 0 -50.8 0)
					(length 3.81)
					(hide yes)
					(name "GND"
						(effects
							(font
								(size 1.27 1.27)
							)
						)
					)
					(number "L17"
						(effects
							(font
								(size 1.27 1.27)
							)
						)
					)
				)
				(pin passive line
					(at 0 -50.8 0)
					(length 3.81)
					(hide yes)
					(name "GND"
						(effects
							(font
								(size 1.27 1.27)
							)
						)
					)
					(number "L20"
						(effects
							(font
								(size 1.27 1.27)
							)
						)
					)
				)
				(pin passive line
					(at 0 -50.8 0)
					(length 3.81)
					(hide yes)
					(name "GND"
						(effects
							(font
								(size 1.27 1.27)
							)
						)
					)
					(number "L21"
						(effects
							(font
								(size 1.27 1.27)
							)
						)
					)
				)
				(pin passive line
					(at 0 -50.8 0)
					(length 3.81)
					(hide yes)
					(name "GND"
						(effects
							(font
								(size 1.27 1.27)
							)
						)
					)
					(number "L24"
						(effects
							(font
								(size 1.27 1.27)
							)
						)
					)
				)
				(pin passive line
					(at 0 -50.8 0)
					(length 3.81)
					(hide yes)
					(name "GND"
						(effects
							(font
								(size 1.27 1.27)
							)
						)
					)
					(number "L25"
						(effects
							(font
								(size 1.27 1.27)
							)
						)
					)
				)
				(pin passive line
					(at 0 -50.8 0)
					(length 3.81)
					(hide yes)
					(name "GND"
						(effects
							(font
								(size 1.27 1.27)
							)
						)
					)
					(number "L28"
						(effects
							(font
								(size 1.27 1.27)
							)
						)
					)
				)
				(pin passive line
					(at 0 -50.8 0)
					(length 3.81)
					(hide yes)
					(name "GND"
						(effects
							(font
								(size 1.27 1.27)
							)
						)
					)
					(number "L29"
						(effects
							(font
								(size 1.27 1.27)
							)
						)
					)
				)
				(pin passive line
					(at 0 -50.8 0)
					(length 3.81)
					(hide yes)
					(name "GND"
						(effects
							(font
								(size 1.27 1.27)
							)
						)
					)
					(number "L3"
						(effects
							(font
								(size 1.27 1.27)
							)
						)
					)
				)
				(pin passive line
					(at 0 -50.8 0)
					(length 3.81)
					(hide yes)
					(name "GND"
						(effects
							(font
								(size 1.27 1.27)
							)
						)
					)
					(number "L32"
						(effects
							(font
								(size 1.27 1.27)
							)
						)
					)
				)
				(pin passive line
					(at 0 -50.8 0)
					(length 3.81)
					(hide yes)
					(name "GND"
						(effects
							(font
								(size 1.27 1.27)
							)
						)
					)
					(number "L33"
						(effects
							(font
								(size 1.27 1.27)
							)
						)
					)
				)
				(pin passive line
					(at 0 -50.8 0)
					(length 3.81)
					(hide yes)
					(name "GND"
						(effects
							(font
								(size 1.27 1.27)
							)
						)
					)
					(number "L36"
						(effects
							(font
								(size 1.27 1.27)
							)
						)
					)
				)
				(pin passive line
					(at 0 -50.8 0)
					(length 3.81)
					(hide yes)
					(name "GND"
						(effects
							(font
								(size 1.27 1.27)
							)
						)
					)
					(number "L37"
						(effects
							(font
								(size 1.27 1.27)
							)
						)
					)
				)
				(pin passive line
					(at 0 -50.8 0)
					(length 3.81)
					(hide yes)
					(name "GND"
						(effects
							(font
								(size 1.27 1.27)
							)
						)
					)
					(number "L40"
						(effects
							(font
								(size 1.27 1.27)
							)
						)
					)
				)
				(pin passive line
					(at 0 -50.8 0)
					(length 3.81)
					(hide yes)
					(name "GND"
						(effects
							(font
								(size 1.27 1.27)
							)
						)
					)
					(number "L43"
						(effects
							(font
								(size 1.27 1.27)
							)
						)
					)
				)
				(pin passive line
					(at 0 -50.8 0)
					(length 3.81)
					(hide yes)
					(name "GND"
						(effects
							(font
								(size 1.27 1.27)
							)
						)
					)
					(number "L46"
						(effects
							(font
								(size 1.27 1.27)
							)
						)
					)
				)
				(pin passive line
					(at 0 -50.8 0)
					(length 3.81)
					(hide yes)
					(name "GND"
						(effects
							(font
								(size 1.27 1.27)
							)
						)
					)
					(number "L7"
						(effects
							(font
								(size 1.27 1.27)
							)
						)
					)
				)
				(pin input line
					(at 57.15 0 180)
					(length 3.81)
					(name "MODULE_POWER_ON"
						(effects
							(font
								(size 1.27 1.27)
							)
						)
					)
					(number "L54"
						(effects
							(font
								(size 1.27 1.27)
							)
						)
					)
				)
				(pin output line
					(at 57.15 -2.54 180)
					(length 3.81)
					(name "CARRIER_POWER_ON"
						(effects
							(font
								(size 1.27 1.27)
							)
						)
					)
					(number "L62"
						(effects
							(font
								(size 1.27 1.27)
							)
						)
					)
				)
				(pin bidirectional line
					(at 57.15 -6.35 180)
					(length 3.81)
					(name "POWER_BTN_N"
						(effects
							(font
								(size 1.27 1.27)
							)
						)
					)
					(number "L61"
						(effects
							(font
								(size 1.27 1.27)
							)
						)
					)
				)
				(pin input line
					(at 57.15 -8.89 180)
					(length 3.81)
					(name "PERIPHERAL_RESET_N"
						(effects
							(font
								(size 1.27 1.27)
							)
						)
					)
					(number "L58"
						(effects
							(font
								(size 1.27 1.27)
							)
						)
					)
				)
				(pin input line
					(at 57.15 -11.43 180)
					(length 3.81)
					(name "FORCE_RECOVERY_N"
						(effects
							(font
								(size 1.27 1.27)
							)
						)
					)
					(number "L10"
						(effects
							(font
								(size 1.27 1.27)
							)
						)
					)
				)
				(pin input line
					(at 57.15 -13.97 180)
					(length 3.81)
					(name "SLEEP_REQ_N"
						(effects
							(font
								(size 1.27 1.27)
							)
						)
					)
					(number "L11"
						(effects
							(font
								(size 1.27 1.27)
							)
						)
					)
				)
				(pin output line
					(at 57.15 -16.51 180)
					(length 3.81)
					(name "MODULE_SLEEP_N"
						(effects
							(font
								(size 1.27 1.27)
							)
						)
					)
					(number "J60"
						(effects
							(font
								(size 1.27 1.27)
							)
						)
					)
				)
				(pin bidirectional line
					(at 57.15 -21.59 180)
					(length 3.81)
					(name "VCOMP_ALERT_N"
						(effects
							(font
								(size 1.27 1.27)
							)
						)
					)
					(number "F61"
						(effects
							(font
								(size 1.27 1.27)
							)
						)
					)
				)
				(pin output line
					(at 57.15 -24.13 180)
					(length 3.81)
					(name "THERM_ALERT_N"
						(effects
							(font
								(size 1.27 1.27)
							)
						)
					)
					(number "L56"
						(effects
							(font
								(size 1.27 1.27)
							)
						)
					)
				)
				(pin input line
					(at 57.15 -26.67 180)
					(length 3.81)
					(name "SYSTEM_OC_N"
						(effects
							(font
								(size 1.27 1.27)
							)
						)
					)
					(number "A61"
						(effects
							(font
								(size 1.27 1.27)
							)
						)
					)
				)
				(pin output line
					(at 57.15 -29.21 180)
					(length 3.81)
					(name "MODULE_SHDN_N"
						(effects
							(font
								(size 1.27 1.27)
							)
						)
					)
					(number "L52"
						(effects
							(font
								(size 1.27 1.27)
							)
						)
					)
				)
				(pin passive line
					(at 57.15 -33.02 180)
					(length 3.81)
					(name "UFS0_REF_CLK"
						(effects
							(font
								(size 1.27 1.27)
							)
						)
					)
					(number "A6"
						(effects
							(font
								(size 1.27 1.27)
							)
						)
					)
				)
				(pin passive line
					(at 57.15 -35.56 180)
					(length 3.81)
					(name "UFS0_RST_N"
						(effects
							(font
								(size 1.27 1.27)
							)
						)
					)
					(number "C6"
						(effects
							(font
								(size 1.27 1.27)
							)
						)
					)
				)
				(pin output line
					(at 57.15 -38.1 180)
					(length 3.81)
					(name "THERM_SHDN_REQ_N"
						(effects
							(font
								(size 1.27 1.27)
							)
						)
					)
					(number "G59"
						(effects
							(font
								(size 1.27 1.27)
							)
						)
					)
				)
				(pin passive line
					(at 57.15 -40.64 180)
					(length 3.81)
					(name "FSI_GPIO03"
						(effects
							(font
								(size 1.27 1.27)
							)
						)
					)
					(number "K37"
						(effects
							(font
								(size 1.27 1.27)
							)
						)
					)
					(alternate "SOC_ERROR" passive line)
				)
				(pin output line
					(at 57.15 -45.72 180)
					(length 3.81)
					(name "VM_SLEEP_N"
						(effects
							(font
								(size 1.27 1.27)
							)
						)
					)
					(number "L41"
						(effects
							(font
								(size 1.27 1.27)
							)
						)
					)
				)
				(pin passive line
					(at 57.15 -48.26 180)
					(length 3.81)
					(name "GPIO56"
						(effects
							(font
								(size 1.27 1.27)
							)
						)
					)
					(number "G5"
						(effects
							(font
								(size 1.27 1.27)
							)
						)
					)
					(alternate "BOOT_CHAIN_SEL" passive line)
				)
				(pin passive line
					(at 57.15 -50.8 180)
					(length 3.81)
					(name "GPIO30"
						(effects
							(font
								(size 1.27 1.27)
							)
						)
					)
					(number "B55"
						(effects
							(font
								(size 1.27 1.27)
							)
						)
					)
					(alternate "IST_DONE_N" passive line)
				)
			)
			(symbol "Hermaphroditic_Molex_203456-0003_CUSTOM_Jetson_AGX_Thor_H8mm_2_1"
				(rectangle
					(start 3.81 3.81)
					(end 36.83 -93.98)
					(stroke
						(width 0.254)
						(type default)
					)
					(fill
						(type background)
					)
				)
				(polyline
					(pts
						(xy 3.81 -41.91) (xy 36.83 -41.91)
					)
					(stroke
						(width 0.254)
						(type default)
					)
					(fill
						(type background)
					)
				)
				(polyline
					(pts
						(xy 3.81 -86.36) (xy 36.83 -86.36)
					)
					(stroke
						(width 0.254)
						(type default)
					)
					(fill
						(type background)
					)
				)
				(text "UHPY0"
					(at 17.272 1.524 0)
					(effects
						(font
							(size 1.27 1.27)
							(thickness 0.15)
						)
						(justify left bottom)
					)
				)
				(text "UPHY1"
					(at 17.526 -44.196 0)
					(effects
						(font
							(size 1.27 1.27)
							(thickness 0.15)
						)
						(justify left bottom)
					)
				)
				(pin input line
					(at 0 0 0)
					(length 3.81)
					(name "UPHY_RX0_P"
						(effects
							(font
								(size 1.27 1.27)
							)
						)
					)
					(number "C34"
						(effects
							(font
								(size 1.27 1.27)
							)
						)
					)
				)
				(pin input line
					(at 0 -2.54 0)
					(length 3.81)
					(name "UPHY_RX0_N"
						(effects
							(font
								(size 1.27 1.27)
							)
						)
					)
					(number "C35"
						(effects
							(font
								(size 1.27 1.27)
							)
						)
					)
				)
				(pin input line
					(at 0 -5.08 0)
					(length 3.81)
					(name "UPHY_RX1_P"
						(effects
							(font
								(size 1.27 1.27)
							)
						)
					)
					(number "A22"
						(effects
							(font
								(size 1.27 1.27)
							)
						)
					)
				)
				(pin input line
					(at 0 -7.62 0)
					(length 3.81)
					(name "UPHY_RX1_N"
						(effects
							(font
								(size 1.27 1.27)
							)
						)
					)
					(number "A23"
						(effects
							(font
								(size 1.27 1.27)
							)
						)
					)
				)
				(pin input line
					(at 0 -10.16 0)
					(length 3.81)
					(name "UPHY_RX2_P"
						(effects
							(font
								(size 1.27 1.27)
							)
						)
					)
					(number "C23"
						(effects
							(font
								(size 1.27 1.27)
							)
						)
					)
				)
				(pin input line
					(at 0 -12.7 0)
					(length 3.81)
					(name "UPHY_RX2_N"
						(effects
							(font
								(size 1.27 1.27)
							)
						)
					)
					(number "C22"
						(effects
							(font
								(size 1.27 1.27)
							)
						)
					)
				)
				(pin input line
					(at 0 -15.24 0)
					(length 3.81)
					(name "UPHY_RX3_P"
						(effects
							(font
								(size 1.27 1.27)
							)
						)
					)
					(number "B33"
						(effects
							(font
								(size 1.27 1.27)
							)
						)
					)
				)
				(pin input line
					(at 0 -17.78 0)
					(length 3.81)
					(name "UPHY_RX3_N"
						(effects
							(font
								(size 1.27 1.27)
							)
						)
					)
					(number "B32"
						(effects
							(font
								(size 1.27 1.27)
							)
						)
					)
				)
				(pin input line
					(at 0 -20.32 0)
					(length 3.81)
					(name "UPHY_RX4_P"
						(effects
							(font
								(size 1.27 1.27)
							)
						)
					)
					(number "B21"
						(effects
							(font
								(size 1.27 1.27)
							)
						)
					)
				)
				(pin input line
					(at 0 -22.86 0)
					(length 3.81)
					(name "UPHY_RX4_N"
						(effects
							(font
								(size 1.27 1.27)
							)
						)
					)
					(number "B20"
						(effects
							(font
								(size 1.27 1.27)
							)
						)
					)
				)
				(pin input line
					(at 0 -25.4 0)
					(length 3.81)
					(name "UPHY_RX5_P"
						(effects
							(font
								(size 1.27 1.27)
							)
						)
					)
					(number "D20"
						(effects
							(font
								(size 1.27 1.27)
							)
						)
					)
				)
				(pin input line
					(at 0 -27.94 0)
					(length 3.81)
					(name "UPHY_RX5_N"
						(effects
							(font
								(size 1.27 1.27)
							)
						)
					)
					(number "D21"
						(effects
							(font
								(size 1.27 1.27)
							)
						)
					)
				)
				(pin input line
					(at 0 -30.48 0)
					(length 3.81)
					(name "UPHY_RX6_P"
						(effects
							(font
								(size 1.27 1.27)
							)
						)
					)
					(number "B12"
						(effects
							(font
								(size 1.27 1.27)
							)
						)
					)
				)
				(pin input line
					(at 0 -33.02 0)
					(length 3.81)
					(name "UPHY_RX6_N"
						(effects
							(font
								(size 1.27 1.27)
							)
						)
					)
					(number "B13"
						(effects
							(font
								(size 1.27 1.27)
							)
						)
					)
				)
				(pin input line
					(at 0 -35.56 0)
					(length 3.81)
					(name "UPHY_RX7_P"
						(effects
							(font
								(size 1.27 1.27)
							)
						)
					)
					(number "D12"
						(effects
							(font
								(size 1.27 1.27)
							)
						)
					)
				)
				(pin input line
					(at 0 -38.1 0)
					(length 3.81)
					(name "UPHY_RX7_N"
						(effects
							(font
								(size 1.27 1.27)
							)
						)
					)
					(number "D13"
						(effects
							(font
								(size 1.27 1.27)
							)
						)
					)
				)
				(pin input line
					(at 0 -45.72 0)
					(length 3.81)
					(name "UPHY_RX8_P"
						(effects
							(font
								(size 1.27 1.27)
							)
						)
					)
					(number "D24"
						(effects
							(font
								(size 1.27 1.27)
							)
						)
					)
				)
				(pin input line
					(at 0 -48.26 0)
					(length 3.81)
					(name "UPHY_RX8_N"
						(effects
							(font
								(size 1.27 1.27)
							)
						)
					)
					(number "D25"
						(effects
							(font
								(size 1.27 1.27)
							)
						)
					)
				)
				(pin input line
					(at 0 -50.8 0)
					(length 3.81)
					(name "UPHY_RX9_P"
						(effects
							(font
								(size 1.27 1.27)
							)
						)
					)
					(number "B25"
						(effects
							(font
								(size 1.27 1.27)
							)
						)
					)
				)
				(pin input line
					(at 0 -53.34 0)
					(length 3.81)
					(name "UPHY_RX9_N"
						(effects
							(font
								(size 1.27 1.27)
							)
						)
					)
					(number "B24"
						(effects
							(font
								(size 1.27 1.27)
							)
						)
					)
				)
				(pin input line
					(at 0 -55.88 0)
					(length 3.81)
					(name "UPHY_RX10_P"
						(effects
							(font
								(size 1.27 1.27)
							)
						)
					)
					(number "C27"
						(effects
							(font
								(size 1.27 1.27)
							)
						)
					)
				)
				(pin input line
					(at 0 -58.42 0)
					(length 3.81)
					(name "UPHY_RX10_N"
						(effects
							(font
								(size 1.27 1.27)
							)
						)
					)
					(number "C26"
						(effects
							(font
								(size 1.27 1.27)
							)
						)
					)
				)
				(pin input line
					(at 0 -60.96 0)
					(length 3.81)
					(name "UPHY_RX11_P"
						(effects
							(font
								(size 1.27 1.27)
							)
						)
					)
					(number "A26"
						(effects
							(font
								(size 1.27 1.27)
							)
						)
					)
				)
				(pin input line
					(at 0 -63.5 0)
					(length 3.81)
					(name "UPHY_RX11_N"
						(effects
							(font
								(size 1.27 1.27)
							)
						)
					)
					(number "A27"
						(effects
							(font
								(size 1.27 1.27)
							)
						)
					)
				)
				(pin input line
					(at 0 -66.04 0)
					(length 3.81)
					(name "UPHY_RX12_P"
						(effects
							(font
								(size 1.27 1.27)
							)
						)
					)
					(number "D28"
						(effects
							(font
								(size 1.27 1.27)
							)
						)
					)
				)
				(pin input line
					(at 0 -68.58 0)
					(length 3.81)
					(name "UPHY_RX12_N"
						(effects
							(font
								(size 1.27 1.27)
							)
						)
					)
					(number "D29"
						(effects
							(font
								(size 1.27 1.27)
							)
						)
					)
				)
				(pin input line
					(at 0 -71.12 0)
					(length 3.81)
					(name "UPHY_RX13_P"
						(effects
							(font
								(size 1.27 1.27)
							)
						)
					)
					(number "B29"
						(effects
							(font
								(size 1.27 1.27)
							)
						)
					)
				)
				(pin input line
					(at 0 -73.66 0)
					(length 3.81)
					(name "UPHY_RX13_N"
						(effects
							(font
								(size 1.27 1.27)
							)
						)
					)
					(number "B28"
						(effects
							(font
								(size 1.27 1.27)
							)
						)
					)
				)
				(pin input line
					(at 0 -76.2 0)
					(length 3.81)
					(name "UPHY_RX14_P"
						(effects
							(font
								(size 1.27 1.27)
							)
						)
					)
					(number "C31"
						(effects
							(font
								(size 1.27 1.27)
							)
						)
					)
				)
				(pin input line
					(at 0 -78.74 0)
					(length 3.81)
					(name "UPHY_RX14_N"
						(effects
							(font
								(size 1.27 1.27)
							)
						)
					)
					(number "C30"
						(effects
							(font
								(size 1.27 1.27)
							)
						)
					)
				)
				(pin input line
					(at 0 -81.28 0)
					(length 3.81)
					(name "UPHY_RX15_P"
						(effects
							(font
								(size 1.27 1.27)
							)
						)
					)
					(number "A30"
						(effects
							(font
								(size 1.27 1.27)
							)
						)
					)
				)
				(pin input line
					(at 0 -83.82 0)
					(length 3.81)
					(name "UPHY_RX15_N"
						(effects
							(font
								(size 1.27 1.27)
							)
						)
					)
					(number "A31"
						(effects
							(font
								(size 1.27 1.27)
							)
						)
					)
				)
				(pin input line
					(at 0 -88.9 0)
					(length 3.81)
					(name "UPHY_RX16_P"
						(effects
							(font
								(size 1.27 1.27)
							)
						)
					)
					(number "B16"
						(effects
							(font
								(size 1.27 1.27)
							)
						)
					)
				)
				(pin input line
					(at 0 -91.44 0)
					(length 3.81)
					(name "UPHY_RX16_N"
						(effects
							(font
								(size 1.27 1.27)
							)
						)
					)
					(number "B17"
						(effects
							(font
								(size 1.27 1.27)
							)
						)
					)
				)
				(pin output line
					(at 40.64 0 180)
					(length 3.81)
					(name "UPHY_TX0_P"
						(effects
							(font
								(size 1.27 1.27)
							)
						)
					)
					(number "K32"
						(effects
							(font
								(size 1.27 1.27)
							)
						)
					)
				)
				(pin output line
					(at 40.64 -2.54 180)
					(length 3.81)
					(name "UPHY_TX0_N"
						(effects
							(font
								(size 1.27 1.27)
							)
						)
					)
					(number "K33"
						(effects
							(font
								(size 1.27 1.27)
							)
						)
					)
				)
				(pin output line
					(at 40.64 -5.08 180)
					(length 3.81)
					(name "UPHY_TX1_P"
						(effects
							(font
								(size 1.27 1.27)
							)
						)
					)
					(number "J22"
						(effects
							(font
								(size 1.27 1.27)
							)
						)
					)
				)
				(pin output line
					(at 40.64 -7.62 180)
					(length 3.81)
					(name "UPHY_TX1_N"
						(effects
							(font
								(size 1.27 1.27)
							)
						)
					)
					(number "J23"
						(effects
							(font
								(size 1.27 1.27)
							)
						)
					)
				)
				(pin output line
					(at 40.64 -10.16 180)
					(length 3.81)
					(name "UPHY_TX2_P"
						(effects
							(font
								(size 1.27 1.27)
							)
						)
					)
					(number "G23"
						(effects
							(font
								(size 1.27 1.27)
							)
						)
					)
				)
				(pin output line
					(at 40.64 -12.7 180)
					(length 3.81)
					(name "UPHY_TX2_N"
						(effects
							(font
								(size 1.27 1.27)
							)
						)
					)
					(number "G22"
						(effects
							(font
								(size 1.27 1.27)
							)
						)
					)
				)
				(pin output line
					(at 40.64 -15.24 180)
					(length 3.81)
					(name "UPHY_TX3_P"
						(effects
							(font
								(size 1.27 1.27)
							)
						)
					)
					(number "G35"
						(effects
							(font
								(size 1.27 1.27)
							)
						)
					)
				)
				(pin output line
					(at 40.64 -17.78 180)
					(length 3.81)
					(name "UPHY_TX3_N"
						(effects
							(font
								(size 1.27 1.27)
							)
						)
					)
					(number "G34"
						(effects
							(font
								(size 1.27 1.27)
							)
						)
					)
				)
				(pin output line
					(at 40.64 -20.32 180)
					(length 3.81)
					(name "UPHY_TX4_P"
						(effects
							(font
								(size 1.27 1.27)
							)
						)
					)
					(number "K21"
						(effects
							(font
								(size 1.27 1.27)
							)
						)
					)
				)
				(pin output line
					(at 40.64 -22.86 180)
					(length 3.81)
					(name "UPHY_TX4_N"
						(effects
							(font
								(size 1.27 1.27)
							)
						)
					)
					(number "K20"
						(effects
							(font
								(size 1.27 1.27)
							)
						)
					)
				)
				(pin output line
					(at 40.64 -25.4 180)
					(length 3.81)
					(name "UPHY_TX5_P"
						(effects
							(font
								(size 1.27 1.27)
							)
						)
					)
					(number "H20"
						(effects
							(font
								(size 1.27 1.27)
							)
						)
					)
				)
				(pin output line
					(at 40.64 -27.94 180)
					(length 3.81)
					(name "UPHY_TX5_N"
						(effects
							(font
								(size 1.27 1.27)
							)
						)
					)
					(number "H21"
						(effects
							(font
								(size 1.27 1.27)
							)
						)
					)
				)
				(pin output line
					(at 40.64 -30.48 180)
					(length 3.81)
					(name "UPHY_TX6_P"
						(effects
							(font
								(size 1.27 1.27)
							)
						)
					)
					(number "K13"
						(effects
							(font
								(size 1.27 1.27)
							)
						)
					)
				)
				(pin output line
					(at 40.64 -33.02 180)
					(length 3.81)
					(name "UPHY_TX6_N"
						(effects
							(font
								(size 1.27 1.27)
							)
						)
					)
					(number "K12"
						(effects
							(font
								(size 1.27 1.27)
							)
						)
					)
				)
				(pin output line
					(at 40.64 -35.56 180)
					(length 3.81)
					(name "UPHY_TX7_P"
						(effects
							(font
								(size 1.27 1.27)
							)
						)
					)
					(number "H12"
						(effects
							(font
								(size 1.27 1.27)
							)
						)
					)
				)
				(pin output line
					(at 40.64 -38.1 180)
					(length 3.81)
					(name "UPHY_TX7_N"
						(effects
							(font
								(size 1.27 1.27)
							)
						)
					)
					(number "H13"
						(effects
							(font
								(size 1.27 1.27)
							)
						)
					)
				)
				(pin output line
					(at 40.64 -45.72 180)
					(length 3.81)
					(name "UPHY_TX8_P"
						(effects
							(font
								(size 1.27 1.27)
							)
						)
					)
					(number "H24"
						(effects
							(font
								(size 1.27 1.27)
							)
						)
					)
				)
				(pin output line
					(at 40.64 -48.26 180)
					(length 3.81)
					(name "UPHY_TX8_N"
						(effects
							(font
								(size 1.27 1.27)
							)
						)
					)
					(number "H25"
						(effects
							(font
								(size 1.27 1.27)
							)
						)
					)
				)
				(pin output line
					(at 40.64 -50.8 180)
					(length 3.81)
					(name "UPHY_TX9_P"
						(effects
							(font
								(size 1.27 1.27)
							)
						)
					)
					(number "K25"
						(effects
							(font
								(size 1.27 1.27)
							)
						)
					)
				)
				(pin output line
					(at 40.64 -53.34 180)
					(length 3.81)
					(name "UPHY_TX9_N"
						(effects
							(font
								(size 1.27 1.27)
							)
						)
					)
					(number "K24"
						(effects
							(font
								(size 1.27 1.27)
							)
						)
					)
				)
				(pin output line
					(at 40.64 -55.88 180)
					(length 3.81)
					(name "UPHY_TX10_P"
						(effects
							(font
								(size 1.27 1.27)
							)
						)
					)
					(number "G27"
						(effects
							(font
								(size 1.27 1.27)
							)
						)
					)
				)
				(pin output line
					(at 40.64 -58.42 180)
					(length 3.81)
					(name "UPHY_TX10_N"
						(effects
							(font
								(size 1.27 1.27)
							)
						)
					)
					(number "G26"
						(effects
							(font
								(size 1.27 1.27)
							)
						)
					)
				)
				(pin output line
					(at 40.64 -60.96 180)
					(length 3.81)
					(name "UPHY_TX11_P"
						(effects
							(font
								(size 1.27 1.27)
							)
						)
					)
					(number "J26"
						(effects
							(font
								(size 1.27 1.27)
							)
						)
					)
				)
				(pin output line
					(at 40.64 -63.5 180)
					(length 3.81)
					(name "UPHY_TX11_N"
						(effects
							(font
								(size 1.27 1.27)
							)
						)
					)
					(number "J27"
						(effects
							(font
								(size 1.27 1.27)
							)
						)
					)
				)
				(pin output line
					(at 40.64 -66.04 180)
					(length 3.81)
					(name "UPHY_TX12_P"
						(effects
							(font
								(size 1.27 1.27)
							)
						)
					)
					(number "H28"
						(effects
							(font
								(size 1.27 1.27)
							)
						)
					)
				)
				(pin output line
					(at 40.64 -68.58 180)
					(length 3.81)
					(name "UPHY_TX12_N"
						(effects
							(font
								(size 1.27 1.27)
							)
						)
					)
					(number "H29"
						(effects
							(font
								(size 1.27 1.27)
							)
						)
					)
				)
				(pin output line
					(at 40.64 -71.12 180)
					(length 3.81)
					(name "UPHY_TX13_P"
						(effects
							(font
								(size 1.27 1.27)
							)
						)
					)
					(number "K29"
						(effects
							(font
								(size 1.27 1.27)
							)
						)
					)
				)
				(pin output line
					(at 40.64 -73.66 180)
					(length 3.81)
					(name "UPHY_TX13_N"
						(effects
							(font
								(size 1.27 1.27)
							)
						)
					)
					(number "K28"
						(effects
							(font
								(size 1.27 1.27)
							)
						)
					)
				)
				(pin output line
					(at 40.64 -76.2 180)
					(length 3.81)
					(name "UPHY_TX14_P"
						(effects
							(font
								(size 1.27 1.27)
							)
						)
					)
					(number "G31"
						(effects
							(font
								(size 1.27 1.27)
							)
						)
					)
				)
				(pin output line
					(at 40.64 -78.74 180)
					(length 3.81)
					(name "UPHY_TX14_N"
						(effects
							(font
								(size 1.27 1.27)
							)
						)
					)
					(number "G30"
						(effects
							(font
								(size 1.27 1.27)
							)
						)
					)
				)
				(pin output line
					(at 40.64 -81.28 180)
					(length 3.81)
					(name "UPHY_TX15_P"
						(effects
							(font
								(size 1.27 1.27)
							)
						)
					)
					(number "J30"
						(effects
							(font
								(size 1.27 1.27)
							)
						)
					)
				)
				(pin output line
					(at 40.64 -83.82 180)
					(length 3.81)
					(name "UPHY_TX15_N"
						(effects
							(font
								(size 1.27 1.27)
							)
						)
					)
					(number "J31"
						(effects
							(font
								(size 1.27 1.27)
							)
						)
					)
				)
				(pin output line
					(at 40.64 -88.9 180)
					(length 3.81)
					(name "UPHY_TX16_P"
						(effects
							(font
								(size 1.27 1.27)
							)
						)
					)
					(number "K17"
						(effects
							(font
								(size 1.27 1.27)
							)
						)
					)
				)
				(pin output line
					(at 40.64 -91.44 180)
					(length 3.81)
					(name "UPHY_TX16_N"
						(effects
							(font
								(size 1.27 1.27)
							)
						)
					)
					(number "K16"
						(effects
							(font
								(size 1.27 1.27)
							)
						)
					)
				)
			)
			(symbol "Hermaphroditic_Molex_203456-0003_CUSTOM_Jetson_AGX_Thor_H8mm_3_1"
				(rectangle
					(start 3.81 2.54)
					(end 43.18 -59.69)
					(stroke
						(width 0.254)
						(type default)
					)
					(fill
						(type background)
					)
				)
				(pin bidirectional line
					(at 0 0 0)
					(length 3.81)
					(name "USB0_P"
						(effects
							(font
								(size 1.27 1.27)
							)
						)
					)
					(number "F12"
						(effects
							(font
								(size 1.27 1.27)
							)
						)
					)
				)
				(pin bidirectional line
					(at 0 -2.54 0)
					(length 3.81)
					(name "USB0_N"
						(effects
							(font
								(size 1.27 1.27)
							)
						)
					)
					(number "F13"
						(effects
							(font
								(size 1.27 1.27)
							)
						)
					)
				)
				(pin bidirectional line
					(at 0 -6.35 0)
					(length 3.81)
					(name "USB1_P"
						(effects
							(font
								(size 1.27 1.27)
							)
						)
					)
					(number "C11"
						(effects
							(font
								(size 1.27 1.27)
							)
						)
					)
				)
				(pin bidirectional line
					(at 0 -8.89 0)
					(length 3.81)
					(name "USB1_N"
						(effects
							(font
								(size 1.27 1.27)
							)
						)
					)
					(number "C10"
						(effects
							(font
								(size 1.27 1.27)
							)
						)
					)
				)
				(pin output line
					(at 0 -16.51 0)
					(length 3.81)
					(name "UPHY_REFCLK0_P"
						(effects
							(font
								(size 1.27 1.27)
							)
						)
					)
					(number "F16"
						(effects
							(font
								(size 1.27 1.27)
							)
						)
					)
				)
				(pin output line
					(at 0 -19.05 0)
					(length 3.81)
					(name "UPHY_REFCLK0_N"
						(effects
							(font
								(size 1.27 1.27)
							)
						)
					)
					(number "F17"
						(effects
							(font
								(size 1.27 1.27)
							)
						)
					)
				)
				(pin bidirectional line
					(at 0 -21.59 0)
					(length 3.81)
					(name "UPHY_REFCLK1_P"
						(effects
							(font
								(size 1.27 1.27)
							)
						)
					)
					(number "F24"
						(effects
							(font
								(size 1.27 1.27)
							)
						)
					)
				)
				(pin bidirectional line
					(at 0 -24.13 0)
					(length 3.81)
					(name "UPHY_REFCLK1_N"
						(effects
							(font
								(size 1.27 1.27)
							)
						)
					)
					(number "F25"
						(effects
							(font
								(size 1.27 1.27)
							)
						)
					)
				)
				(pin output line
					(at 0 -26.67 0)
					(length 3.81)
					(name "UPHY_REFCLK2_P"
						(effects
							(font
								(size 1.27 1.27)
							)
						)
					)
					(number "F28"
						(effects
							(font
								(size 1.27 1.27)
							)
						)
					)
				)
				(pin output line
					(at 0 -29.21 0)
					(length 3.81)
					(name "UPHY_REFCLK2_N"
						(effects
							(font
								(size 1.27 1.27)
							)
						)
					)
					(number "F29"
						(effects
							(font
								(size 1.27 1.27)
							)
						)
					)
				)
				(pin bidirectional line
					(at 0 -31.75 0)
					(length 3.81)
					(name "UPHY_REFCLK3_P"
						(effects
							(font
								(size 1.27 1.27)
							)
						)
					)
					(number "F32"
						(effects
							(font
								(size 1.27 1.27)
							)
						)
					)
				)
				(pin bidirectional line
					(at 0 -34.29 0)
					(length 3.81)
					(name "UPHY_REFCLK3_N"
						(effects
							(font
								(size 1.27 1.27)
							)
						)
					)
					(number "F33"
						(effects
							(font
								(size 1.27 1.27)
							)
						)
					)
				)
				(pin output line
					(at 0 -36.83 0)
					(length 3.81)
					(name "UPHY_REFCLK4_P"
						(effects
							(font
								(size 1.27 1.27)
							)
						)
					)
					(number "E23"
						(effects
							(font
								(size 1.27 1.27)
							)
						)
					)
				)
				(pin output line
					(at 0 -39.37 0)
					(length 3.81)
					(name "UPHY_REFCLK4_N"
						(effects
							(font
								(size 1.27 1.27)
							)
						)
					)
					(number "E22"
						(effects
							(font
								(size 1.27 1.27)
							)
						)
					)
				)
				(pin bidirectional line
					(at 0 -41.91 0)
					(length 3.81)
					(name "UPHY_REFCLK5_P"
						(effects
							(font
								(size 1.27 1.27)
							)
						)
					)
					(number "E15"
						(effects
							(font
								(size 1.27 1.27)
							)
						)
					)
				)
				(pin bidirectional line
					(at 0 -44.45 0)
					(length 3.81)
					(name "UPHY_REFCLK5_N"
						(effects
							(font
								(size 1.27 1.27)
							)
						)
					)
					(number "E14"
						(effects
							(font
								(size 1.27 1.27)
							)
						)
					)
				)
				(pin output line
					(at 0 -46.99 0)
					(length 3.81)
					(name "UPHY_REFCLK6_P"
						(effects
							(font
								(size 1.27 1.27)
							)
						)
					)
					(number "D49"
						(effects
							(font
								(size 1.27 1.27)
							)
						)
					)
				)
				(pin output line
					(at 0 -49.53 0)
					(length 3.81)
					(name "UPHY_REFCLK6_N"
						(effects
							(font
								(size 1.27 1.27)
							)
						)
					)
					(number "D48"
						(effects
							(font
								(size 1.27 1.27)
							)
						)
					)
				)
				(pin bidirectional line
					(at 46.99 0 180)
					(length 3.81)
					(name "USB2_P"
						(effects
							(font
								(size 1.27 1.27)
							)
						)
					)
					(number "A10"
						(effects
							(font
								(size 1.27 1.27)
							)
						)
					)
				)
				(pin bidirectional line
					(at 46.99 -2.54 180)
					(length 3.81)
					(name "USB2_N"
						(effects
							(font
								(size 1.27 1.27)
							)
						)
					)
					(number "A11"
						(effects
							(font
								(size 1.27 1.27)
							)
						)
					)
				)
				(pin bidirectional line
					(at 46.99 -6.35 180)
					(length 3.81)
					(name "USB3_P"
						(effects
							(font
								(size 1.27 1.27)
							)
						)
					)
					(number "G11"
						(effects
							(font
								(size 1.27 1.27)
							)
						)
					)
				)
				(pin bidirectional line
					(at 46.99 -8.89 180)
					(length 3.81)
					(name "USB3_N"
						(effects
							(font
								(size 1.27 1.27)
							)
						)
					)
					(number "G10"
						(effects
							(font
								(size 1.27 1.27)
							)
						)
					)
				)
				(pin passive line
					(at 46.99 -12.7 180)
					(length 3.81)
					(name "GPIO22"
						(effects
							(font
								(size 1.27 1.27)
							)
						)
					)
					(number "F54"
						(effects
							(font
								(size 1.27 1.27)
							)
						)
					)
				)
				(pin passive line
					(at 46.99 -15.24 180)
					(length 3.81)
					(name "GPIO23"
						(effects
							(font
								(size 1.27 1.27)
							)
						)
					)
					(number "G55"
						(effects
							(font
								(size 1.27 1.27)
							)
						)
					)
				)
				(pin bidirectional line
					(at 46.99 -20.32 180)
					(length 3.81)
					(name "PEX_C1_CLKREQ_N"
						(effects
							(font
								(size 1.27 1.27)
							)
						)
					)
					(number "B37"
						(effects
							(font
								(size 1.27 1.27)
							)
						)
					)
				)
				(pin bidirectional line
					(at 46.99 -22.86 180)
					(length 3.81)
					(name "PEX_C2_CLKREQ_N"
						(effects
							(font
								(size 1.27 1.27)
							)
						)
					)
					(number "E11"
						(effects
							(font
								(size 1.27 1.27)
							)
						)
					)
				)
				(pin bidirectional line
					(at 46.99 -25.4 180)
					(length 3.81)
					(name "PEX_C3_CLKREQ_N"
						(effects
							(font
								(size 1.27 1.27)
							)
						)
					)
					(number "G8"
						(effects
							(font
								(size 1.27 1.27)
							)
						)
					)
				)
				(pin bidirectional line
					(at 46.99 -27.94 180)
					(length 3.81)
					(name "PEX_C4_CLKREQ_N"
						(effects
							(font
								(size 1.27 1.27)
							)
						)
					)
					(number "C8"
						(effects
							(font
								(size 1.27 1.27)
							)
						)
					)
				)
				(pin bidirectional line
					(at 46.99 -30.48 180)
					(length 3.81)
					(name "PEX_C5_CLKREQ_N"
						(effects
							(font
								(size 1.27 1.27)
							)
						)
					)
					(number "L19"
						(effects
							(font
								(size 1.27 1.27)
							)
						)
					)
				)
				(pin output line
					(at 46.99 -35.56 180)
					(length 3.81)
					(name "PEX_C1_RST_N"
						(effects
							(font
								(size 1.27 1.27)
							)
						)
					)
					(number "B36"
						(effects
							(font
								(size 1.27 1.27)
							)
						)
					)
				)
				(pin output line
					(at 46.99 -38.1 180)
					(length 3.81)
					(name "PEX_C2_RST_N"
						(effects
							(font
								(size 1.27 1.27)
							)
						)
					)
					(number "D10"
						(effects
							(font
								(size 1.27 1.27)
							)
						)
					)
				)
				(pin output line
					(at 46.99 -40.64 180)
					(length 3.81)
					(name "PEX_C3_RST_N"
						(effects
							(font
								(size 1.27 1.27)
							)
						)
					)
					(number "J9"
						(effects
							(font
								(size 1.27 1.27)
							)
						)
					)
				)
				(pin output line
					(at 46.99 -43.18 180)
					(length 3.81)
					(name "PEX_C4_RST_N"
						(effects
							(font
								(size 1.27 1.27)
							)
						)
					)
					(number "H10"
						(effects
							(font
								(size 1.27 1.27)
							)
						)
					)
				)
				(pin output line
					(at 46.99 -45.72 180)
					(length 3.81)
					(name "PEX_C5_RST_N"
						(effects
							(font
								(size 1.27 1.27)
							)
						)
					)
					(number "L18"
						(effects
							(font
								(size 1.27 1.27)
							)
						)
					)
				)
				(pin input line
					(at 46.99 -49.53 180)
					(length 3.81)
					(name "PEX_WAKE_N"
						(effects
							(font
								(size 1.27 1.27)
							)
						)
					)
					(number "A8"
						(effects
							(font
								(size 1.27 1.27)
							)
						)
					)
				)
				(pin passive line
					(at 46.99 -54.61 180)
					(length 3.81)
					(name "GPIO25"
						(effects
							(font
								(size 1.27 1.27)
							)
						)
					)
					(number "K49"
						(effects
							(font
								(size 1.27 1.27)
							)
						)
					)
					(alternate "XFI0_MDIO" passive line)
				)
				(pin passive line
					(at 46.99 -57.15 180)
					(length 3.81)
					(name "GPIO26"
						(effects
							(font
								(size 1.27 1.27)
							)
						)
					)
					(number "H51"
						(effects
							(font
								(size 1.27 1.27)
							)
						)
					)
					(alternate "XFI0_MDC" passive line)
				)
			)
			(symbol "Hermaphroditic_Molex_203456-0003_CUSTOM_Jetson_AGX_Thor_H8mm_4_1"
				(rectangle
					(start 3.81 2.54)
					(end 36.83 -43.18)
					(stroke
						(width 0.254)
						(type default)
					)
					(fill
						(type background)
					)
				)
				(pin bidirectional line
					(at 0 0 0)
					(length 3.81)
					(name "I2C0_CLK"
						(effects
							(font
								(size 1.27 1.27)
							)
						)
					)
					(number "J52"
						(effects
							(font
								(size 1.27 1.27)
							)
						)
					)
				)
				(pin bidirectional line
					(at 0 -2.54 0)
					(length 3.81)
					(name "I2C0_DAT"
						(effects
							(font
								(size 1.27 1.27)
							)
						)
					)
					(number "J53"
						(effects
							(font
								(size 1.27 1.27)
							)
						)
					)
				)
				(pin bidirectional line
					(at 0 -6.35 0)
					(length 3.81)
					(name "I2C1_CLK"
						(effects
							(font
								(size 1.27 1.27)
							)
						)
					)
					(number "K5"
						(effects
							(font
								(size 1.27 1.27)
							)
						)
					)
				)
				(pin bidirectional line
					(at 0 -8.89 0)
					(length 3.81)
					(name "I2C1_DAT"
						(effects
							(font
								(size 1.27 1.27)
							)
						)
					)
					(number "L8"
						(effects
							(font
								(size 1.27 1.27)
							)
						)
					)
				)
				(pin bidirectional line
					(at 0 -12.7 0)
					(length 3.81)
					(name "I2C2_CLK"
						(effects
							(font
								(size 1.27 1.27)
							)
						)
					)
					(number "J61"
						(effects
							(font
								(size 1.27 1.27)
							)
						)
					)
				)
				(pin bidirectional line
					(at 0 -15.24 0)
					(length 3.81)
					(name "I2C2_DAT"
						(effects
							(font
								(size 1.27 1.27)
							)
						)
					)
					(number "K61"
						(effects
							(font
								(size 1.27 1.27)
							)
						)
					)
				)
				(pin bidirectional line
					(at 0 -19.05 0)
					(length 3.81)
					(name "I2C3_CLK"
						(effects
							(font
								(size 1.27 1.27)
							)
						)
					)
					(number "F53"
						(effects
							(font
								(size 1.27 1.27)
							)
						)
					)
				)
				(pin bidirectional line
					(at 0 -21.59 0)
					(length 3.81)
					(name "I2C3_DAT"
						(effects
							(font
								(size 1.27 1.27)
							)
						)
					)
					(number "E53"
						(effects
							(font
								(size 1.27 1.27)
							)
						)
					)
				)
				(pin bidirectional line
					(at 0 -25.4 0)
					(length 3.81)
					(name "I2C4_CLK"
						(effects
							(font
								(size 1.27 1.27)
							)
						)
					)
					(number "D61"
						(effects
							(font
								(size 1.27 1.27)
							)
						)
					)
				)
				(pin bidirectional line
					(at 0 -27.94 0)
					(length 3.81)
					(name "I2C4_DAT"
						(effects
							(font
								(size 1.27 1.27)
							)
						)
					)
					(number "E60"
						(effects
							(font
								(size 1.27 1.27)
							)
						)
					)
				)
				(pin bidirectional line
					(at 0 -31.75 0)
					(length 3.81)
					(name "I2C5_CLK"
						(effects
							(font
								(size 1.27 1.27)
							)
						)
					)
					(number "A53"
						(effects
							(font
								(size 1.27 1.27)
							)
						)
					)
				)
				(pin bidirectional line
					(at 0 -34.29 0)
					(length 3.81)
					(name "I2C5_DAT"
						(effects
							(font
								(size 1.27 1.27)
							)
						)
					)
					(number "C53"
						(effects
							(font
								(size 1.27 1.27)
							)
						)
					)
				)
				(pin passive line
					(at 40.64 0 180)
					(length 3.81)
					(name "FSI_GPIO28"
						(effects
							(font
								(size 1.27 1.27)
							)
						)
					)
					(number "K10"
						(effects
							(font
								(size 1.27 1.27)
							)
						)
					)
					(alternate "I2C6_CLK" passive line)
				)
				(pin passive line
					(at 40.64 -2.54 180)
					(length 3.81)
					(name "FSI_GPIO29"
						(effects
							(font
								(size 1.27 1.27)
							)
						)
					)
					(number "J11"
						(effects
							(font
								(size 1.27 1.27)
							)
						)
					)
					(alternate "I2C6_DAT" passive line)
				)
				(pin bidirectional line
					(at 40.64 -6.35 180)
					(length 3.81)
					(name "I2C7_CLK"
						(effects
							(font
								(size 1.27 1.27)
							)
						)
					)
					(number "E27"
						(effects
							(font
								(size 1.27 1.27)
							)
						)
					)
				)
				(pin bidirectional line
					(at 40.64 -8.89 180)
					(length 3.81)
					(name "I2C7_DAT"
						(effects
							(font
								(size 1.27 1.27)
							)
						)
					)
					(number "E26"
						(effects
							(font
								(size 1.27 1.27)
							)
						)
					)
				)
				(pin bidirectional line
					(at 40.64 -12.7 180)
					(length 3.81)
					(name "I2C8_CLK"
						(effects
							(font
								(size 1.27 1.27)
							)
						)
					)
					(number "F52"
						(effects
							(font
								(size 1.27 1.27)
							)
						)
					)
				)
				(pin bidirectional line
					(at 40.64 -15.24 180)
					(length 3.81)
					(name "I2C8_DAT"
						(effects
							(font
								(size 1.27 1.27)
							)
						)
					)
					(number "F51"
						(effects
							(font
								(size 1.27 1.27)
							)
						)
					)
				)
				(pin bidirectional line
					(at 40.64 -19.05 180)
					(length 3.81)
					(name "I2C9_CLK"
						(effects
							(font
								(size 1.27 1.27)
							)
						)
					)
					(number "A55"
						(effects
							(font
								(size 1.27 1.27)
							)
						)
					)
				)
				(pin bidirectional line
					(at 40.64 -21.59 180)
					(length 3.81)
					(name "I2C9_DAT"
						(effects
							(font
								(size 1.27 1.27)
							)
						)
					)
					(number "J55"
						(effects
							(font
								(size 1.27 1.27)
							)
						)
					)
				)
				(pin bidirectional line
					(at 40.64 -25.4 180)
					(length 3.81)
					(name "I2C10_CLK"
						(effects
							(font
								(size 1.27 1.27)
							)
						)
					)
					(number "A47"
						(effects
							(font
								(size 1.27 1.27)
							)
						)
					)
				)
				(pin bidirectional line
					(at 40.64 -27.94 180)
					(length 3.81)
					(name "I2C10_DAT"
						(effects
							(font
								(size 1.27 1.27)
							)
						)
					)
					(number "A48"
						(effects
							(font
								(size 1.27 1.27)
							)
						)
					)
				)
				(pin bidirectional line
					(at 40.64 -31.75 180)
					(length 3.81)
					(name "MCLK04"
						(effects
							(font
								(size 1.27 1.27)
							)
						)
					)
					(number "H55"
						(effects
							(font
								(size 1.27 1.27)
							)
						)
					)
				)
				(pin bidirectional line
					(at 40.64 -34.29 180)
					(length 3.81)
					(name "MCLK05"
						(effects
							(font
								(size 1.27 1.27)
							)
						)
					)
					(number "L57"
						(effects
							(font
								(size 1.27 1.27)
							)
						)
					)
				)
				(pin bidirectional line
					(at 40.64 -38.1 180)
					(length 3.81)
					(name "VM_I2C_SCK"
						(effects
							(font
								(size 1.27 1.27)
							)
						)
					)
					(number "L44"
						(effects
							(font
								(size 1.27 1.27)
							)
						)
					)
				)
				(pin bidirectional line
					(at 40.64 -40.64 180)
					(length 3.81)
					(name "VM_I2C_DAT"
						(effects
							(font
								(size 1.27 1.27)
							)
						)
					)
					(number "L45"
						(effects
							(font
								(size 1.27 1.27)
							)
						)
					)
				)
			)
			(symbol "Hermaphroditic_Molex_203456-0003_CUSTOM_Jetson_AGX_Thor_H8mm_5_1"
				(rectangle
					(start 3.81 2.54)
					(end 39.37 -104.14)
					(stroke
						(width 0.254)
						(type default)
					)
					(fill
						(type background)
					)
				)
				(polyline
					(pts
						(xy 3.81 -2.54) (xy 39.37 -2.54)
					)
					(stroke
						(width 0.254)
						(type default)
					)
					(fill
						(type background)
					)
				)
				(polyline
					(pts
						(xy 3.81 -27.94) (xy 39.37 -27.94)
					)
					(stroke
						(width 0.254)
						(type default)
					)
					(fill
						(type background)
					)
				)
				(polyline
					(pts
						(xy 3.81 -53.34) (xy 39.37 -53.34)
					)
					(stroke
						(width 0.254)
						(type default)
					)
					(fill
						(type background)
					)
				)
				(polyline
					(pts
						(xy 3.81 -78.74) (xy 39.37 -78.74)
					)
					(stroke
						(width 0.254)
						(type default)
					)
					(fill
						(type background)
					)
				)
				(text "Display Port 3"
					(at 14.732 -80.772 0)
					(effects
						(font
							(size 1.27 1.27)
							(thickness 0.15)
						)
						(justify left bottom)
					)
				)
				(text "Display Port 0"
					(at 14.986 -4.572 0)
					(effects
						(font
							(size 1.27 1.27)
							(thickness 0.15)
						)
						(justify left bottom)
					)
				)
				(text "Display Port 1\n"
					(at 14.986 -29.972 0)
					(effects
						(font
							(size 1.27 1.27)
							(thickness 0.15)
						)
						(justify left bottom)
					)
				)
				(text "Display Port 2"
					(at 14.986 -55.372 0)
					(effects
						(font
							(size 1.27 1.27)
							(thickness 0.15)
						)
						(justify left bottom)
					)
				)
				(pin bidirectional line
					(at 0 0 0)
					(length 3.81)
					(name "HDMI_CEC"
						(effects
							(font
								(size 1.27 1.27)
							)
						)
					)
					(number "J50"
						(effects
							(font
								(size 1.27 1.27)
							)
						)
					)
				)
				(pin output line
					(at 0 -6.35 0)
					(length 3.81)
					(name "DP0_D0_HDMI_D2_P"
						(effects
							(font
								(size 1.27 1.27)
							)
						)
					)
					(number "D51"
						(effects
							(font
								(size 1.27 1.27)
							)
						)
					)
				)
				(pin output line
					(at 0 -8.89 0)
					(length 3.81)
					(name "DP0_D0_HDMI_D2_N"
						(effects
							(font
								(size 1.27 1.27)
							)
						)
					)
					(number "D52"
						(effects
							(font
								(size 1.27 1.27)
							)
						)
					)
				)
				(pin output line
					(at 0 -11.43 0)
					(length 3.81)
					(name "DP0_D1_HDMI_D1_P"
						(effects
							(font
								(size 1.27 1.27)
							)
						)
					)
					(number "B51"
						(effects
							(font
								(size 1.27 1.27)
							)
						)
					)
				)
				(pin output line
					(at 0 -13.97 0)
					(length 3.81)
					(name "DP0_D1_HDMI_D1_N"
						(effects
							(font
								(size 1.27 1.27)
							)
						)
					)
					(number "B52"
						(effects
							(font
								(size 1.27 1.27)
							)
						)
					)
				)
				(pin output line
					(at 0 -16.51 0)
					(length 3.81)
					(name "DP0_D2_HDMI_D0_P"
						(effects
							(font
								(size 1.27 1.27)
							)
						)
					)
					(number "A51"
						(effects
							(font
								(size 1.27 1.27)
							)
						)
					)
				)
				(pin output line
					(at 0 -19.05 0)
					(length 3.81)
					(name "DP0_D2_HDMI_D0_N"
						(effects
							(font
								(size 1.27 1.27)
							)
						)
					)
					(number "A50"
						(effects
							(font
								(size 1.27 1.27)
							)
						)
					)
				)
				(pin output line
					(at 0 -21.59 0)
					(length 3.81)
					(name "DP0_D3_HDMI_CK_P"
						(effects
							(font
								(size 1.27 1.27)
							)
						)
					)
					(number "C51"
						(effects
							(font
								(size 1.27 1.27)
							)
						)
					)
				)
				(pin output line
					(at 0 -24.13 0)
					(length 3.81)
					(name "DP0_D3_HDMI_CK_N"
						(effects
							(font
								(size 1.27 1.27)
							)
						)
					)
					(number "C50"
						(effects
							(font
								(size 1.27 1.27)
							)
						)
					)
				)
				(pin output line
					(at 0 -31.75 0)
					(length 3.81)
					(name "DP1_D0_HDMI_D2_P"
						(effects
							(font
								(size 1.27 1.27)
							)
						)
					)
					(number "H49"
						(effects
							(font
								(size 1.27 1.27)
							)
						)
					)
				)
				(pin output line
					(at 0 -34.29 0)
					(length 3.81)
					(name "DP1_D0_HDMI_D2_N"
						(effects
							(font
								(size 1.27 1.27)
							)
						)
					)
					(number "H48"
						(effects
							(font
								(size 1.27 1.27)
							)
						)
					)
				)
				(pin output line
					(at 0 -36.83 0)
					(length 3.81)
					(name "DP1_D1_HDMI_D1_P"
						(effects
							(font
								(size 1.27 1.27)
							)
						)
					)
					(number "G51"
						(effects
							(font
								(size 1.27 1.27)
							)
						)
					)
				)
				(pin output line
					(at 0 -39.37 0)
					(length 3.81)
					(name "DP1_D1_HDMI_D1_N"
						(effects
							(font
								(size 1.27 1.27)
							)
						)
					)
					(number "G50"
						(effects
							(font
								(size 1.27 1.27)
							)
						)
					)
				)
				(pin output line
					(at 0 -41.91 0)
					(length 3.81)
					(name "DP1_D2_HDMI_D0_P"
						(effects
							(font
								(size 1.27 1.27)
							)
						)
					)
					(number "J47"
						(effects
							(font
								(size 1.27 1.27)
							)
						)
					)
				)
				(pin output line
					(at 0 -44.45 0)
					(length 3.81)
					(name "DP1_D2_HDMI_D0_N"
						(effects
							(font
								(size 1.27 1.27)
							)
						)
					)
					(number "J48"
						(effects
							(font
								(size 1.27 1.27)
							)
						)
					)
				)
				(pin output line
					(at 0 -46.99 0)
					(length 3.81)
					(name "DP1_D3_HDMI_CK_P"
						(effects
							(font
								(size 1.27 1.27)
							)
						)
					)
					(number "K46"
						(effects
							(font
								(size 1.27 1.27)
							)
						)
					)
				)
				(pin output line
					(at 0 -49.53 0)
					(length 3.81)
					(name "DP1_D3_HDMI_CK_N"
						(effects
							(font
								(size 1.27 1.27)
							)
						)
					)
					(number "K47"
						(effects
							(font
								(size 1.27 1.27)
							)
						)
					)
				)
				(pin output line
					(at 0 -57.15 0)
					(length 3.81)
					(name "DP2_D0_HDMI_D2_P"
						(effects
							(font
								(size 1.27 1.27)
							)
						)
					)
					(number "A15"
						(effects
							(font
								(size 1.27 1.27)
							)
						)
					)
				)
				(pin output line
					(at 0 -59.69 0)
					(length 3.81)
					(name "DP2_D0_HDMI_D2_N"
						(effects
							(font
								(size 1.27 1.27)
							)
						)
					)
					(number "A14"
						(effects
							(font
								(size 1.27 1.27)
							)
						)
					)
				)
				(pin output line
					(at 0 -62.23 0)
					(length 3.81)
					(name "DP2_D1_HDMI_D1_P"
						(effects
							(font
								(size 1.27 1.27)
							)
						)
					)
					(number "J14"
						(effects
							(font
								(size 1.27 1.27)
							)
						)
					)
				)
				(pin output line
					(at 0 -64.77 0)
					(length 3.81)
					(name "DP2_D1_HDMI_D1_N"
						(effects
							(font
								(size 1.27 1.27)
							)
						)
					)
					(number "J15"
						(effects
							(font
								(size 1.27 1.27)
							)
						)
					)
				)
				(pin output line
					(at 0 -67.31 0)
					(length 3.81)
					(name "DP2_D2_HDMI_D0_P"
						(effects
							(font
								(size 1.27 1.27)
							)
						)
					)
					(number "C15"
						(effects
							(font
								(size 1.27 1.27)
							)
						)
					)
				)
				(pin output line
					(at 0 -69.85 0)
					(length 3.81)
					(name "DP2_D2_HDMI_D0_N"
						(effects
							(font
								(size 1.27 1.27)
							)
						)
					)
					(number "C14"
						(effects
							(font
								(size 1.27 1.27)
							)
						)
					)
				)
				(pin output line
					(at 0 -72.39 0)
					(length 3.81)
					(name "DP2_D3_HDMI_CK_P"
						(effects
							(font
								(size 1.27 1.27)
							)
						)
					)
					(number "G15"
						(effects
							(font
								(size 1.27 1.27)
							)
						)
					)
				)
				(pin output line
					(at 0 -74.93 0)
					(length 3.81)
					(name "DP2_D3_HDMI_CK_N"
						(effects
							(font
								(size 1.27 1.27)
							)
						)
					)
					(number "G14"
						(effects
							(font
								(size 1.27 1.27)
							)
						)
					)
				)
				(pin output line
					(at 0 -82.55 0)
					(length 3.81)
					(name "DP3_D0_HDMI_D2_P"
						(effects
							(font
								(size 1.27 1.27)
							)
						)
					)
					(number "D33"
						(effects
							(font
								(size 1.27 1.27)
							)
						)
					)
				)
				(pin output line
					(at 0 -85.09 0)
					(length 3.81)
					(name "DP3_D0_HDMI_D2_N"
						(effects
							(font
								(size 1.27 1.27)
							)
						)
					)
					(number "D32"
						(effects
							(font
								(size 1.27 1.27)
							)
						)
					)
				)
				(pin output line
					(at 0 -87.63 0)
					(length 3.81)
					(name "DP3_D1_HDMI_D1_P"
						(effects
							(font
								(size 1.27 1.27)
							)
						)
					)
					(number "J35"
						(effects
							(font
								(size 1.27 1.27)
							)
						)
					)
				)
				(pin output line
					(at 0 -90.17 0)
					(length 3.81)
					(name "DP3_D1_HDMI_D1_N"
						(effects
							(font
								(size 1.27 1.27)
							)
						)
					)
					(number "J34"
						(effects
							(font
								(size 1.27 1.27)
							)
						)
					)
				)
				(pin output line
					(at 0 -92.71 0)
					(length 3.81)
					(name "DP3_D2_HDMI_D0_P"
						(effects
							(font
								(size 1.27 1.27)
							)
						)
					)
					(number "A34"
						(effects
							(font
								(size 1.27 1.27)
							)
						)
					)
				)
				(pin output line
					(at 0 -95.25 0)
					(length 3.81)
					(name "DP3_D2_HDMI_D0_N"
						(effects
							(font
								(size 1.27 1.27)
							)
						)
					)
					(number "A35"
						(effects
							(font
								(size 1.27 1.27)
							)
						)
					)
				)
				(pin output line
					(at 0 -97.79 0)
					(length 3.81)
					(name "DP3_D3_HDMI_CK_P"
						(effects
							(font
								(size 1.27 1.27)
							)
						)
					)
					(number "H32"
						(effects
							(font
								(size 1.27 1.27)
							)
						)
					)
				)
				(pin output line
					(at 0 -100.33 0)
					(length 3.81)
					(name "DP3_D3_HDMI_CK_N"
						(effects
							(font
								(size 1.27 1.27)
							)
						)
					)
					(number "H33"
						(effects
							(font
								(size 1.27 1.27)
							)
						)
					)
				)
				(pin bidirectional line
					(at 43.18 -6.35 180)
					(length 3.81)
					(name "HPD0"
						(effects
							(font
								(size 1.27 1.27)
							)
						)
					)
					(number "K50"
						(effects
							(font
								(size 1.27 1.27)
							)
						)
					)
				)
				(pin bidirectional line
					(at 43.18 -21.59 180)
					(length 3.81)
					(name "DP_AUX_CH0_P"
						(effects
							(font
								(size 1.27 1.27)
							)
						)
					)
					(number "G53"
						(effects
							(font
								(size 1.27 1.27)
							)
						)
					)
				)
				(pin bidirectional line
					(at 43.18 -24.13 180)
					(length 3.81)
					(name "DP_AUX_CH0_N"
						(effects
							(font
								(size 1.27 1.27)
							)
						)
					)
					(number "G54"
						(effects
							(font
								(size 1.27 1.27)
							)
						)
					)
				)
				(pin bidirectional line
					(at 43.18 -31.75 180)
					(length 3.81)
					(name "HPD1"
						(effects
							(font
								(size 1.27 1.27)
							)
						)
					)
					(number "C18"
						(effects
							(font
								(size 1.27 1.27)
							)
						)
					)
				)
				(pin bidirectional line
					(at 43.18 -46.99 180)
					(length 3.81)
					(name "DP_AUX_CH1_P"
						(effects
							(font
								(size 1.27 1.27)
							)
						)
					)
					(number "D16"
						(effects
							(font
								(size 1.27 1.27)
							)
						)
					)
				)
				(pin bidirectional line
					(at 43.18 -49.53 180)
					(length 3.81)
					(name "DP_AUX_CH1_N"
						(effects
							(font
								(size 1.27 1.27)
							)
						)
					)
					(number "D17"
						(effects
							(font
								(size 1.27 1.27)
							)
						)
					)
				)
				(pin bidirectional line
					(at 43.18 -57.15 180)
					(length 3.81)
					(name "HPD2"
						(effects
							(font
								(size 1.27 1.27)
							)
						)
					)
					(number "A19"
						(effects
							(font
								(size 1.27 1.27)
							)
						)
					)
				)
				(pin bidirectional line
					(at 43.18 -72.39 180)
					(length 3.81)
					(name "DP_AUX_CH2_P"
						(effects
							(font
								(size 1.27 1.27)
							)
						)
					)
					(number "E19"
						(effects
							(font
								(size 1.27 1.27)
							)
						)
					)
				)
				(pin bidirectional line
					(at 43.18 -74.93 180)
					(length 3.81)
					(name "DP_AUX_CH2_N"
						(effects
							(font
								(size 1.27 1.27)
							)
						)
					)
					(number "E18"
						(effects
							(font
								(size 1.27 1.27)
							)
						)
					)
				)
				(pin bidirectional line
					(at 43.18 -82.55 180)
					(length 3.81)
					(name "HPD3"
						(effects
							(font
								(size 1.27 1.27)
							)
						)
					)
					(number "C19"
						(effects
							(font
								(size 1.27 1.27)
							)
						)
					)
				)
				(pin bidirectional line
					(at 43.18 -97.79 180)
					(length 3.81)
					(name "DP_AUX_CH3_P"
						(effects
							(font
								(size 1.27 1.27)
							)
						)
					)
					(number "F20"
						(effects
							(font
								(size 1.27 1.27)
							)
						)
					)
				)
				(pin bidirectional line
					(at 43.18 -100.33 180)
					(length 3.81)
					(name "DP_AUX_CH3_N"
						(effects
							(font
								(size 1.27 1.27)
							)
						)
					)
					(number "F21"
						(effects
							(font
								(size 1.27 1.27)
							)
						)
					)
				)
			)
			(symbol "Hermaphroditic_Molex_203456-0003_CUSTOM_Jetson_AGX_Thor_H8mm_6_1"
				(rectangle
					(start 3.81 2.54)
					(end 30.48 -64.77)
					(stroke
						(width 0.254)
						(type default)
					)
					(fill
						(type background)
					)
				)
				(pin input line
					(at 0 0 0)
					(length 3.81)
					(name "CSI0_CLK_P"
						(effects
							(font
								(size 1.27 1.27)
							)
						)
					)
					(number "F43"
						(effects
							(font
								(size 1.27 1.27)
							)
						)
					)
				)
				(pin input line
					(at 0 -2.54 0)
					(length 3.81)
					(name "CSI0_CLK_N"
						(effects
							(font
								(size 1.27 1.27)
							)
						)
					)
					(number "F42"
						(effects
							(font
								(size 1.27 1.27)
							)
						)
					)
				)
				(pin input line
					(at 0 -5.08 0)
					(length 3.81)
					(name "CSI0_D0_P"
						(effects
							(font
								(size 1.27 1.27)
							)
						)
					)
					(number "E42"
						(effects
							(font
								(size 1.27 1.27)
							)
						)
					)
				)
				(pin input line
					(at 0 -7.62 0)
					(length 3.81)
					(name "CSI0_D0_N"
						(effects
							(font
								(size 1.27 1.27)
							)
						)
					)
					(number "E41"
						(effects
							(font
								(size 1.27 1.27)
							)
						)
					)
				)
				(pin input line
					(at 0 -10.16 0)
					(length 3.81)
					(name "CSI0_D1_P"
						(effects
							(font
								(size 1.27 1.27)
							)
						)
					)
					(number "E39"
						(effects
							(font
								(size 1.27 1.27)
							)
						)
					)
				)
				(pin input line
					(at 0 -12.7 0)
					(length 3.81)
					(name "CSI0_D1_N"
						(effects
							(font
								(size 1.27 1.27)
							)
						)
					)
					(number "E38"
						(effects
							(font
								(size 1.27 1.27)
							)
						)
					)
				)
				(pin input line
					(at 0 -16.51 0)
					(length 3.81)
					(name "CSI1_CLK_P"
						(effects
							(font
								(size 1.27 1.27)
							)
						)
					)
					(number "H43"
						(effects
							(font
								(size 1.27 1.27)
							)
						)
					)
				)
				(pin input line
					(at 0 -19.05 0)
					(length 3.81)
					(name "CSI1_CLK_N"
						(effects
							(font
								(size 1.27 1.27)
							)
						)
					)
					(number "H42"
						(effects
							(font
								(size 1.27 1.27)
							)
						)
					)
				)
				(pin input line
					(at 0 -21.59 0)
					(length 3.81)
					(name "CSI1_D0_P"
						(effects
							(font
								(size 1.27 1.27)
							)
						)
					)
					(number "G41"
						(effects
							(font
								(size 1.27 1.27)
							)
						)
					)
				)
				(pin input line
					(at 0 -24.13 0)
					(length 3.81)
					(name "CSI1_D0_N"
						(effects
							(font
								(size 1.27 1.27)
							)
						)
					)
					(number "G42"
						(effects
							(font
								(size 1.27 1.27)
							)
						)
					)
				)
				(pin input line
					(at 0 -26.67 0)
					(length 3.81)
					(name "CSI1_D1_P"
						(effects
							(font
								(size 1.27 1.27)
							)
						)
					)
					(number "J41"
						(effects
							(font
								(size 1.27 1.27)
							)
						)
					)
				)
				(pin input line
					(at 0 -29.21 0)
					(length 3.81)
					(name "CSI1_D1_N"
						(effects
							(font
								(size 1.27 1.27)
							)
						)
					)
					(number "J42"
						(effects
							(font
								(size 1.27 1.27)
							)
						)
					)
				)
				(pin input line
					(at 0 -33.02 0)
					(length 3.81)
					(name "CSI2_CLK_P"
						(effects
							(font
								(size 1.27 1.27)
							)
						)
					)
					(number "B43"
						(effects
							(font
								(size 1.27 1.27)
							)
						)
					)
				)
				(pin input line
					(at 0 -35.56 0)
					(length 3.81)
					(name "CSI2_CLK_N"
						(effects
							(font
								(size 1.27 1.27)
							)
						)
					)
					(number "B42"
						(effects
							(font
								(size 1.27 1.27)
							)
						)
					)
				)
				(pin input line
					(at 0 -38.1 0)
					(length 3.81)
					(name "CSI2_D0_P"
						(effects
							(font
								(size 1.27 1.27)
							)
						)
					)
					(number "A41"
						(effects
							(font
								(size 1.27 1.27)
							)
						)
					)
				)
				(pin input line
					(at 0 -40.64 0)
					(length 3.81)
					(name "CSI2_D0_N"
						(effects
							(font
								(size 1.27 1.27)
							)
						)
					)
					(number "A42"
						(effects
							(font
								(size 1.27 1.27)
							)
						)
					)
				)
				(pin input line
					(at 0 -43.18 0)
					(length 3.81)
					(name "CSI2_D1_P"
						(effects
							(font
								(size 1.27 1.27)
							)
						)
					)
					(number "C42"
						(effects
							(font
								(size 1.27 1.27)
							)
						)
					)
				)
				(pin input line
					(at 0 -45.72 0)
					(length 3.81)
					(name "CSI2_D1_N"
						(effects
							(font
								(size 1.27 1.27)
							)
						)
					)
					(number "C41"
						(effects
							(font
								(size 1.27 1.27)
							)
						)
					)
				)
				(pin input line
					(at 0 -49.53 0)
					(length 3.81)
					(name "CSI3_CLK_P"
						(effects
							(font
								(size 1.27 1.27)
							)
						)
					)
					(number "F46"
						(effects
							(font
								(size 1.27 1.27)
							)
						)
					)
				)
				(pin input line
					(at 0 -52.07 0)
					(length 3.81)
					(name "CSI3_CLK_N"
						(effects
							(font
								(size 1.27 1.27)
							)
						)
					)
					(number "F45"
						(effects
							(font
								(size 1.27 1.27)
							)
						)
					)
				)
				(pin input line
					(at 0 -54.61 0)
					(length 3.81)
					(name "CSI3_D0_P"
						(effects
							(font
								(size 1.27 1.27)
							)
						)
					)
					(number "E45"
						(effects
							(font
								(size 1.27 1.27)
							)
						)
					)
				)
				(pin input line
					(at 0 -57.15 0)
					(length 3.81)
					(name "CSI3_D0_N"
						(effects
							(font
								(size 1.27 1.27)
							)
						)
					)
					(number "E44"
						(effects
							(font
								(size 1.27 1.27)
							)
						)
					)
				)
				(pin input line
					(at 0 -59.69 0)
					(length 3.81)
					(name "CSI3_D1_P"
						(effects
							(font
								(size 1.27 1.27)
							)
						)
					)
					(number "G44"
						(effects
							(font
								(size 1.27 1.27)
							)
						)
					)
				)
				(pin input line
					(at 0 -62.23 0)
					(length 3.81)
					(name "CSI3_D1_N"
						(effects
							(font
								(size 1.27 1.27)
							)
						)
					)
					(number "G45"
						(effects
							(font
								(size 1.27 1.27)
							)
						)
					)
				)
				(pin input line
					(at 34.29 0 180)
					(length 3.81)
					(name "CSI4_CLK_P"
						(effects
							(font
								(size 1.27 1.27)
							)
						)
					)
					(number "F48"
						(effects
							(font
								(size 1.27 1.27)
							)
						)
					)
				)
				(pin input line
					(at 34.29 -2.54 180)
					(length 3.81)
					(name "CSI4_CLK_N"
						(effects
							(font
								(size 1.27 1.27)
							)
						)
					)
					(number "F49"
						(effects
							(font
								(size 1.27 1.27)
							)
						)
					)
				)
				(pin input line
					(at 34.29 -5.08 180)
					(length 3.81)
					(name "CSI4_D0_P"
						(effects
							(font
								(size 1.27 1.27)
							)
						)
					)
					(number "G48"
						(effects
							(font
								(size 1.27 1.27)
							)
						)
					)
				)
				(pin input line
					(at 34.29 -7.62 180)
					(length 3.81)
					(name "CSI4_D0_N"
						(effects
							(font
								(size 1.27 1.27)
							)
						)
					)
					(number "G47"
						(effects
							(font
								(size 1.27 1.27)
							)
						)
					)
				)
				(pin input line
					(at 34.29 -10.16 180)
					(length 3.81)
					(name "CSI4_D1_P"
						(effects
							(font
								(size 1.27 1.27)
							)
						)
					)
					(number "E47"
						(effects
							(font
								(size 1.27 1.27)
							)
						)
					)
				)
				(pin input line
					(at 34.29 -12.7 180)
					(length 3.81)
					(name "CSI4_D1_N"
						(effects
							(font
								(size 1.27 1.27)
							)
						)
					)
					(number "E48"
						(effects
							(font
								(size 1.27 1.27)
							)
						)
					)
				)
				(pin input line
					(at 34.29 -16.51 180)
					(length 3.81)
					(name "CSI5_CLK_P"
						(effects
							(font
								(size 1.27 1.27)
							)
						)
					)
					(number "C44"
						(effects
							(font
								(size 1.27 1.27)
							)
						)
					)
				)
				(pin input line
					(at 34.29 -19.05 180)
					(length 3.81)
					(name "CSI5_CLK_N"
						(effects
							(font
								(size 1.27 1.27)
							)
						)
					)
					(number "C45"
						(effects
							(font
								(size 1.27 1.27)
							)
						)
					)
				)
				(pin input line
					(at 34.29 -21.59 180)
					(length 3.81)
					(name "CSI5_D0_P"
						(effects
							(font
								(size 1.27 1.27)
							)
						)
					)
					(number "D42"
						(effects
							(font
								(size 1.27 1.27)
							)
						)
					)
				)
				(pin input line
					(at 34.29 -24.13 180)
					(length 3.81)
					(name "CSI5_D0_N"
						(effects
							(font
								(size 1.27 1.27)
							)
						)
					)
					(number "D43"
						(effects
							(font
								(size 1.27 1.27)
							)
						)
					)
				)
				(pin input line
					(at 34.29 -26.67 180)
					(length 3.81)
					(name "CSI5_D1_P"
						(effects
							(font
								(size 1.27 1.27)
							)
						)
					)
					(number "D46"
						(effects
							(font
								(size 1.27 1.27)
							)
						)
					)
				)
				(pin input line
					(at 34.29 -29.21 180)
					(length 3.81)
					(name "CSI5_D1_N"
						(effects
							(font
								(size 1.27 1.27)
							)
						)
					)
					(number "D45"
						(effects
							(font
								(size 1.27 1.27)
							)
						)
					)
				)
				(pin input line
					(at 34.29 -33.02 180)
					(length 3.81)
					(name "CSI6_CLK_P"
						(effects
							(font
								(size 1.27 1.27)
							)
						)
					)
					(number "J44"
						(effects
							(font
								(size 1.27 1.27)
							)
						)
					)
				)
				(pin input line
					(at 34.29 -35.56 180)
					(length 3.81)
					(name "CSI6_CLK_N"
						(effects
							(font
								(size 1.27 1.27)
							)
						)
					)
					(number "J45"
						(effects
							(font
								(size 1.27 1.27)
							)
						)
					)
				)
				(pin input line
					(at 34.29 -38.1 180)
					(length 3.81)
					(name "CSI6_D0_P"
						(effects
							(font
								(size 1.27 1.27)
							)
						)
					)
					(number "K44"
						(effects
							(font
								(size 1.27 1.27)
							)
						)
					)
				)
				(pin input line
					(at 34.29 -40.64 180)
					(length 3.81)
					(name "CSI6_D0_N"
						(effects
							(font
								(size 1.27 1.27)
							)
						)
					)
					(number "K43"
						(effects
							(font
								(size 1.27 1.27)
							)
						)
					)
				)
				(pin input line
					(at 34.29 -43.18 180)
					(length 3.81)
					(name "CSI6_D1_P"
						(effects
							(font
								(size 1.27 1.27)
							)
						)
					)
					(number "H46"
						(effects
							(font
								(size 1.27 1.27)
							)
						)
					)
				)
				(pin input line
					(at 34.29 -45.72 180)
					(length 3.81)
					(name "CSI6_D1_N"
						(effects
							(font
								(size 1.27 1.27)
							)
						)
					)
					(number "H45"
						(effects
							(font
								(size 1.27 1.27)
							)
						)
					)
				)
				(pin input line
					(at 34.29 -49.53 180)
					(length 3.81)
					(name "CSI7_CLK_P"
						(effects
							(font
								(size 1.27 1.27)
							)
						)
					)
					(number "B45"
						(effects
							(font
								(size 1.27 1.27)
							)
						)
					)
				)
				(pin input line
					(at 34.29 -52.07 180)
					(length 3.81)
					(name "CSI7_CLK_N"
						(effects
							(font
								(size 1.27 1.27)
							)
						)
					)
					(number "B46"
						(effects
							(font
								(size 1.27 1.27)
							)
						)
					)
				)
				(pin input line
					(at 34.29 -54.61 180)
					(length 3.81)
					(name "CSI7_D0_P"
						(effects
							(font
								(size 1.27 1.27)
							)
						)
					)
					(number "A44"
						(effects
							(font
								(size 1.27 1.27)
							)
						)
					)
				)
				(pin input line
					(at 34.29 -57.15 180)
					(length 3.81)
					(name "CSI7_D0_N"
						(effects
							(font
								(size 1.27 1.27)
							)
						)
					)
					(number "A45"
						(effects
							(font
								(size 1.27 1.27)
							)
						)
					)
				)
				(pin input line
					(at 34.29 -59.69 180)
					(length 3.81)
					(name "CSI7_D1_P"
						(effects
							(font
								(size 1.27 1.27)
							)
						)
					)
					(number "C47"
						(effects
							(font
								(size 1.27 1.27)
							)
						)
					)
				)
				(pin input line
					(at 34.29 -62.23 180)
					(length 3.81)
					(name "CSI7_D1_N"
						(effects
							(font
								(size 1.27 1.27)
							)
						)
					)
					(number "C48"
						(effects
							(font
								(size 1.27 1.27)
							)
						)
					)
				)
			)
			(symbol "Hermaphroditic_Molex_203456-0003_CUSTOM_Jetson_AGX_Thor_H8mm_7_1"
				(rectangle
					(start 3.81 2.54)
					(end 46.99 -22.86)
					(stroke
						(width 0.254)
						(type default)
					)
					(fill
						(type background)
					)
				)
				(pin passive line
					(at 0 0 0)
					(length 3.81)
					(name "FSI_GPIO00"
						(effects
							(font
								(size 1.27 1.27)
							)
						)
					)
					(number "F40"
						(effects
							(font
								(size 1.27 1.27)
							)
						)
					)
				)
				(pin passive line
					(at 0 -2.54 0)
					(length 3.81)
					(name "FSI_GPIO01"
						(effects
							(font
								(size 1.27 1.27)
							)
						)
					)
					(number "D40"
						(effects
							(font
								(size 1.27 1.27)
							)
						)
					)
				)
				(pin passive line
					(at 0 -5.08 0)
					(length 3.81)
					(name "FSI_GPIO02"
						(effects
							(font
								(size 1.27 1.27)
							)
						)
					)
					(number "B40"
						(effects
							(font
								(size 1.27 1.27)
							)
						)
					)
				)
				(pin passive line
					(at 0 -7.62 0)
					(length 3.81)
					(name "FSI_GPIO04"
						(effects
							(font
								(size 1.27 1.27)
							)
						)
					)
					(number "K36"
						(effects
							(font
								(size 1.27 1.27)
							)
						)
					)
				)
				(pin passive line
					(at 0 -10.16 0)
					(length 3.81)
					(name "FSI_GPIO05"
						(effects
							(font
								(size 1.27 1.27)
							)
						)
					)
					(number "J38"
						(effects
							(font
								(size 1.27 1.27)
							)
						)
					)
				)
				(pin passive line
					(at 0 -12.7 0)
					(length 3.81)
					(name "FSI_GPIO06"
						(effects
							(font
								(size 1.27 1.27)
							)
						)
					)
					(number "J39"
						(effects
							(font
								(size 1.27 1.27)
							)
						)
					)
				)
				(pin passive line
					(at 0 -15.24 0)
					(length 3.81)
					(name "FSI_GPIO11"
						(effects
							(font
								(size 1.27 1.27)
							)
						)
					)
					(number "D36"
						(effects
							(font
								(size 1.27 1.27)
							)
						)
					)
				)
				(pin passive line
					(at 0 -17.78 0)
					(length 3.81)
					(name "FSI_GPIO16"
						(effects
							(font
								(size 1.27 1.27)
							)
						)
					)
					(number "B48"
						(effects
							(font
								(size 1.27 1.27)
							)
						)
					)
				)
				(pin passive line
					(at 0 -20.32 0)
					(length 3.81)
					(name "FSI_GPIO17"
						(effects
							(font
								(size 1.27 1.27)
							)
						)
					)
					(number "B49"
						(effects
							(font
								(size 1.27 1.27)
							)
						)
					)
				)
				(pin input line
					(at 50.8 0 180)
					(length 3.81)
					(name "FSI_GPIO20"
						(effects
							(font
								(size 1.27 1.27)
							)
						)
					)
					(number "B9"
						(effects
							(font
								(size 1.27 1.27)
							)
						)
					)
				)
				(pin passive line
					(at 50.8 -2.54 180)
					(length 3.81)
					(name "FSI_GPIO21"
						(effects
							(font
								(size 1.27 1.27)
							)
						)
					)
					(number "J10"
						(effects
							(font
								(size 1.27 1.27)
							)
						)
					)
				)
				(pin passive line
					(at 50.8 -5.08 180)
					(length 3.81)
					(name "FSI_GPIO22"
						(effects
							(font
								(size 1.27 1.27)
							)
						)
					)
					(number "K9"
						(effects
							(font
								(size 1.27 1.27)
							)
						)
					)
				)
				(pin passive line
					(at 50.8 -7.62 180)
					(length 3.81)
					(name "FSI_GPIO23"
						(effects
							(font
								(size 1.27 1.27)
							)
						)
					)
					(number "E31"
						(effects
							(font
								(size 1.27 1.27)
							)
						)
					)
				)
				(pin passive line
					(at 50.8 -10.16 180)
					(length 3.81)
					(name "FSI_GPIO24"
						(effects
							(font
								(size 1.27 1.27)
							)
						)
					)
					(number "E30"
						(effects
							(font
								(size 1.27 1.27)
							)
						)
					)
				)
				(pin bidirectional line
					(at 50.8 -12.7 180)
					(length 3.81)
					(name "FSI_GPIO25"
						(effects
							(font
								(size 1.27 1.27)
							)
						)
					)
					(number "D9"
						(effects
							(font
								(size 1.27 1.27)
							)
						)
					)
				)
				(pin passive line
					(at 50.8 -15.24 180)
					(length 3.81)
					(name "FSI_GPIO26"
						(effects
							(font
								(size 1.27 1.27)
							)
						)
					)
					(number "B5"
						(effects
							(font
								(size 1.27 1.27)
							)
						)
					)
				)
				(pin passive line
					(at 50.8 -17.78 180)
					(length 3.81)
					(name "FSI_GPIO27"
						(effects
							(font
								(size 1.27 1.27)
							)
						)
					)
					(number "K7"
						(effects
							(font
								(size 1.27 1.27)
							)
						)
					)
				)
			)
			(symbol "Hermaphroditic_Molex_203456-0003_CUSTOM_Jetson_AGX_Thor_H8mm_8_1"
				(rectangle
					(start 3.81 2.54)
					(end 39.37 -39.37)
					(stroke
						(width 0.254)
						(type default)
					)
					(fill
						(type background)
					)
				)
				(pin output line
					(at 0 0 0)
					(length 3.81)
					(name "MCLK01"
						(effects
							(font
								(size 1.27 1.27)
							)
						)
					)
					(number "H9"
						(effects
							(font
								(size 1.27 1.27)
							)
						)
					)
				)
				(pin bidirectional line
					(at 0 -3.81 0)
					(length 3.81)
					(name "I2S1_CLK"
						(effects
							(font
								(size 1.27 1.27)
							)
						)
					)
					(number "L14"
						(effects
							(font
								(size 1.27 1.27)
							)
						)
					)
				)
				(pin bidirectional line
					(at 0 -6.35 0)
					(length 3.81)
					(name "I2S1_FS"
						(effects
							(font
								(size 1.27 1.27)
							)
						)
					)
					(number "D8"
						(effects
							(font
								(size 1.27 1.27)
							)
						)
					)
				)
				(pin output line
					(at 0 -8.89 0)
					(length 3.81)
					(name "I2S1_SDOUT"
						(effects
							(font
								(size 1.27 1.27)
							)
						)
					)
					(number "C7"
						(effects
							(font
								(size 1.27 1.27)
							)
						)
					)
				)
				(pin input line
					(at 0 -11.43 0)
					(length 3.81)
					(name "I2S1_SDIN"
						(effects
							(font
								(size 1.27 1.27)
							)
						)
					)
					(number "H8"
						(effects
							(font
								(size 1.27 1.27)
							)
						)
					)
				)
				(pin bidirectional line
					(at 0 -15.24 0)
					(length 3.81)
					(name "I2S2_CLK"
						(effects
							(font
								(size 1.27 1.27)
							)
						)
					)
					(number "G4"
						(effects
							(font
								(size 1.27 1.27)
							)
						)
					)
					(alternate "BOOT_CHAIN_1" passive line)
				)
				(pin bidirectional line
					(at 0 -17.78 0)
					(length 3.81)
					(name "I2S2_FS"
						(effects
							(font
								(size 1.27 1.27)
							)
						)
					)
					(number "E4"
						(effects
							(font
								(size 1.27 1.27)
							)
						)
					)
				)
				(pin output line
					(at 0 -20.32 0)
					(length 3.81)
					(name "I2S2_DOUT"
						(effects
							(font
								(size 1.27 1.27)
							)
						)
					)
					(number "F5"
						(effects
							(font
								(size 1.27 1.27)
							)
						)
					)
				)
				(pin input line
					(at 0 -22.86 0)
					(length 3.81)
					(name "I2S2_DIN"
						(effects
							(font
								(size 1.27 1.27)
							)
						)
					)
					(number "F6"
						(effects
							(font
								(size 1.27 1.27)
							)
						)
					)
				)
				(pin passive line
					(at 0 -26.67 0)
					(length 3.81)
					(name "GPIO61"
						(effects
							(font
								(size 1.27 1.27)
							)
						)
					)
					(number "H16"
						(effects
							(font
								(size 1.27 1.27)
							)
						)
					)
				)
				(pin passive line
					(at 0 -29.21 0)
					(length 3.81)
					(name "GPIO57"
						(effects
							(font
								(size 1.27 1.27)
							)
						)
					)
					(number "G18"
						(effects
							(font
								(size 1.27 1.27)
							)
						)
					)
				)
				(pin passive line
					(at 0 -31.75 0)
					(length 3.81)
					(name "GPIO62"
						(effects
							(font
								(size 1.27 1.27)
							)
						)
					)
					(number "H17"
						(effects
							(font
								(size 1.27 1.27)
							)
						)
					)
				)
				(pin passive line
					(at 0 -34.29 0)
					(length 3.81)
					(name "GPIO58"
						(effects
							(font
								(size 1.27 1.27)
							)
						)
					)
					(number "G19"
						(effects
							(font
								(size 1.27 1.27)
							)
						)
					)
				)
				(pin bidirectional line
					(at 43.18 0 180)
					(length 3.81)
					(name "I2S3_SCLK"
						(effects
							(font
								(size 1.27 1.27)
							)
						)
					)
					(number "C59"
						(effects
							(font
								(size 1.27 1.27)
							)
						)
					)
				)
				(pin bidirectional line
					(at 43.18 -2.54 180)
					(length 3.81)
					(name "I2S3_FS"
						(effects
							(font
								(size 1.27 1.27)
							)
						)
					)
					(number "C60"
						(effects
							(font
								(size 1.27 1.27)
							)
						)
					)
				)
				(pin output line
					(at 43.18 -5.08 180)
					(length 3.81)
					(name "I2S3_DOUT"
						(effects
							(font
								(size 1.27 1.27)
							)
						)
					)
					(number "K59"
						(effects
							(font
								(size 1.27 1.27)
							)
						)
					)
				)
				(pin input line
					(at 43.18 -7.62 180)
					(length 3.81)
					(name "I2S3_DIN"
						(effects
							(font
								(size 1.27 1.27)
							)
						)
					)
					(number "J59"
						(effects
							(font
								(size 1.27 1.27)
							)
						)
					)
				)
				(pin bidirectional line
					(at 43.18 -11.43 180)
					(length 3.81)
					(name "GPIO29"
						(effects
							(font
								(size 1.27 1.27)
							)
						)
					)
					(number "A7"
						(effects
							(font
								(size 1.27 1.27)
							)
						)
					)
				)
				(pin bidirectional line
					(at 43.18 -13.97 180)
					(length 3.81)
					(name "GPIO12"
						(effects
							(font
								(size 1.27 1.27)
							)
						)
					)
					(number "E10"
						(effects
							(font
								(size 1.27 1.27)
							)
						)
					)
				)
				(pin output line
					(at 43.18 -16.51 180)
					(length 3.81)
					(name "GPIO40"
						(effects
							(font
								(size 1.27 1.27)
							)
						)
					)
					(number "C5"
						(effects
							(font
								(size 1.27 1.27)
							)
						)
					)
				)
				(pin input line
					(at 43.18 -19.05 180)
					(length 3.81)
					(name "GPIO11"
						(effects
							(font
								(size 1.27 1.27)
							)
						)
					)
					(number "B8"
						(effects
							(font
								(size 1.27 1.27)
							)
						)
					)
				)
				(pin passive line
					(at 43.18 -22.86 180)
					(length 3.81)
					(name "I2S7_SCLK"
						(effects
							(font
								(size 1.27 1.27)
							)
						)
					)
					(number "L50"
						(effects
							(font
								(size 1.27 1.27)
							)
						)
					)
				)
				(pin input line
					(at 43.18 -25.4 180)
					(length 3.81)
					(name "I2S7_LRCK"
						(effects
							(font
								(size 1.27 1.27)
							)
						)
					)
					(number "L49"
						(effects
							(font
								(size 1.27 1.27)
							)
						)
					)
				)
				(pin output line
					(at 43.18 -27.94 180)
					(length 3.81)
					(name "I2S7_DOUT"
						(effects
							(font
								(size 1.27 1.27)
							)
						)
					)
					(number "L9"
						(effects
							(font
								(size 1.27 1.27)
							)
						)
					)
				)
				(pin input line
					(at 43.18 -30.48 180)
					(length 3.81)
					(name "I2S7_DIN"
						(effects
							(font
								(size 1.27 1.27)
							)
						)
					)
					(number "L48"
						(effects
							(font
								(size 1.27 1.27)
							)
						)
					)
				)
				(pin bidirectional line
					(at 43.18 -34.29 180)
					(length 3.81)
					(name "MCLK02"
						(effects
							(font
								(size 1.27 1.27)
							)
						)
					)
					(number "J54"
						(effects
							(font
								(size 1.27 1.27)
							)
						)
					)
				)
				(pin passive line
					(at 43.18 -36.83 180)
					(length 3.81)
					(name "MCLK03"
						(effects
							(font
								(size 1.27 1.27)
							)
						)
					)
					(number "H53"
						(effects
							(font
								(size 1.27 1.27)
							)
						)
					)
				)
			)
			(symbol "Hermaphroditic_Molex_203456-0003_CUSTOM_Jetson_AGX_Thor_H8mm_9_1"
				(rectangle
					(start 3.81 2.54)
					(end 40.64 -104.14)
					(stroke
						(width 0.254)
						(type default)
					)
					(fill
						(type background)
					)
				)
				(pin bidirectional line
					(at 0 0 0)
					(length 3.81)
					(name "SPI1_CS0_N"
						(effects
							(font
								(size 1.27 1.27)
							)
						)
					)
					(number "E55"
						(effects
							(font
								(size 1.27 1.27)
							)
						)
					)
				)
				(pin bidirectional line
					(at 0 -2.54 0)
					(length 3.81)
					(name "SPI1_CS1_N"
						(effects
							(font
								(size 1.27 1.27)
							)
						)
					)
					(number "B56"
						(effects
							(font
								(size 1.27 1.27)
							)
						)
					)
				)
				(pin bidirectional line
					(at 0 -5.08 0)
					(length 3.81)
					(name "SPI1_CLK"
						(effects
							(font
								(size 1.27 1.27)
							)
						)
					)
					(number "J57"
						(effects
							(font
								(size 1.27 1.27)
							)
						)
					)
				)
				(pin bidirectional line
					(at 0 -7.62 0)
					(length 3.81)
					(name "SPI1_MISO"
						(effects
							(font
								(size 1.27 1.27)
							)
						)
					)
					(number "A56"
						(effects
							(font
								(size 1.27 1.27)
							)
						)
					)
				)
				(pin bidirectional line
					(at 0 -10.16 0)
					(length 3.81)
					(name "SPI1_MOSI"
						(effects
							(font
								(size 1.27 1.27)
							)
						)
					)
					(number "D55"
						(effects
							(font
								(size 1.27 1.27)
							)
						)
					)
				)
				(pin bidirectional line
					(at 0 -13.97 0)
					(length 3.81)
					(name "SPI2_CS0_N"
						(effects
							(font
								(size 1.27 1.27)
							)
						)
					)
					(number "D60"
						(effects
							(font
								(size 1.27 1.27)
							)
						)
					)
				)
				(pin bidirectional line
					(at 0 -16.51 0)
					(length 3.81)
					(name "SPI2_CLK"
						(effects
							(font
								(size 1.27 1.27)
							)
						)
					)
					(number "E61"
						(effects
							(font
								(size 1.27 1.27)
							)
						)
					)
				)
				(pin bidirectional line
					(at 0 -19.05 0)
					(length 3.81)
					(name "SPI2_MISO"
						(effects
							(font
								(size 1.27 1.27)
							)
						)
					)
					(number "D62"
						(effects
							(font
								(size 1.27 1.27)
							)
						)
					)
				)
				(pin bidirectional line
					(at 0 -21.59 0)
					(length 3.81)
					(name "SPI2_MOSI"
						(effects
							(font
								(size 1.27 1.27)
							)
						)
					)
					(number "F60"
						(effects
							(font
								(size 1.27 1.27)
							)
						)
					)
				)
				(pin bidirectional line
					(at 0 -25.4 0)
					(length 3.81)
					(name "SPI3_CS0_N"
						(effects
							(font
								(size 1.27 1.27)
							)
						)
					)
					(number "C57"
						(effects
							(font
								(size 1.27 1.27)
							)
						)
					)
				)
				(pin bidirectional line
					(at 0 -27.94 0)
					(length 3.81)
					(name "SPI3_CS1_N"
						(effects
							(font
								(size 1.27 1.27)
							)
						)
					)
					(number "E56"
						(effects
							(font
								(size 1.27 1.27)
							)
						)
					)
				)
				(pin bidirectional line
					(at 0 -30.48 0)
					(length 3.81)
					(name "SPI3_CLK"
						(effects
							(font
								(size 1.27 1.27)
							)
						)
					)
					(number "F55"
						(effects
							(font
								(size 1.27 1.27)
							)
						)
					)
				)
				(pin bidirectional line
					(at 0 -33.02 0)
					(length 3.81)
					(name "SPI3_MISO"
						(effects
							(font
								(size 1.27 1.27)
							)
						)
					)
					(number "D56"
						(effects
							(font
								(size 1.27 1.27)
							)
						)
					)
				)
				(pin bidirectional line
					(at 0 -35.56 0)
					(length 3.81)
					(name "SPI3_MOSI"
						(effects
							(font
								(size 1.27 1.27)
							)
						)
					)
					(number "G56"
						(effects
							(font
								(size 1.27 1.27)
							)
						)
					)
				)
				(pin output line
					(at 0 -40.64 0)
					(length 3.81)
					(name "FSI_GPIO18"
						(effects
							(font
								(size 1.27 1.27)
							)
						)
					)
					(number "E51"
						(effects
							(font
								(size 1.27 1.27)
							)
						)
					)
					(alternate "SGMII1_MDC" passive line)
				)
				(pin bidirectional line
					(at 0 -43.18 0)
					(length 3.81)
					(name "FSI_GPIO19"
						(effects
							(font
								(size 1.27 1.27)
							)
						)
					)
					(number "E50"
						(effects
							(font
								(size 1.27 1.27)
							)
						)
					)
					(alternate "SGMII1_MDIO" passive line)
				)
				(pin output line
					(at 0 -48.26 0)
					(length 3.81)
					(name "GPIO19"
						(effects
							(font
								(size 1.27 1.27)
							)
						)
					)
					(number "K56"
						(effects
							(font
								(size 1.27 1.27)
							)
						)
					)
					(alternate "XFI1_MDC" passive line)
				)
				(pin bidirectional line
					(at 0 -50.8 0)
					(length 3.81)
					(name "GPIO33"
						(effects
							(font
								(size 1.27 1.27)
							)
						)
					)
					(number "C54"
						(effects
							(font
								(size 1.27 1.27)
							)
						)
					)
					(alternate "XFI1_MDIO" passive line)
				)
				(pin output line
					(at 0 -54.61 0)
					(length 3.81)
					(name "GPIO03"
						(effects
							(font
								(size 1.27 1.27)
							)
						)
					)
					(number "D54"
						(effects
							(font
								(size 1.27 1.27)
							)
						)
					)
					(alternate "XFI2_MDC" passive line)
				)
				(pin bidirectional line
					(at 0 -57.15 0)
					(length 3.81)
					(name "GPIO24"
						(effects
							(font
								(size 1.27 1.27)
							)
						)
					)
					(number "J51"
						(effects
							(font
								(size 1.27 1.27)
							)
						)
					)
					(alternate "XFI2_MDIO" passive line)
				)
				(pin passive line
					(at 0 -60.96 0)
					(length 3.81)
					(name "GPIO70"
						(effects
							(font
								(size 1.27 1.27)
							)
						)
					)
					(number "K52"
						(effects
							(font
								(size 1.27 1.27)
							)
						)
					)
					(alternate "XFI3_MDC" passive line)
				)
				(pin passive line
					(at 0 -63.5 0)
					(length 3.81)
					(name "GPIO69"
						(effects
							(font
								(size 1.27 1.27)
							)
						)
					)
					(number "K51"
						(effects
							(font
								(size 1.27 1.27)
							)
						)
					)
					(alternate "XFI3_MDIO" passive line)
				)
				(pin output line
					(at 0 -68.58 0)
					(length 3.81)
					(name "SGMII0_MDC"
						(effects
							(font
								(size 1.27 1.27)
							)
						)
					)
					(number "E6"
						(effects
							(font
								(size 1.27 1.27)
							)
						)
					)
					(alternate "GPIO52" passive line)
				)
				(pin bidirectional line
					(at 0 -71.12 0)
					(length 3.81)
					(name "SGMII0_MDIO"
						(effects
							(font
								(size 1.27 1.27)
							)
						)
					)
					(number "E7"
						(effects
							(font
								(size 1.27 1.27)
							)
						)
					)
					(alternate "GPIO53" passive line)
				)
				(pin bidirectional line
					(at 0 -76.2 0)
					(length 3.81)
					(name "FSI_GPIO31"
						(effects
							(font
								(size 1.27 1.27)
							)
						)
					)
					(number "F8"
						(effects
							(font
								(size 1.27 1.27)
							)
						)
					)
					(alternate "SPI4_CS0_N" passive line)
				)
				(pin bidirectional line
					(at 0 -78.74 0)
					(length 3.81)
					(name "FSI_GPIO32"
						(effects
							(font
								(size 1.27 1.27)
							)
						)
					)
					(number "A4"
						(effects
							(font
								(size 1.27 1.27)
							)
						)
					)
					(alternate "SPI4_CS1_N" passive line)
				)
				(pin bidirectional line
					(at 0 -81.28 0)
					(length 3.81)
					(name "FSI_GPIO33"
						(effects
							(font
								(size 1.27 1.27)
							)
						)
					)
					(number "D6"
						(effects
							(font
								(size 1.27 1.27)
							)
						)
					)
					(alternate "SPI4_CS2_N" passive line)
				)
				(pin passive line
					(at 0 -83.82 0)
					(length 3.81)
					(name "FSI_GPIO30"
						(effects
							(font
								(size 1.27 1.27)
							)
						)
					)
					(number "B6"
						(effects
							(font
								(size 1.27 1.27)
							)
						)
					)
					(alternate "SPI4_CLK" passive line)
				)
				(pin bidirectional line
					(at 0 -86.36 0)
					(length 3.81)
					(name "FSI_GPIO34"
						(effects
							(font
								(size 1.27 1.27)
							)
						)
					)
					(number "A5"
						(effects
							(font
								(size 1.27 1.27)
							)
						)
					)
					(alternate "SPI4_MISO" passive line)
				)
				(pin bidirectional line
					(at 0 -88.9 0)
					(length 3.81)
					(name "FSI_GPIO35"
						(effects
							(font
								(size 1.27 1.27)
							)
						)
					)
					(number "E8"
						(effects
							(font
								(size 1.27 1.27)
							)
						)
					)
					(alternate "SPI4_MOSI" passive line)
				)
				(pin passive line
					(at 0 -93.98 0)
					(length 3.81)
					(name "FSI_GPIO15"
						(effects
							(font
								(size 1.27 1.27)
							)
						)
					)
					(number "E34"
						(effects
							(font
								(size 1.27 1.27)
							)
						)
					)
					(alternate "SPI5_CS0_N" passive line)
				)
				(pin passive line
					(at 0 -96.52 0)
					(length 3.81)
					(name "FSI_GPIO12"
						(effects
							(font
								(size 1.27 1.27)
							)
						)
					)
					(number "F37"
						(effects
							(font
								(size 1.27 1.27)
							)
						)
					)
					(alternate "SPI5_CLK" passive line)
				)
				(pin passive line
					(at 0 -99.06 0)
					(length 3.81)
					(name "FSI_GPIO13"
						(effects
							(font
								(size 1.27 1.27)
							)
						)
					)
					(number "F36"
						(effects
							(font
								(size 1.27 1.27)
							)
						)
					)
					(alternate "SPI5_MISO" passive line)
				)
				(pin passive line
					(at 0 -101.6 0)
					(length 3.81)
					(name "FSI_GPIO14"
						(effects
							(font
								(size 1.27 1.27)
							)
						)
					)
					(number "E35"
						(effects
							(font
								(size 1.27 1.27)
							)
						)
					)
					(alternate "SPI5_MOSI" passive line)
				)
				(pin input line
					(at 44.45 0 180)
					(length 3.81)
					(name "FSI_GPIO08"
						(effects
							(font
								(size 1.27 1.27)
							)
						)
					)
					(number "G39"
						(effects
							(font
								(size 1.27 1.27)
							)
						)
					)
					(alternate "CAN0_DIN" passive line)
				)
				(pin output line
					(at 44.45 -2.54 180)
					(length 3.81)
					(name "FSI_GPIO07"
						(effects
							(font
								(size 1.27 1.27)
							)
						)
					)
					(number "G38"
						(effects
							(font
								(size 1.27 1.27)
							)
						)
					)
					(alternate "CAN0_DOUT" passive line)
				)
				(pin input line
					(at 44.45 -6.35 180)
					(length 3.81)
					(name "FSI_GPIO10"
						(effects
							(font
								(size 1.27 1.27)
							)
						)
					)
					(number "H36"
						(effects
							(font
								(size 1.27 1.27)
							)
						)
					)
					(alternate "CAN1_DIN" passive line)
				)
				(pin output line
					(at 44.45 -8.89 180)
					(length 3.81)
					(name "FSI_GPIO09"
						(effects
							(font
								(size 1.27 1.27)
							)
						)
					)
					(number "H37"
						(effects
							(font
								(size 1.27 1.27)
							)
						)
					)
					(alternate "CAN1_DOUT" passive line)
				)
				(pin input line
					(at 44.45 -12.7 180)
					(length 3.81)
					(name "CAN2_DIN"
						(effects
							(font
								(size 1.27 1.27)
							)
						)
					)
					(number "F58"
						(effects
							(font
								(size 1.27 1.27)
							)
						)
					)
				)
				(pin output line
					(at 44.45 -15.24 180)
					(length 3.81)
					(name "CAN2_DOUT"
						(effects
							(font
								(size 1.27 1.27)
							)
						)
					)
					(number "D59"
						(effects
							(font
								(size 1.27 1.27)
							)
						)
					)
				)
				(pin input line
					(at 44.45 -19.05 180)
					(length 3.81)
					(name "CAN3_DIN"
						(effects
							(font
								(size 1.27 1.27)
							)
						)
					)
					(number "B61"
						(effects
							(font
								(size 1.27 1.27)
							)
						)
					)
				)
				(pin output line
					(at 44.45 -21.59 180)
					(length 3.81)
					(name "CAN3_DOUT"
						(effects
							(font
								(size 1.27 1.27)
							)
						)
					)
					(number "H61"
						(effects
							(font
								(size 1.27 1.27)
							)
						)
					)
				)
				(pin output line
					(at 44.45 -26.67 180)
					(length 3.81)
					(name "UART1_RTS"
						(effects
							(font
								(size 1.27 1.27)
							)
						)
					)
					(number "L51"
						(effects
							(font
								(size 1.27 1.27)
							)
						)
					)
				)
				(pin input line
					(at 44.45 -29.21 180)
					(length 3.81)
					(name "UART1_CTS"
						(effects
							(font
								(size 1.27 1.27)
							)
						)
					)
					(number "H54"
						(effects
							(font
								(size 1.27 1.27)
							)
						)
					)
				)
				(pin output line
					(at 44.45 -31.75 180)
					(length 3.81)
					(name "UART1_TX"
						(effects
							(font
								(size 1.27 1.27)
							)
						)
					)
					(number "K53"
						(effects
							(font
								(size 1.27 1.27)
							)
						)
					)
				)
				(pin input line
					(at 44.45 -34.29 180)
					(length 3.81)
					(name "UART1_RX"
						(effects
							(font
								(size 1.27 1.27)
							)
						)
					)
					(number "K54"
						(effects
							(font
								(size 1.27 1.27)
							)
						)
					)
				)
				(pin output line
					(at 44.45 -38.1 180)
					(length 3.81)
					(name "UART2_RTS"
						(effects
							(font
								(size 1.27 1.27)
							)
						)
					)
					(number "G58"
						(effects
							(font
								(size 1.27 1.27)
							)
						)
					)
				)
				(pin input line
					(at 44.45 -40.64 180)
					(length 3.81)
					(name "UART2_CTS"
						(effects
							(font
								(size 1.27 1.27)
							)
						)
					)
					(number "A57"
						(effects
							(font
								(size 1.27 1.27)
							)
						)
					)
				)
				(pin output line
					(at 44.45 -43.18 180)
					(length 3.81)
					(name "UART2_TX"
						(effects
							(font
								(size 1.27 1.27)
							)
						)
					)
					(number "C58"
						(effects
							(font
								(size 1.27 1.27)
							)
						)
					)
				)
				(pin input line
					(at 44.45 -45.72 180)
					(length 3.81)
					(name "UART2_RX"
						(effects
							(font
								(size 1.27 1.27)
							)
						)
					)
					(number "C56"
						(effects
							(font
								(size 1.27 1.27)
							)
						)
					)
				)
				(pin output line
					(at 44.45 -49.53 180)
					(length 3.81)
					(name "UART3_TX_DEBUG"
						(effects
							(font
								(size 1.27 1.27)
							)
						)
					)
					(number "H62"
						(effects
							(font
								(size 1.27 1.27)
							)
						)
					)
				)
				(pin input line
					(at 44.45 -52.07 180)
					(length 3.81)
					(name "UART3_RX_DEBUG"
						(effects
							(font
								(size 1.27 1.27)
							)
						)
					)
					(number "K60"
						(effects
							(font
								(size 1.27 1.27)
							)
						)
					)
				)
				(pin output line
					(at 44.45 -55.88 180)
					(length 3.81)
					(name "UART4_RTS"
						(effects
							(font
								(size 1.27 1.27)
							)
						)
					)
					(number "L4"
						(effects
							(font
								(size 1.27 1.27)
							)
						)
					)
				)
				(pin input line
					(at 44.45 -58.42 180)
					(length 3.81)
					(name "UART4_CTS"
						(effects
							(font
								(size 1.27 1.27)
							)
						)
					)
					(number "L6"
						(effects
							(font
								(size 1.27 1.27)
							)
						)
					)
				)
				(pin output line
					(at 44.45 -60.96 180)
					(length 3.81)
					(name "UART4_TX"
						(effects
							(font
								(size 1.27 1.27)
							)
						)
					)
					(number "L5"
						(effects
							(font
								(size 1.27 1.27)
							)
						)
					)
				)
				(pin input line
					(at 44.45 -63.5 180)
					(length 3.81)
					(name "UART4_RX"
						(effects
							(font
								(size 1.27 1.27)
							)
						)
					)
					(number "H6"
						(effects
							(font
								(size 1.27 1.27)
							)
						)
					)
				)
				(pin output line
					(at 44.45 -67.31 180)
					(length 3.81)
					(name "UART5_RTS"
						(effects
							(font
								(size 1.27 1.27)
							)
						)
					)
					(number "K58"
						(effects
							(font
								(size 1.27 1.27)
							)
						)
					)
				)
				(pin input line
					(at 44.45 -69.85 180)
					(length 3.81)
					(name "UART5_CTS"
						(effects
							(font
								(size 1.27 1.27)
							)
						)
					)
					(number "H57"
						(effects
							(font
								(size 1.27 1.27)
							)
						)
					)
				)
				(pin output line
					(at 44.45 -72.39 180)
					(length 3.81)
					(name "UART5_TX"
						(effects
							(font
								(size 1.27 1.27)
							)
						)
					)
					(number "J58"
						(effects
							(font
								(size 1.27 1.27)
							)
						)
					)
				)
				(pin input line
					(at 44.45 -74.93 180)
					(length 3.81)
					(name "UART5_RX"
						(effects
							(font
								(size 1.27 1.27)
							)
						)
					)
					(number "H58"
						(effects
							(font
								(size 1.27 1.27)
							)
						)
					)
				)
				(pin passive line
					(at 44.45 -80.01 180)
					(length 3.81)
					(name "PWM01"
						(effects
							(font
								(size 1.27 1.27)
							)
						)
					)
					(number "K57"
						(effects
							(font
								(size 1.27 1.27)
							)
						)
					)
				)
				(pin input line
					(at 44.45 -99.06 180)
					(length 3.81)
					(name "FAN_TACH"
						(effects
							(font
								(size 1.27 1.27)
							)
						)
					)
					(number "E54"
						(effects
							(font
								(size 1.27 1.27)
							)
						)
					)
				)
				(pin output line
					(at 44.45 -101.6 180)
					(length 3.81)
					(name "FAN_PWM"
						(effects
							(font
								(size 1.27 1.27)
							)
						)
					)
					(number "K62"
						(effects
							(font
								(size 1.27 1.27)
							)
						)
					)
				)
			)
			(symbol "Hermaphroditic_Molex_203456-0003_CUSTOM_Jetson_AGX_Thor_H8mm_10_1"
				(rectangle
					(start 3.81 2.54)
					(end 19.05 -19.05)
					(stroke
						(width 0.254)
						(type default)
					)
					(fill
						(type background)
					)
				)
				(pin passive line
					(at 0 0 0)
					(length 3.81)
					(name "JTAG_TMS"
						(effects
							(font
								(size 1.27 1.27)
							)
						)
					)
					(number "E58"
						(effects
							(font
								(size 1.27 1.27)
							)
						)
					)
				)
				(pin passive line
					(at 0 -2.54 0)
					(length 3.81)
					(name "JTAG_TDI"
						(effects
							(font
								(size 1.27 1.27)
							)
						)
					)
					(number "B60"
						(effects
							(font
								(size 1.27 1.27)
							)
						)
					)
				)
				(pin passive line
					(at 0 -5.08 0)
					(length 3.81)
					(name "JTAG_TCK"
						(effects
							(font
								(size 1.27 1.27)
							)
						)
					)
					(number "A60"
						(effects
							(font
								(size 1.27 1.27)
							)
						)
					)
				)
				(pin passive line
					(at 0 -7.62 0)
					(length 3.81)
					(name "JTAG_TDO"
						(effects
							(font
								(size 1.27 1.27)
							)
						)
					)
					(number "D58"
						(effects
							(font
								(size 1.27 1.27)
							)
						)
					)
				)
				(pin passive line
					(at 0 -10.16 0)
					(length 3.81)
					(name "JTAG_TRST_N"
						(effects
							(font
								(size 1.27 1.27)
							)
						)
					)
					(number "G61"
						(effects
							(font
								(size 1.27 1.27)
							)
						)
					)
				)
				(pin passive line
					(at 0 -13.97 0)
					(length 3.81)
					(name "NVJTAG_SEL"
						(effects
							(font
								(size 1.27 1.27)
							)
						)
					)
					(number "H59"
						(effects
							(font
								(size 1.27 1.27)
							)
						)
					)
				)
				(pin passive line
					(at 0 -16.51 0)
					(length 3.81)
					(name "NVDBG_SEL"
						(effects
							(font
								(size 1.27 1.27)
							)
						)
					)
					(number "G60"
						(effects
							(font
								(size 1.27 1.27)
							)
						)
					)
				)
			)
			(symbol "Hermaphroditic_Molex_203456-0003_CUSTOM_Jetson_AGX_Thor_H8mm_11_1"
				(rectangle
					(start 3.81 2.54)
					(end 21.59 -43.18)
					(stroke
						(width 0.254)
						(type default)
					)
					(fill
						(type background)
					)
				)
				(pin passive line
					(at 0 0 0)
					(length 3.81)
					(name "GPIO01"
						(effects
							(font
								(size 1.27 1.27)
							)
						)
					)
					(number "J4"
						(effects
							(font
								(size 1.27 1.27)
							)
						)
					)
				)
				(pin passive line
					(at 0 -2.54 0)
					(length 3.81)
					(name "GPIO04"
						(effects
							(font
								(size 1.27 1.27)
							)
						)
					)
					(number "B59"
						(effects
							(font
								(size 1.27 1.27)
							)
						)
					)
				)
				(pin passive line
					(at 0 -5.08 0)
					(length 3.81)
					(name "GPIO05"
						(effects
							(font
								(size 1.27 1.27)
							)
						)
					)
					(number "A59"
						(effects
							(font
								(size 1.27 1.27)
							)
						)
					)
				)
				(pin passive line
					(at 0 -7.62 0)
					(length 3.81)
					(name "GPIO08"
						(effects
							(font
								(size 1.27 1.27)
							)
						)
					)
					(number "B62"
						(effects
							(font
								(size 1.27 1.27)
							)
						)
					)
				)
				(pin passive line
					(at 0 -10.16 0)
					(length 3.81)
					(name "GPIO09"
						(effects
							(font
								(size 1.27 1.27)
							)
						)
					)
					(number "C61"
						(effects
							(font
								(size 1.27 1.27)
							)
						)
					)
				)
				(pin passive line
					(at 0 -12.7 0)
					(length 3.81)
					(name "GPIO13"
						(effects
							(font
								(size 1.27 1.27)
							)
						)
					)
					(number "G7"
						(effects
							(font
								(size 1.27 1.27)
							)
						)
					)
				)
				(pin passive line
					(at 0 -15.24 0)
					(length 3.81)
					(name "GPIO14"
						(effects
							(font
								(size 1.27 1.27)
							)
						)
					)
					(number "L15"
						(effects
							(font
								(size 1.27 1.27)
							)
						)
					)
				)
				(pin passive line
					(at 0 -17.78 0)
					(length 3.81)
					(name "GPIO15"
						(effects
							(font
								(size 1.27 1.27)
							)
						)
					)
					(number "F10"
						(effects
							(font
								(size 1.27 1.27)
							)
						)
					)
				)
				(pin passive line
					(at 0 -20.32 0)
					(length 3.81)
					(name "GPIO16"
						(effects
							(font
								(size 1.27 1.27)
							)
						)
					)
					(number "F9"
						(effects
							(font
								(size 1.27 1.27)
							)
						)
					)
				)
				(pin passive line
					(at 0 -22.86 0)
					(length 3.81)
					(name "GPIO17"
						(effects
							(font
								(size 1.27 1.27)
							)
						)
					)
					(number "A62"
						(effects
							(font
								(size 1.27 1.27)
							)
						)
					)
				)
				(pin passive line
					(at 0 -25.4 0)
					(length 3.81)
					(name "GPIO18"
						(effects
							(font
								(size 1.27 1.27)
							)
						)
					)
					(number "C39"
						(effects
							(font
								(size 1.27 1.27)
							)
						)
					)
				)
				(pin passive line
					(at 0 -27.94 0)
					(length 3.81)
					(name "GPIO20"
						(effects
							(font
								(size 1.27 1.27)
							)
						)
					)
					(number "A58"
						(effects
							(font
								(size 1.27 1.27)
							)
						)
					)
				)
				(pin passive line
					(at 0 -30.48 0)
					(length 3.81)
					(name "GPIO21"
						(effects
							(font
								(size 1.27 1.27)
							)
						)
					)
					(number "B58"
						(effects
							(font
								(size 1.27 1.27)
							)
						)
					)
				)
				(pin passive line
					(at 0 -33.02 0)
					(length 3.81)
					(name "GPIO27"
						(effects
							(font
								(size 1.27 1.27)
							)
						)
					)
					(number "H52"
						(effects
							(font
								(size 1.27 1.27)
							)
						)
					)
				)
				(pin passive line
					(at 0 -35.56 0)
					(length 3.81)
					(name "GPIO32"
						(effects
							(font
								(size 1.27 1.27)
							)
						)
					)
					(number "C38"
						(effects
							(font
								(size 1.27 1.27)
							)
						)
					)
				)
				(pin passive line
					(at 0 -38.1 0)
					(length 3.81)
					(name "GPIO34"
						(effects
							(font
								(size 1.27 1.27)
							)
						)
					)
					(number "A18"
						(effects
							(font
								(size 1.27 1.27)
							)
						)
					)
				)
				(pin passive line
					(at 0 -40.64 0)
					(length 3.81)
					(name "GPIO36"
						(effects
							(font
								(size 1.27 1.27)
							)
						)
					)
					(number "F56"
						(effects
							(font
								(size 1.27 1.27)
							)
						)
					)
				)
				(pin passive line
					(at 25.4 0 180)
					(length 3.81)
					(name "GPIO37"
						(effects
							(font
								(size 1.27 1.27)
							)
						)
					)
					(number "A39"
						(effects
							(font
								(size 1.27 1.27)
							)
						)
					)
				)
				(pin passive line
					(at 25.4 -2.54 180)
					(length 3.81)
					(name "GPIO38"
						(effects
							(font
								(size 1.27 1.27)
							)
						)
					)
					(number "E59"
						(effects
							(font
								(size 1.27 1.27)
							)
						)
					)
				)
				(pin passive line
					(at 25.4 -5.08 180)
					(length 3.81)
					(name "GPIO42"
						(effects
							(font
								(size 1.27 1.27)
							)
						)
					)
					(number "F59"
						(effects
							(font
								(size 1.27 1.27)
							)
						)
					)
				)
				(pin passive line
					(at 25.4 -7.62 180)
					(length 3.81)
					(name "GPIO43"
						(effects
							(font
								(size 1.27 1.27)
							)
						)
					)
					(number "A38"
						(effects
							(font
								(size 1.27 1.27)
							)
						)
					)
				)
				(pin passive line
					(at 25.4 -10.16 180)
					(length 3.81)
					(name "GPIO44"
						(effects
							(font
								(size 1.27 1.27)
							)
						)
					)
					(number "E5"
						(effects
							(font
								(size 1.27 1.27)
							)
						)
					)
				)
				(pin passive line
					(at 25.4 -12.7 180)
					(length 3.81)
					(name "GPIO45"
						(effects
							(font
								(size 1.27 1.27)
							)
						)
					)
					(number "B54"
						(effects
							(font
								(size 1.27 1.27)
							)
						)
					)
				)
				(pin passive line
					(at 25.4 -15.24 180)
					(length 3.81)
					(name "GPIO46"
						(effects
							(font
								(size 1.27 1.27)
							)
						)
					)
					(number "A54"
						(effects
							(font
								(size 1.27 1.27)
							)
						)
					)
				)
				(pin passive line
					(at 25.4 -17.78 180)
					(length 3.81)
					(name "GPIO47"
						(effects
							(font
								(size 1.27 1.27)
							)
						)
					)
					(number "C4"
						(effects
							(font
								(size 1.27 1.27)
							)
						)
					)
				)
				(pin passive line
					(at 25.4 -20.32 180)
					(length 3.81)
					(name "GPIO48"
						(effects
							(font
								(size 1.27 1.27)
							)
						)
					)
					(number "D5"
						(effects
							(font
								(size 1.27 1.27)
							)
						)
					)
				)
				(pin passive line
					(at 25.4 -22.86 180)
					(length 3.81)
					(name "GPIO49"
						(effects
							(font
								(size 1.27 1.27)
							)
						)
					)
					(number "G6"
						(effects
							(font
								(size 1.27 1.27)
							)
						)
					)
				)
				(pin passive line
					(at 25.4 -25.4 180)
					(length 3.81)
					(name "GPIO50"
						(effects
							(font
								(size 1.27 1.27)
							)
						)
					)
					(number "J18"
						(effects
							(font
								(size 1.27 1.27)
							)
						)
					)
				)
				(pin passive line
					(at 25.4 -27.94 180)
					(length 3.81)
					(name "GPIO59"
						(effects
							(font
								(size 1.27 1.27)
							)
						)
					)
					(number "H5"
						(effects
							(font
								(size 1.27 1.27)
							)
						)
					)
				)
				(pin passive line
					(at 25.4 -30.48 180)
					(length 3.81)
					(name "GPIO60"
						(effects
							(font
								(size 1.27 1.27)
							)
						)
					)
					(number "K6"
						(effects
							(font
								(size 1.27 1.27)
							)
						)
					)
				)
				(pin passive line
					(at 25.4 -33.02 180)
					(length 3.81)
					(name "GPIO63"
						(effects
							(font
								(size 1.27 1.27)
							)
						)
					)
					(number "J5"
						(effects
							(font
								(size 1.27 1.27)
							)
						)
					)
				)
				(pin passive line
					(at 25.4 -35.56 180)
					(length 3.81)
					(name "GPIO64"
						(effects
							(font
								(size 1.27 1.27)
							)
						)
					)
					(number "J6"
						(effects
							(font
								(size 1.27 1.27)
							)
						)
					)
				)
				(pin passive line
					(at 25.4 -38.1 180)
					(length 3.81)
					(name "GPIO65"
						(effects
							(font
								(size 1.27 1.27)
							)
						)
					)
					(number "J7"
						(effects
							(font
								(size 1.27 1.27)
							)
						)
					)
				)
				(pin passive line
					(at 25.4 -40.64 180)
					(length 3.81)
					(name "GPIO67"
						(effects
							(font
								(size 1.27 1.27)
							)
						)
					)
					(number "J19"
						(effects
							(font
								(size 1.27 1.27)
							)
						)
					)
				)
			)
		)
	(symbol "antmicroB2BConnectors:Plug_Samtec_UMPT_1x6_UMPT-06-02.5-L-V-S-W-TR"
			(exclude_from_sim no)
			(in_bom yes)
			(on_board yes)
			(property "Reference" "J"
				(at 22.86 -2.54 0)
				(effects
					(font
						(size 1.27 1.27)
						(thickness 0.15)
					)
					(justify left bottom)
				)
			)
			(property "Value" "Plug_Samtec_UMPT_1x6_UMPT-06-02.5-L-V-S-W-TR"
				(at 22.86 -7.62 0)
				(effects
					(font
						(size 1.27 1.27)
						(thickness 0.15)
					)
					(justify left bottom)
					(hide yes)
				)
			)
			(property "Footprint" "antmicro-footprints:Conn_Plug_Samtec_UMPT_1x6_UMPT-06-02.5-L-V-S-W-TR"
				(at 22.86 -10.16 0)
				(effects
					(font
						(size 1.27 1.27)
						(thickness 0.15)
					)
					(justify left bottom)
					(hide yes)
				)
			)
			(property "Datasheet" "https://suddendocs.samtec.com/catalog_english/umpt.pdf"
				(at 22.86 -12.7 0)
				(effects
					(font
						(size 1.27 1.27)
						(thickness 0.15)
					)
					(justify left bottom)
					(hide yes)
				)
			)
			(property "Description" "2.00 mm mPOWER® Ultra Micro Power Terminal, Vertical"
				(at 22.86 -25.4 0)
				(effects
					(font
						(size 1.27 1.27)
						(thickness 0.15)
					)
					(justify left bottom)
					(hide yes)
				)
			)
			(property "MPN" "UMPT-06-02.5-L-V-S-W-TR"
				(at 22.86 -5.08 0)
				(effects
					(font
						(size 1.27 1.27)
						(thickness 0.15)
					)
					(justify left bottom)
				)
			)
			(property "Manufacturer" "Samtec"
				(at 22.86 -17.78 0)
				(effects
					(font
						(size 1.27 1.27)
						(thickness 0.15)
					)
					(justify left bottom)
					(hide yes)
				)
			)
			(property "Author" "Antmicro"
				(at 22.86 -20.32 0)
				(effects
					(font
						(size 1.27 1.27)
						(thickness 0.15)
					)
					(justify left bottom)
					(hide yes)
				)
			)
			(property "License" "Apache-2.0"
				(at 22.86 -22.86 0)
				(effects
					(font
						(size 1.27 1.27)
						(thickness 0.15)
					)
					(justify left bottom)
					(hide yes)
				)
			)
			(property "ki_keywords" "POWER, B2B, VERTICAL"
				(at 0 0 0)
				(effects
					(font
						(size 1.27 1.27)
					)
					(hide yes)
				)
			)
			(symbol "Plug_Samtec_UMPT_1x6_UMPT-06-02.5-L-V-S-W-TR_1_1"
				(rectangle
					(start 3.81 2.54)
					(end 7.62 -20.32)
					(stroke
						(width 0.254)
						(type default)
					)
					(fill
						(type background)
					)
				)
				(pin passive line
					(at 0 0 0)
					(length 3.81)
					(name "~"
						(effects
							(font
								(size 1.27 1.27)
							)
						)
					)
					(number "1"
						(effects
							(font
								(size 1.27 1.27)
							)
						)
					)
				)
				(pin passive line
					(at 0 -2.54 0)
					(length 3.81)
					(name "~"
						(effects
							(font
								(size 1.27 1.27)
							)
						)
					)
					(number "2"
						(effects
							(font
								(size 1.27 1.27)
							)
						)
					)
				)
				(pin passive line
					(at 0 -5.08 0)
					(length 3.81)
					(name "~"
						(effects
							(font
								(size 1.27 1.27)
							)
						)
					)
					(number "3"
						(effects
							(font
								(size 1.27 1.27)
							)
						)
					)
				)
				(pin passive line
					(at 0 -7.62 0)
					(length 3.81)
					(name "~"
						(effects
							(font
								(size 1.27 1.27)
							)
						)
					)
					(number "4"
						(effects
							(font
								(size 1.27 1.27)
							)
						)
					)
				)
				(pin passive line
					(at 0 -10.16 0)
					(length 3.81)
					(name "~"
						(effects
							(font
								(size 1.27 1.27)
							)
						)
					)
					(number "5"
						(effects
							(font
								(size 1.27 1.27)
							)
						)
					)
				)
				(pin passive line
					(at 0 -12.7 0)
					(length 3.81)
					(name "~"
						(effects
							(font
								(size 1.27 1.27)
							)
						)
					)
					(number "6"
						(effects
							(font
								(size 1.27 1.27)
							)
						)
					)
				)
				(pin passive line
					(at 0 -15.24 0)
					(length 3.81)
					(name "~"
						(effects
							(font
								(size 1.27 1.27)
							)
						)
					)
					(number "MP1"
						(effects
							(font
								(size 1.27 1.27)
							)
						)
					)
				)
				(pin passive line
					(at 0 -17.78 0)
					(length 3.81)
					(name "~"
						(effects
							(font
								(size 1.27 1.27)
							)
						)
					)
					(number "MP2"
						(effects
							(font
								(size 1.27 1.27)
							)
						)
					)
				)
			)
		)
	(symbol "antmicroBatteryHoldersClipsContacts:Battery_Holder_MS621FE-FL11E"
			(pin_names
				(offset 0)
			)
			(exclude_from_sim no)
			(in_bom yes)
			(on_board yes)
			(property "Reference" "BT"
				(at 17.78 -2.54 0)
				(effects
					(font
						(size 1.27 1.27)
						(thickness 0.15)
					)
					(justify left bottom)
				)
			)
			(property "Value" "Battery_Holder_MS621FE-FL11E"
				(at 17.78 -7.62 0)
				(effects
					(font
						(size 1.27 1.27)
						(thickness 0.15)
					)
					(justify left bottom)
					(hide yes)
				)
			)
			(property "Footprint" "antmicro-footprints:MS621FE-FL11E"
				(at 17.78 -10.16 0)
				(effects
					(font
						(size 1.27 1.27)
						(thickness 0.15)
					)
					(justify left bottom)
					(hide yes)
				)
			)
			(property "Datasheet" "https://www.sii.co.jp/en/me/datasheets/ms-rechargeable/ms621fe/"
				(at 17.78 -12.7 0)
				(effects
					(font
						(size 1.27 1.27)
						(thickness 0.15)
					)
					(justify left bottom)
					(hide yes)
				)
			)
			(property "Description" "Rechargeable Battery, Coin Cell, Single Cell, 3 V, Lithium Manganese Dioxide, 5.5 mAh, Button Cell"
				(at 17.78 -22.86 0)
				(effects
					(font
						(size 1.27 1.27)
					)
					(justify left bottom)
					(hide yes)
				)
			)
			(property "Manufacturer" "Seiko Instruments"
				(at 17.78 -15.24 0)
				(effects
					(font
						(size 1.27 1.27)
						(thickness 0.15)
					)
					(justify left bottom)
					(hide yes)
				)
			)
			(property "MPN" "MS621FE-FL11E"
				(at 17.78 -5.08 0)
				(effects
					(font
						(size 1.27 1.27)
						(thickness 0.15)
					)
					(justify left bottom)
				)
			)
			(property "Author" "Antmicro"
				(at 17.78 -17.78 0)
				(effects
					(font
						(size 1.27 1.27)
						(thickness 0.15)
					)
					(justify left bottom)
					(hide yes)
				)
			)
			(property "License" "Apache-2.0"
				(at 17.78 -20.32 0)
				(effects
					(font
						(size 1.27 1.27)
						(thickness 0.15)
					)
					(justify left bottom)
					(hide yes)
				)
			)
			(property "ki_keywords" "HORIZONTAL, SMT, HOLDER, BATTERY"
				(at 0 0 0)
				(effects
					(font
						(size 1.27 1.27)
					)
					(hide yes)
				)
			)
			(symbol "Battery_Holder_MS621FE-FL11E_0_1"
				(rectangle
					(start -1.27 -5.08)
					(end 1.27 -4.826)
					(stroke
						(width 0.254)
						(type default)
					)
					(fill
						(type outline)
					)
				)
				(polyline
					(pts
						(xy 0 -2.54) (xy 0 -3.81)
					)
					(stroke
						(width 0.254)
						(type default)
					)
					(fill
						(type none)
					)
				)
			)
			(symbol "Battery_Holder_MS621FE-FL11E_1_1"
				(polyline
					(pts
						(xy -2.54 -3.81) (xy 2.54 -3.81)
					)
					(stroke
						(width 0.254)
						(type default)
					)
					(fill
						(type background)
					)
				)
				(polyline
					(pts
						(xy 0 -6.35) (xy 0 -5.08)
					)
					(stroke
						(width 0.254)
						(type default)
					)
					(fill
						(type background)
					)
				)
				(pin passive line
					(at 0 0 270)
					(length 2.54)
					(name "+"
						(effects
							(font
								(size 1.27 1.27)
							)
						)
					)
					(number "1"
						(effects
							(font
								(size 1.27 1.27)
							)
						)
					)
				)
				(pin passive line
					(at 0 -8.89 90)
					(length 2.54)
					(name "-"
						(effects
							(font
								(size 1.27 1.27)
							)
						)
					)
					(number "2"
						(effects
							(font
								(size 1.27 1.27)
							)
						)
					)
				)
			)
		)
	(symbol "antmicroCapacitors0402:C_100n_0402"
			(pin_numbers
				(hide yes)
			)
			(pin_names
				(hide yes)
			)
			(exclude_from_sim no)
			(in_bom yes)
			(on_board yes)
			(property "Reference" "C"
				(at 20.32 -5.08 0)
				(effects
					(font
						(size 1.27 1.27)
						(thickness 0.15)
					)
					(justify left bottom)
				)
			)
			(property "Value" "C_100n_0402"
				(at 20.32 -10.16 0)
				(effects
					(font
						(size 1.27 1.27)
						(thickness 0.15)
					)
					(justify left bottom)
					(hide yes)
				)
			)
			(property "Footprint" "antmicro-footprints:C_0402_1005Metric"
				(at 20.32 -12.7 0)
				(effects
					(font
						(size 1.27 1.27)
						(thickness 0.15)
					)
					(justify left bottom)
					(hide yes)
				)
			)
			(property "Datasheet" "https://www.murata.com/products/productdetail?partno=GRM155R61H104KE14%23"
				(at 20.32 -15.24 0)
				(effects
					(font
						(size 1.27 1.27)
						(thickness 0.15)
					)
					(justify left bottom)
					(hide yes)
				)
			)
			(property "Description" "SMD Multilayer Ceramic Capacitor, 0.1 µF, 50 V, 0402 [1005 Metric], ± 10%, X5R, GRM Series"
				(at 20.32 -33.02 0)
				(effects
					(font
						(size 1.27 1.27)
					)
					(justify left bottom)
					(hide yes)
				)
			)
			(property "MPN" "GRM155R61H104KE14D"
				(at 20.32 -17.78 0)
				(effects
					(font
						(size 1.27 1.27)
						(thickness 0.15)
					)
					(justify left bottom)
					(hide yes)
				)
			)
			(property "Manufacturer" "Murata"
				(at 20.32 -20.32 0)
				(effects
					(font
						(size 1.27 1.27)
						(thickness 0.15)
					)
					(justify left bottom)
					(hide yes)
				)
			)
			(property "License" "Apache-2.0"
				(at 20.32 -22.86 0)
				(effects
					(font
						(size 1.27 1.27)
						(thickness 0.15)
					)
					(justify left bottom)
					(hide yes)
				)
			)
			(property "Author" "Antmicro"
				(at 20.32 -25.4 0)
				(effects
					(font
						(size 1.27 1.27)
						(thickness 0.15)
					)
					(justify left bottom)
					(hide yes)
				)
			)
			(property "Val" "100n"
				(at 20.32 -7.62 0)
				(effects
					(font
						(size 1.27 1.27)
						(thickness 0.15)
					)
					(justify left bottom)
				)
			)
			(property "Voltage" "50V"
				(at 20.32 -27.94 0)
				(effects
					(font
						(size 1.27 1.27)
					)
					(justify left bottom)
					(hide yes)
				)
			)
			(property "Dielectric" "X5R"
				(at 20.32 -30.48 0)
				(effects
					(font
						(size 1.27 1.27)
					)
					(justify left bottom)
					(hide yes)
				)
			)
			(property "ki_keywords" "0402, SMT, CAPACITOR, PASSIVE, CERAMIC, MLCC"
				(at 0 0 0)
				(effects
					(font
						(size 1.27 1.27)
					)
					(hide yes)
				)
			)
			(symbol "C_100n_0402_0_1"
				(polyline
					(pts
						(xy 2.032 -1.524) (xy 2.032 1.524)
					)
					(stroke
						(width 0.3048)
						(type default)
					)
					(fill
						(type none)
					)
				)
				(polyline
					(pts
						(xy 3.048 -1.524) (xy 3.048 1.524)
					)
					(stroke
						(width 0.3302)
						(type default)
					)
					(fill
						(type none)
					)
				)
			)
			(symbol "C_100n_0402_1_1"
				(pin passive line
					(at 0 0 0)
					(length 2.032)
					(name "~"
						(effects
							(font
								(size 1.27 1.27)
							)
						)
					)
					(number "1"
						(effects
							(font
								(size 1.27 1.27)
							)
						)
					)
				)
				(pin passive line
					(at 5.08 0 180)
					(length 2.032)
					(name "~"
						(effects
							(font
								(size 1.27 1.27)
							)
						)
					)
					(number "2"
						(effects
							(font
								(size 1.27 1.27)
							)
						)
					)
				)
			)
		)
	(symbol "antmicroCapacitors0402:C_10u_0402"
			(pin_numbers
				(hide yes)
			)
			(pin_names
				(hide yes)
			)
			(exclude_from_sim no)
			(in_bom yes)
			(on_board yes)
			(property "Reference" "C"
				(at 20.32 -5.08 0)
				(effects
					(font
						(size 1.27 1.27)
						(thickness 0.15)
					)
					(justify left bottom)
				)
			)
			(property "Value" "C_10u_0402"
				(at 20.32 -10.16 0)
				(effects
					(font
						(size 1.27 1.27)
						(thickness 0.15)
					)
					(justify left bottom)
					(hide yes)
				)
			)
			(property "Footprint" "antmicro-footprints:C_0402_1005Metric"
				(at 20.32 -12.7 0)
				(effects
					(font
						(size 1.27 1.27)
						(thickness 0.15)
					)
					(justify left bottom)
					(hide yes)
				)
			)
			(property "Datasheet" "https://www.yageo.com/en/Chart/Download/pdf/CC0402MRX5R5BB106"
				(at 20.32 -15.24 0)
				(effects
					(font
						(size 1.27 1.27)
						(thickness 0.15)
					)
					(justify left bottom)
					(hide yes)
				)
			)
			(property "Description" "SMD Multilayer Ceramic Capacitor, 10 µF, 6.3 V, 0402 [1005 Metric], ± 20%, X5R, CC Series"
				(at 20.32 -33.02 0)
				(effects
					(font
						(size 1.27 1.27)
					)
					(justify left bottom)
					(hide yes)
				)
			)
			(property "MPN" "CC0402MRX5R5BB106"
				(at 20.32 -17.78 0)
				(effects
					(font
						(size 1.27 1.27)
						(thickness 0.15)
					)
					(justify left bottom)
					(hide yes)
				)
			)
			(property "Manufacturer" "YAGEO"
				(at 20.32 -20.32 0)
				(effects
					(font
						(size 1.27 1.27)
						(thickness 0.15)
					)
					(justify left bottom)
					(hide yes)
				)
			)
			(property "License" "Apache-2.0"
				(at 20.32 -22.86 0)
				(effects
					(font
						(size 1.27 1.27)
						(thickness 0.15)
					)
					(justify left bottom)
					(hide yes)
				)
			)
			(property "Author" "Antmicro"
				(at 20.32 -25.4 0)
				(effects
					(font
						(size 1.27 1.27)
						(thickness 0.15)
					)
					(justify left bottom)
					(hide yes)
				)
			)
			(property "Val" "10u"
				(at 20.32 -7.62 0)
				(effects
					(font
						(size 1.27 1.27)
						(thickness 0.15)
					)
					(justify left bottom)
				)
			)
			(property "Voltage" ""
				(at 20.32 -27.94 0)
				(effects
					(font
						(size 1.27 1.27)
					)
					(justify left bottom)
					(hide yes)
				)
			)
			(property "Dielectric" ""
				(at 20.32 -30.48 0)
				(effects
					(font
						(size 1.27 1.27)
					)
					(justify left bottom)
					(hide yes)
				)
			)
			(property "ki_keywords" "0402, SMT, CAPACITOR, PASSIVE, MLCC, CERAMIC"
				(at 0 0 0)
				(effects
					(font
						(size 1.27 1.27)
					)
					(hide yes)
				)
			)
			(symbol "C_10u_0402_0_1"
				(polyline
					(pts
						(xy 2.032 -1.524) (xy 2.032 1.524)
					)
					(stroke
						(width 0.3048)
						(type default)
					)
					(fill
						(type none)
					)
				)
				(polyline
					(pts
						(xy 3.048 -1.524) (xy 3.048 1.524)
					)
					(stroke
						(width 0.3302)
						(type default)
					)
					(fill
						(type none)
					)
				)
			)
			(symbol "C_10u_0402_1_1"
				(pin passive line
					(at 0 0 0)
					(length 2.032)
					(name "~"
						(effects
							(font
								(size 1.27 1.27)
							)
						)
					)
					(number "1"
						(effects
							(font
								(size 1.27 1.27)
							)
						)
					)
				)
				(pin passive line
					(at 5.08 0 180)
					(length 2.032)
					(name "~"
						(effects
							(font
								(size 1.27 1.27)
							)
						)
					)
					(number "2"
						(effects
							(font
								(size 1.27 1.27)
							)
						)
					)
				)
			)
		)
	(symbol "antmicroCapacitors0402:C_1n_0402"
			(pin_numbers
				(hide yes)
			)
			(pin_names
				(hide yes)
			)
			(exclude_from_sim no)
			(in_bom yes)
			(on_board yes)
			(property "Reference" "C"
				(at 20.32 -5.08 0)
				(effects
					(font
						(size 1.27 1.27)
						(thickness 0.15)
					)
					(justify left bottom)
				)
			)
			(property "Value" "C_1n_0402"
				(at 20.32 -10.16 0)
				(effects
					(font
						(size 1.27 1.27)
						(thickness 0.15)
					)
					(justify left bottom)
					(hide yes)
				)
			)
			(property "Footprint" "antmicro-footprints:C_0402_1005Metric"
				(at 20.32 -12.7 0)
				(effects
					(font
						(size 1.27 1.27)
						(thickness 0.15)
					)
					(justify left bottom)
					(hide yes)
				)
			)
			(property "Datasheet" "https://www.murata.com/products/productdetail?partno=GRM1555C1H102JA01%23"
				(at 20.32 -15.24 0)
				(effects
					(font
						(size 1.27 1.27)
						(thickness 0.15)
					)
					(justify left bottom)
					(hide yes)
				)
			)
			(property "Description" "SMD Multilayer Ceramic Capacitor, 1000 pF, 50 V, 0402 [1005 Metric], ± 5%, C0G / NP0, GRM Series"
				(at 20.32 -33.02 0)
				(effects
					(font
						(size 1.27 1.27)
					)
					(justify left bottom)
					(hide yes)
				)
			)
			(property "MPN" "GRM1555C1H102JA01D"
				(at 20.32 -17.78 0)
				(effects
					(font
						(size 1.27 1.27)
						(thickness 0.15)
					)
					(justify left bottom)
					(hide yes)
				)
			)
			(property "Manufacturer" "Murata"
				(at 20.32 -20.32 0)
				(effects
					(font
						(size 1.27 1.27)
						(thickness 0.15)
					)
					(justify left bottom)
					(hide yes)
				)
			)
			(property "License" "Apache-2.0"
				(at 20.32 -22.86 0)
				(effects
					(font
						(size 1.27 1.27)
						(thickness 0.15)
					)
					(justify left bottom)
					(hide yes)
				)
			)
			(property "Author" "Antmicro"
				(at 20.32 -25.4 0)
				(effects
					(font
						(size 1.27 1.27)
						(thickness 0.15)
					)
					(justify left bottom)
					(hide yes)
				)
			)
			(property "Val" "1n"
				(at 20.32 -7.62 0)
				(effects
					(font
						(size 1.27 1.27)
						(thickness 0.15)
					)
					(justify left bottom)
				)
			)
			(property "Voltage" "50V"
				(at 20.32 -27.94 0)
				(effects
					(font
						(size 1.27 1.27)
					)
					(justify left bottom)
					(hide yes)
				)
			)
			(property "Dielectric" "C0G"
				(at 20.32 -30.48 0)
				(effects
					(font
						(size 1.27 1.27)
					)
					(justify left bottom)
					(hide yes)
				)
			)
			(property "ki_keywords" "0402, SMT, CAPACITOR, PASSIVE, CERAMIC, MLCC"
				(at 0 0 0)
				(effects
					(font
						(size 1.27 1.27)
					)
					(hide yes)
				)
			)
			(symbol "C_1n_0402_0_1"
				(polyline
					(pts
						(xy 2.032 -1.524) (xy 2.032 1.524)
					)
					(stroke
						(width 0.3048)
						(type default)
					)
					(fill
						(type none)
					)
				)
				(polyline
					(pts
						(xy 3.048 -1.524) (xy 3.048 1.524)
					)
					(stroke
						(width 0.3302)
						(type default)
					)
					(fill
						(type none)
					)
				)
			)
			(symbol "C_1n_0402_1_1"
				(pin passive line
					(at 0 0 0)
					(length 2.032)
					(name "~"
						(effects
							(font
								(size 1.27 1.27)
							)
						)
					)
					(number "1"
						(effects
							(font
								(size 1.27 1.27)
							)
						)
					)
				)
				(pin passive line
					(at 5.08 0 180)
					(length 2.032)
					(name "~"
						(effects
							(font
								(size 1.27 1.27)
							)
						)
					)
					(number "2"
						(effects
							(font
								(size 1.27 1.27)
							)
						)
					)
				)
			)
		)
	(symbol "antmicroCapacitors0402:C_1u_0402"
			(pin_numbers
				(hide yes)
			)
			(pin_names
				(hide yes)
			)
			(exclude_from_sim no)
			(in_bom yes)
			(on_board yes)
			(property "Reference" "C"
				(at 20.32 -5.08 0)
				(effects
					(font
						(size 1.27 1.27)
						(thickness 0.15)
					)
					(justify left bottom)
				)
			)
			(property "Value" "C_1u_0402"
				(at 20.32 -10.16 0)
				(effects
					(font
						(size 1.27 1.27)
						(thickness 0.15)
					)
					(justify left bottom)
					(hide yes)
				)
			)
			(property "Footprint" "antmicro-footprints:C_0402_1005Metric"
				(at 20.32 -12.7 0)
				(effects
					(font
						(size 1.27 1.27)
						(thickness 0.15)
					)
					(justify left bottom)
					(hide yes)
				)
			)
			(property "Datasheet" "https://product.tdk.com/en/search/capacitor/ceramic/mlcc/info?part_no=C1005X6S1A105K050BC"
				(at 20.32 -15.24 0)
				(effects
					(font
						(size 1.27 1.27)
						(thickness 0.15)
					)
					(justify left bottom)
					(hide yes)
				)
			)
			(property "Description" "SMD Multilayer Ceramic Capacitor, 1 µF, 10 V, 0402 [1005 Metric], ± 10%, X6S, C"
				(at 20.32 -33.02 0)
				(effects
					(font
						(size 1.27 1.27)
					)
					(justify left bottom)
					(hide yes)
				)
			)
			(property "MPN" "C1005X6S1A105K050BC"
				(at 20.32 -17.78 0)
				(effects
					(font
						(size 1.27 1.27)
						(thickness 0.15)
					)
					(justify left bottom)
					(hide yes)
				)
			)
			(property "Manufacturer" "TDK"
				(at 20.32 -20.32 0)
				(effects
					(font
						(size 1.27 1.27)
						(thickness 0.15)
					)
					(justify left bottom)
					(hide yes)
				)
			)
			(property "License" "Apache-2.0"
				(at 20.32 -22.86 0)
				(effects
					(font
						(size 1.27 1.27)
						(thickness 0.15)
					)
					(justify left bottom)
					(hide yes)
				)
			)
			(property "Author" "Antmicro"
				(at 20.32 -25.4 0)
				(effects
					(font
						(size 1.27 1.27)
						(thickness 0.15)
					)
					(justify left bottom)
					(hide yes)
				)
			)
			(property "Val" "1u"
				(at 20.32 -7.62 0)
				(effects
					(font
						(size 1.27 1.27)
						(thickness 0.15)
					)
					(justify left bottom)
				)
			)
			(property "Voltage" ""
				(at 20.32 -27.94 0)
				(effects
					(font
						(size 1.27 1.27)
					)
					(justify left bottom)
					(hide yes)
				)
			)
			(property "Dielectric" ""
				(at 20.32 -30.48 0)
				(effects
					(font
						(size 1.27 1.27)
					)
					(justify left bottom)
					(hide yes)
				)
			)
			(property "ki_keywords" "0402, SMT, CAPACITOR, PASSIVE, CERAMIC, MLCC"
				(at 0 0 0)
				(effects
					(font
						(size 1.27 1.27)
					)
					(hide yes)
				)
			)
			(symbol "C_1u_0402_0_1"
				(polyline
					(pts
						(xy 2.032 -1.524) (xy 2.032 1.524)
					)
					(stroke
						(width 0.3048)
						(type default)
					)
					(fill
						(type none)
					)
				)
				(polyline
					(pts
						(xy 3.048 -1.524) (xy 3.048 1.524)
					)
					(stroke
						(width 0.3302)
						(type default)
					)
					(fill
						(type none)
					)
				)
			)
			(symbol "C_1u_0402_1_1"
				(pin passive line
					(at 0 0 0)
					(length 2.032)
					(name "~"
						(effects
							(font
								(size 1.27 1.27)
							)
						)
					)
					(number "1"
						(effects
							(font
								(size 1.27 1.27)
							)
						)
					)
				)
				(pin passive line
					(at 5.08 0 180)
					(length 2.032)
					(name "~"
						(effects
							(font
								(size 1.27 1.27)
							)
						)
					)
					(number "2"
						(effects
							(font
								(size 1.27 1.27)
							)
						)
					)
				)
			)
		)
	(symbol "antmicroCapacitors0402:C_1u_25V_0402"
			(pin_numbers
				(hide yes)
			)
			(pin_names
				(hide yes)
			)
			(exclude_from_sim no)
			(in_bom yes)
			(on_board yes)
			(property "Reference" "C"
				(at 20.32 -5.08 0)
				(effects
					(font
						(size 1.27 1.27)
						(thickness 0.15)
					)
					(justify left bottom)
				)
			)
			(property "Value" "C_1u_25V_0402"
				(at 20.32 -10.16 0)
				(effects
					(font
						(size 1.27 1.27)
						(thickness 0.15)
					)
					(justify left bottom)
					(hide yes)
				)
			)
			(property "Footprint" "antmicro-footprints:C_0402_1005Metric"
				(at 20.32 -12.7 0)
				(effects
					(font
						(size 1.27 1.27)
						(thickness 0.15)
					)
					(justify left bottom)
					(hide yes)
				)
			)
			(property "Datasheet" "https://www.murata.com/products/productdetail?partno=GRM155R61E105KE11%23"
				(at 20.32 -15.24 0)
				(effects
					(font
						(size 1.27 1.27)
						(thickness 0.15)
					)
					(justify left bottom)
					(hide yes)
				)
			)
			(property "Description" "SMD Multilayer Ceramic Capacitor, 1 µF, 25 V, 0402 [1005 Metric], ± 10%, X5R, GRM Series"
				(at 20.32 -33.02 0)
				(effects
					(font
						(size 1.27 1.27)
					)
					(justify left bottom)
					(hide yes)
				)
			)
			(property "MPN" "GRM155R61E105KE11J"
				(at 20.32 -17.78 0)
				(effects
					(font
						(size 1.27 1.27)
						(thickness 0.15)
					)
					(justify left bottom)
					(hide yes)
				)
			)
			(property "Manufacturer" "Murata"
				(at 20.32 -20.32 0)
				(effects
					(font
						(size 1.27 1.27)
						(thickness 0.15)
					)
					(justify left bottom)
					(hide yes)
				)
			)
			(property "License" "Apache-2.0"
				(at 20.32 -22.86 0)
				(effects
					(font
						(size 1.27 1.27)
						(thickness 0.15)
					)
					(justify left bottom)
					(hide yes)
				)
			)
			(property "Author" "Antmicro"
				(at 20.32 -25.4 0)
				(effects
					(font
						(size 1.27 1.27)
						(thickness 0.15)
					)
					(justify left bottom)
					(hide yes)
				)
			)
			(property "Val" "1u"
				(at 20.32 -7.62 0)
				(effects
					(font
						(size 1.27 1.27)
						(thickness 0.15)
					)
					(justify left bottom)
				)
			)
			(property "Voltage" "25V"
				(at 20.32 -27.94 0)
				(effects
					(font
						(size 1.27 1.27)
					)
					(justify left bottom)
					(hide yes)
				)
			)
			(property "Dielectric" "X5R"
				(at 20.32 -30.48 0)
				(effects
					(font
						(size 1.27 1.27)
					)
					(justify left bottom)
					(hide yes)
				)
			)
			(property "ki_keywords" "0402, SMT, CAPACITOR, PASSIVE, CERAMIC"
				(at 0 0 0)
				(effects
					(font
						(size 1.27 1.27)
					)
					(hide yes)
				)
			)
			(symbol "C_1u_25V_0402_0_1"
				(polyline
					(pts
						(xy 2.032 -1.524) (xy 2.032 1.524)
					)
					(stroke
						(width 0.3048)
						(type default)
					)
					(fill
						(type none)
					)
				)
				(polyline
					(pts
						(xy 3.048 -1.524) (xy 3.048 1.524)
					)
					(stroke
						(width 0.3302)
						(type default)
					)
					(fill
						(type none)
					)
				)
			)
			(symbol "C_1u_25V_0402_1_1"
				(pin passive line
					(at 0 0 0)
					(length 2.032)
					(name "~"
						(effects
							(font
								(size 1.27 1.27)
							)
						)
					)
					(number "1"
						(effects
							(font
								(size 1.27 1.27)
							)
						)
					)
				)
				(pin passive line
					(at 5.08 0 180)
					(length 2.032)
					(name "~"
						(effects
							(font
								(size 1.27 1.27)
							)
						)
					)
					(number "2"
						(effects
							(font
								(size 1.27 1.27)
							)
						)
					)
				)
			)
		)
	(symbol "antmicroCapacitors0402:C_220n_0402"
			(pin_numbers
				(hide yes)
			)
			(pin_names
				(hide yes)
			)
			(exclude_from_sim no)
			(in_bom yes)
			(on_board yes)
			(property "Reference" "C"
				(at 20.32 -5.08 0)
				(effects
					(font
						(size 1.27 1.27)
						(thickness 0.15)
					)
					(justify left bottom)
				)
			)
			(property "Value" "C_220n_0402"
				(at 20.32 -10.16 0)
				(effects
					(font
						(size 1.27 1.27)
						(thickness 0.15)
					)
					(justify left bottom)
					(hide yes)
				)
			)
			(property "Footprint" "antmicro-footprints:C_0402_1005Metric"
				(at 20.32 -12.7 0)
				(effects
					(font
						(size 1.27 1.27)
						(thickness 0.15)
					)
					(justify left bottom)
					(hide yes)
				)
			)
			(property "Datasheet" "https://www.yageo.com/en/Chart/Download/pdf/CC0402KRX5R6BB224"
				(at 20.32 -15.24 0)
				(effects
					(font
						(size 1.27 1.27)
						(thickness 0.15)
					)
					(justify left bottom)
					(hide yes)
				)
			)
			(property "Description" "SMD Multilayer Ceramic Capacitor, 0.22 µF, 10 V, 0402 [1005 Metric], ± 10%, X5R, CC Series"
				(at 20.32 -33.02 0)
				(effects
					(font
						(size 1.27 1.27)
					)
					(justify left bottom)
					(hide yes)
				)
			)
			(property "MPN" "CC0402KRX5R6BB224"
				(at 20.32 -17.78 0)
				(effects
					(font
						(size 1.27 1.27)
						(thickness 0.15)
					)
					(justify left bottom)
					(hide yes)
				)
			)
			(property "Manufacturer" "YAGEO"
				(at 20.32 -20.32 0)
				(effects
					(font
						(size 1.27 1.27)
						(thickness 0.15)
					)
					(justify left bottom)
					(hide yes)
				)
			)
			(property "License" "Apache-2.0"
				(at 20.32 -22.86 0)
				(effects
					(font
						(size 1.27 1.27)
						(thickness 0.15)
					)
					(justify left bottom)
					(hide yes)
				)
			)
			(property "Author" "Antmicro"
				(at 20.32 -25.4 0)
				(effects
					(font
						(size 1.27 1.27)
						(thickness 0.15)
					)
					(justify left bottom)
					(hide yes)
				)
			)
			(property "Val" "220n"
				(at 20.32 -7.62 0)
				(effects
					(font
						(size 1.27 1.27)
						(thickness 0.15)
					)
					(justify left bottom)
				)
			)
			(property "Voltage" ""
				(at 20.32 -27.94 0)
				(effects
					(font
						(size 1.27 1.27)
					)
					(justify left bottom)
					(hide yes)
				)
			)
			(property "Dielectric" ""
				(at 20.32 -30.48 0)
				(effects
					(font
						(size 1.27 1.27)
					)
					(justify left bottom)
					(hide yes)
				)
			)
			(property "ki_keywords" "0402, SMT, CAPACITOR, PASSIVE, MLCC, CERAMIC"
				(at 0 0 0)
				(effects
					(font
						(size 1.27 1.27)
					)
					(hide yes)
				)
			)
			(symbol "C_220n_0402_0_1"
				(polyline
					(pts
						(xy 2.032 -1.524) (xy 2.032 1.524)
					)
					(stroke
						(width 0.3048)
						(type default)
					)
					(fill
						(type none)
					)
				)
				(polyline
					(pts
						(xy 3.048 -1.524) (xy 3.048 1.524)
					)
					(stroke
						(width 0.3302)
						(type default)
					)
					(fill
						(type none)
					)
				)
			)
			(symbol "C_220n_0402_1_1"
				(pin passive line
					(at 0 0 0)
					(length 2.032)
					(name "~"
						(effects
							(font
								(size 1.27 1.27)
							)
						)
					)
					(number "1"
						(effects
							(font
								(size 1.27 1.27)
							)
						)
					)
				)
				(pin passive line
					(at 5.08 0 180)
					(length 2.032)
					(name "~"
						(effects
							(font
								(size 1.27 1.27)
							)
						)
					)
					(number "2"
						(effects
							(font
								(size 1.27 1.27)
							)
						)
					)
				)
			)
		)
	(symbol "antmicroCapacitors0402:C_47p_0402"
			(pin_numbers
				(hide yes)
			)
			(pin_names
				(hide yes)
			)
			(exclude_from_sim no)
			(in_bom yes)
			(on_board yes)
			(property "Reference" "C"
				(at 20.32 -5.08 0)
				(effects
					(font
						(size 1.27 1.27)
						(thickness 0.15)
					)
					(justify left bottom)
				)
			)
			(property "Value" "C_47p_0402"
				(at 20.32 -10.16 0)
				(effects
					(font
						(size 1.27 1.27)
						(thickness 0.15)
					)
					(justify left bottom)
					(hide yes)
				)
			)
			(property "Footprint" "antmicro-footprints:C_0402_1005Metric"
				(at 20.32 -12.7 0)
				(effects
					(font
						(size 1.27 1.27)
						(thickness 0.15)
					)
					(justify left bottom)
					(hide yes)
				)
			)
			(property "Datasheet" "https://www.kemet.com/en/us/capacitors/product/C0402C470J5GACTU.html"
				(at 20.32 -15.24 0)
				(effects
					(font
						(size 1.27 1.27)
						(thickness 0.15)
					)
					(justify left bottom)
					(hide yes)
				)
			)
			(property "Description" "SMD Multilayer Ceramic Capacitor, 47 pF, 50 V, 0402 [1005 Metric], ± 5%, C0G / NP0, C Series KEMET"
				(at 20.32 -33.02 0)
				(effects
					(font
						(size 1.27 1.27)
					)
					(justify left bottom)
					(hide yes)
				)
			)
			(property "MPN" "C0402C470J5GACTU"
				(at 20.32 -17.78 0)
				(effects
					(font
						(size 1.27 1.27)
						(thickness 0.15)
					)
					(justify left bottom)
					(hide yes)
				)
			)
			(property "Manufacturer" "KEMET"
				(at 20.32 -20.32 0)
				(effects
					(font
						(size 1.27 1.27)
						(thickness 0.15)
					)
					(justify left bottom)
					(hide yes)
				)
			)
			(property "License" "Apache-2.0"
				(at 20.32 -22.86 0)
				(effects
					(font
						(size 1.27 1.27)
						(thickness 0.15)
					)
					(justify left bottom)
					(hide yes)
				)
			)
			(property "Author" "Antmicro"
				(at 20.32 -25.4 0)
				(effects
					(font
						(size 1.27 1.27)
						(thickness 0.15)
					)
					(justify left bottom)
					(hide yes)
				)
			)
			(property "Val" "47p"
				(at 20.32 -7.62 0)
				(effects
					(font
						(size 1.27 1.27)
						(thickness 0.15)
					)
					(justify left bottom)
				)
			)
			(property "Voltage" ""
				(at 20.32 -27.94 0)
				(effects
					(font
						(size 1.27 1.27)
					)
					(justify left bottom)
					(hide yes)
				)
			)
			(property "Dielectric" "C0G"
				(at 20.32 -30.48 0)
				(effects
					(font
						(size 1.27 1.27)
					)
					(justify left bottom)
					(hide yes)
				)
			)
			(property "ki_keywords" "0402, SMT, CAPACITOR, PASSIVE, CERAMIC, MLCC"
				(at 0 0 0)
				(effects
					(font
						(size 1.27 1.27)
					)
					(hide yes)
				)
			)
			(symbol "C_47p_0402_0_1"
				(polyline
					(pts
						(xy 2.032 -1.524) (xy 2.032 1.524)
					)
					(stroke
						(width 0.3048)
						(type default)
					)
					(fill
						(type none)
					)
				)
				(polyline
					(pts
						(xy 3.048 -1.524) (xy 3.048 1.524)
					)
					(stroke
						(width 0.3302)
						(type default)
					)
					(fill
						(type none)
					)
				)
			)
			(symbol "C_47p_0402_1_1"
				(pin passive line
					(at 0 0 0)
					(length 2.032)
					(name "~"
						(effects
							(font
								(size 1.27 1.27)
							)
						)
					)
					(number "1"
						(effects
							(font
								(size 1.27 1.27)
							)
						)
					)
				)
				(pin passive line
					(at 5.08 0 180)
					(length 2.032)
					(name "~"
						(effects
							(font
								(size 1.27 1.27)
							)
						)
					)
					(number "2"
						(effects
							(font
								(size 1.27 1.27)
							)
						)
					)
				)
			)
		)
	(symbol "antmicroCapacitors0402:C_4u7_25V_0402"
			(pin_numbers
				(hide yes)
			)
			(pin_names
				(hide yes)
			)
			(exclude_from_sim no)
			(in_bom yes)
			(on_board yes)
			(property "Reference" "C"
				(at 20.32 -5.08 0)
				(effects
					(font
						(size 1.27 1.27)
						(thickness 0.15)
					)
					(justify left bottom)
				)
			)
			(property "Value" "C_4u7_25V_0402"
				(at 20.32 -10.16 0)
				(effects
					(font
						(size 1.27 1.27)
						(thickness 0.15)
					)
					(justify left bottom)
					(hide yes)
				)
			)
			(property "Footprint" "antmicro-footprints:C_0402_1005Metric"
				(at 20.32 -12.7 0)
				(effects
					(font
						(size 1.27 1.27)
						(thickness 0.15)
					)
					(justify left bottom)
					(hide yes)
				)
			)
			(property "Datasheet" "https://www.murata.com/products/productdetail?partno=GRM155C61E475ME15%23"
				(at 20.32 -15.24 0)
				(effects
					(font
						(size 1.27 1.27)
						(thickness 0.15)
					)
					(justify left bottom)
					(hide yes)
				)
			)
			(property "Description" "SMD Multilayer Ceramic Capacitor"
				(at 20.32 -33.02 0)
				(effects
					(font
						(size 1.27 1.27)
					)
					(justify left bottom)
					(hide yes)
				)
			)
			(property "MPN" "GRM155C61E475ME15J"
				(at 20.32 -17.78 0)
				(effects
					(font
						(size 1.27 1.27)
						(thickness 0.15)
					)
					(justify left bottom)
					(hide yes)
				)
			)
			(property "Manufacturer" "Murata"
				(at 20.32 -20.32 0)
				(effects
					(font
						(size 1.27 1.27)
						(thickness 0.15)
					)
					(justify left bottom)
					(hide yes)
				)
			)
			(property "License" "Apache-2.0"
				(at 20.32 -22.86 0)
				(effects
					(font
						(size 1.27 1.27)
						(thickness 0.15)
					)
					(justify left bottom)
					(hide yes)
				)
			)
			(property "Author" "Antmicro"
				(at 20.32 -25.4 0)
				(effects
					(font
						(size 1.27 1.27)
						(thickness 0.15)
					)
					(justify left bottom)
					(hide yes)
				)
			)
			(property "Val" "4u7"
				(at 20.32 -7.62 0)
				(effects
					(font
						(size 1.27 1.27)
						(thickness 0.15)
					)
					(justify left bottom)
				)
			)
			(property "Voltage" "25V"
				(at 20.32 -27.94 0)
				(effects
					(font
						(size 1.27 1.27)
					)
					(justify left bottom)
					(hide yes)
				)
			)
			(property "Dielectric" "X5S"
				(at 20.32 -30.48 0)
				(effects
					(font
						(size 1.27 1.27)
					)
					(justify left bottom)
					(hide yes)
				)
			)
			(property "ki_keywords" "0402, SMT, CAPACITOR, PASSIVE, CERAMIC"
				(at 0 0 0)
				(effects
					(font
						(size 1.27 1.27)
					)
					(hide yes)
				)
			)
			(symbol "C_4u7_25V_0402_0_1"
				(polyline
					(pts
						(xy 2.032 -1.524) (xy 2.032 1.524)
					)
					(stroke
						(width 0.3048)
						(type default)
					)
					(fill
						(type none)
					)
				)
				(polyline
					(pts
						(xy 3.048 -1.524) (xy 3.048 1.524)
					)
					(stroke
						(width 0.3302)
						(type default)
					)
					(fill
						(type none)
					)
				)
			)
			(symbol "C_4u7_25V_0402_1_1"
				(pin passive line
					(at 0 0 0)
					(length 2.032)
					(name "~"
						(effects
							(font
								(size 1.27 1.27)
							)
						)
					)
					(number "1"
						(effects
							(font
								(size 1.27 1.27)
							)
						)
					)
				)
				(pin passive line
					(at 5.08 0 180)
					(length 2.032)
					(name "~"
						(effects
							(font
								(size 1.27 1.27)
							)
						)
					)
					(number "2"
						(effects
							(font
								(size 1.27 1.27)
							)
						)
					)
				)
			)
		)
	(symbol "antmicroCapacitors0603:C_22u_16V_0603"
			(pin_numbers
				(hide yes)
			)
			(pin_names
				(hide yes)
			)
			(exclude_from_sim no)
			(in_bom yes)
			(on_board yes)
			(property "Reference" "C"
				(at 20.32 -5.08 0)
				(effects
					(font
						(size 1.27 1.27)
						(thickness 0.15)
					)
					(justify left bottom)
				)
			)
			(property "Value" "C_22u_16V_0603"
				(at 20.32 -10.16 0)
				(effects
					(font
						(size 1.27 1.27)
						(thickness 0.15)
					)
					(justify left bottom)
					(hide yes)
				)
			)
			(property "Footprint" "antmicro-footprints:C_0603_1608Metric_EIA"
				(at 20.32 -12.7 0)
				(effects
					(font
						(size 1.27 1.27)
						(thickness 0.15)
					)
					(justify left bottom)
					(hide yes)
				)
			)
			(property "Datasheet" "https://product.samsungsem.com/mlcc/CL10A226MO7JZN.do"
				(at 20.32 -15.24 0)
				(effects
					(font
						(size 1.27 1.27)
						(thickness 0.15)
					)
					(justify left bottom)
					(hide yes)
				)
			)
			(property "Description" "SMD Multilayer Ceramic Capacitor"
				(at 20.32 -33.02 0)
				(effects
					(font
						(size 1.27 1.27)
					)
					(justify left bottom)
					(hide yes)
				)
			)
			(property "MPN" "CL10A226MO7JZNC"
				(at 20.32 -17.78 0)
				(effects
					(font
						(size 1.27 1.27)
						(thickness 0.15)
					)
					(justify left bottom)
					(hide yes)
				)
			)
			(property "Manufacturer" "Samsung Electro-Mechanics"
				(at 20.32 -20.32 0)
				(effects
					(font
						(size 1.27 1.27)
						(thickness 0.15)
					)
					(justify left bottom)
					(hide yes)
				)
			)
			(property "License" "Apache-2.0"
				(at 20.32 -22.86 0)
				(effects
					(font
						(size 1.27 1.27)
						(thickness 0.15)
					)
					(justify left bottom)
					(hide yes)
				)
			)
			(property "Author" "Antmicro"
				(at 20.32 -25.4 0)
				(effects
					(font
						(size 1.27 1.27)
						(thickness 0.15)
					)
					(justify left bottom)
					(hide yes)
				)
			)
			(property "Val" "22u"
				(at 20.32 -7.62 0)
				(effects
					(font
						(size 1.27 1.27)
						(thickness 0.15)
					)
					(justify left bottom)
				)
			)
			(property "Voltage" "16V"
				(at 20.32 -27.94 0)
				(effects
					(font
						(size 1.27 1.27)
					)
					(justify left bottom)
					(hide yes)
				)
			)
			(property "Dielectric" ""
				(at 20.32 -30.48 0)
				(effects
					(font
						(size 1.27 1.27)
					)
					(justify left bottom)
					(hide yes)
				)
			)
			(property "ki_keywords" "0603, SMT, CAPACITOR, PASSIVE, CERAMIC"
				(at 0 0 0)
				(effects
					(font
						(size 1.27 1.27)
					)
					(hide yes)
				)
			)
			(symbol "C_22u_16V_0603_0_1"
				(polyline
					(pts
						(xy 2.032 -1.524) (xy 2.032 1.524)
					)
					(stroke
						(width 0.3048)
						(type default)
					)
					(fill
						(type none)
					)
				)
				(polyline
					(pts
						(xy 3.048 -1.524) (xy 3.048 1.524)
					)
					(stroke
						(width 0.3302)
						(type default)
					)
					(fill
						(type none)
					)
				)
			)
			(symbol "C_22u_16V_0603_1_1"
				(pin passive line
					(at 0 0 0)
					(length 2.032)
					(name "~"
						(effects
							(font
								(size 1.27 1.27)
							)
						)
					)
					(number "1"
						(effects
							(font
								(size 1.27 1.27)
							)
						)
					)
				)
				(pin passive line
					(at 5.08 0 180)
					(length 2.032)
					(name "~"
						(effects
							(font
								(size 1.27 1.27)
							)
						)
					)
					(number "2"
						(effects
							(font
								(size 1.27 1.27)
							)
						)
					)
				)
			)
		)
	(symbol "antmicroCapacitorsmisc:C_22u_25V_0805"
			(pin_numbers
				(hide yes)
			)
			(pin_names
				(hide yes)
			)
			(exclude_from_sim no)
			(in_bom yes)
			(on_board yes)
			(property "Reference" "C"
				(at 20.32 -5.08 0)
				(effects
					(font
						(size 1.27 1.27)
						(thickness 0.15)
					)
					(justify left bottom)
				)
			)
			(property "Value" "C_22u_25V_0805"
				(at 20.32 -10.16 0)
				(effects
					(font
						(size 1.27 1.27)
						(thickness 0.15)
					)
					(justify left bottom)
					(hide yes)
				)
			)
			(property "Footprint" "antmicro-footprints:C_0805_2012Metric"
				(at 20.32 -12.7 0)
				(effects
					(font
						(size 1.27 1.27)
						(thickness 0.15)
					)
					(justify left bottom)
					(hide yes)
				)
			)
			(property "Datasheet" "https://product.samsungsem.com/mlcc/CL21A226MAYNNN.do"
				(at 20.32 -15.24 0)
				(effects
					(font
						(size 1.27 1.27)
						(thickness 0.15)
					)
					(justify left bottom)
					(hide yes)
				)
			)
			(property "Description" "SMT Multilayer Ceramic Capacitor, 22uF, +/-20%, 25V, X5R, 0805 [2012 Metric]"
				(at 20.32 -33.02 0)
				(effects
					(font
						(size 1.27 1.27)
					)
					(justify left bottom)
					(hide yes)
				)
			)
			(property "MPN" "CL21A226MAYNNNE"
				(at 20.32 -17.78 0)
				(effects
					(font
						(size 1.27 1.27)
						(thickness 0.15)
					)
					(justify left bottom)
					(hide yes)
				)
			)
			(property "Manufacturer" "Samsung Electro-Mechanics"
				(at 20.32 -20.32 0)
				(effects
					(font
						(size 1.27 1.27)
						(thickness 0.15)
					)
					(justify left bottom)
					(hide yes)
				)
			)
			(property "License" "Apache-2.0"
				(at 20.32 -22.86 0)
				(effects
					(font
						(size 1.27 1.27)
						(thickness 0.15)
					)
					(justify left bottom)
					(hide yes)
				)
			)
			(property "Author" "Antmicro"
				(at 20.32 -25.4 0)
				(effects
					(font
						(size 1.27 1.27)
						(thickness 0.15)
					)
					(justify left bottom)
					(hide yes)
				)
			)
			(property "Val" "22u"
				(at 20.32 -7.62 0)
				(effects
					(font
						(size 1.27 1.27)
						(thickness 0.15)
					)
					(justify left bottom)
				)
			)
			(property "Voltage" "25V"
				(at 20.32 -27.94 0)
				(effects
					(font
						(size 1.27 1.27)
					)
					(justify left bottom)
				)
			)
			(property "Dielectric" "X5R"
				(at 20.32 -30.48 0)
				(effects
					(font
						(size 1.27 1.27)
					)
					(justify left bottom)
					(hide yes)
				)
			)
			(property "Public" "False"
				(at 20.32 -33.02 0)
				(effects
					(font
						(size 1.27 1.27)
					)
					(justify left bottom)
					(hide yes)
				)
			)
			(property "ki_keywords" "0805, SMT, CAPACITOR, PASSIVE"
				(at 0 0 0)
				(effects
					(font
						(size 1.27 1.27)
					)
					(hide yes)
				)
			)
			(symbol "C_22u_25V_0805_0_1"
				(polyline
					(pts
						(xy 2.032 -1.524) (xy 2.032 1.524)
					)
					(stroke
						(width 0.3048)
						(type default)
					)
					(fill
						(type none)
					)
				)
				(polyline
					(pts
						(xy 3.048 -1.524) (xy 3.048 1.524)
					)
					(stroke
						(width 0.3302)
						(type default)
					)
					(fill
						(type none)
					)
				)
			)
			(symbol "C_22u_25V_0805_1_1"
				(pin passive line
					(at 0 0 0)
					(length 2.032)
					(name "~"
						(effects
							(font
								(size 1.27 1.27)
							)
						)
					)
					(number "1"
						(effects
							(font
								(size 1.27 1.27)
							)
						)
					)
				)
				(pin passive line
					(at 5.08 0 180)
					(length 2.032)
					(name "~"
						(effects
							(font
								(size 1.27 1.27)
							)
						)
					)
					(number "2"
						(effects
							(font
								(size 1.27 1.27)
							)
						)
					)
				)
			)
		)
	(symbol "antmicroClockTimingProgrammableTimersandOscillators:LTC6994CDCB-1_DFN"
			(exclude_from_sim no)
			(in_bom yes)
			(on_board yes)
			(property "Reference" "U"
				(at 2.54 3.048 0)
				(effects
					(font
						(size 1.27 1.27)
						(thickness 0.15)
					)
					(justify left bottom)
				)
			)
			(property "Value" "LTC6994CDCB-1_DFN"
				(at -0.254 -15.24 0)
				(effects
					(font
						(size 1.27 1.27)
						(thickness 0.15)
					)
					(justify left bottom)
					(hide yes)
				)
			)
			(property "Footprint" "antmicro-footprints:DFN-6-1EP_3x2mm_P0.5mm_EP1.65x1.35mm"
				(at -0.254 -17.78 0)
				(effects
					(font
						(size 1.27 1.27)
						(thickness 0.15)
					)
					(justify left bottom)
					(hide yes)
				)
			)
			(property "Datasheet" "https://www.analog.com/media/en/technical-documentation/data-sheets/699412fb.pdf"
				(at -0.254 -20.32 0)
				(effects
					(font
						(size 1.27 1.27)
						(thickness 0.15)
					)
					(justify left bottom)
					(hide yes)
				)
			)
			(property "Description" "Programmable delay block"
				(at -0.254 -30.48 0)
				(effects
					(font
						(size 1.27 1.27)
					)
					(justify left bottom)
					(hide yes)
				)
			)
			(property "MPN" "LTC6994CDCB-1#TRMPBF"
				(at -0.254 -12.7 0)
				(effects
					(font
						(size 1.27 1.27)
						(thickness 0.15)
					)
					(justify left bottom)
				)
			)
			(property "Manufacturer" "Analog Devices"
				(at -0.254 -22.86 0)
				(effects
					(font
						(size 1.27 1.27)
						(thickness 0.15)
					)
					(justify left bottom)
					(hide yes)
				)
			)
			(property "Author" "Antmicro"
				(at -0.254 -25.4 0)
				(effects
					(font
						(size 1.27 1.27)
						(thickness 0.15)
					)
					(justify left bottom)
					(hide yes)
				)
			)
			(property "License" "Apache-2.0"
				(at -0.254 -27.94 0)
				(effects
					(font
						(size 1.27 1.27)
						(thickness 0.15)
					)
					(justify left bottom)
					(hide yes)
				)
			)
			(property "ki_keywords" "IC, SMT"
				(at 0 0 0)
				(effects
					(font
						(size 1.27 1.27)
					)
					(hide yes)
				)
			)
			(symbol "LTC6994CDCB-1_DFN_1_1"
				(rectangle
					(start 2.54 2.54)
					(end 15.24 -10.16)
					(stroke
						(width 0.254)
						(type default)
					)
					(fill
						(type background)
					)
				)
				(pin input line
					(at 0 0 0)
					(length 2.54)
					(name "IN"
						(effects
							(font
								(size 1.27 1.27)
							)
						)
					)
					(number "4"
						(effects
							(font
								(size 1.27 1.27)
							)
						)
					)
				)
				(pin passive line
					(at 0 -2.54 0)
					(length 2.54)
					(name "SET"
						(effects
							(font
								(size 1.27 1.27)
							)
						)
					)
					(number "3"
						(effects
							(font
								(size 1.27 1.27)
							)
						)
					)
				)
				(pin passive line
					(at 0 -5.08 0)
					(length 2.54)
					(name "EP"
						(effects
							(font
								(size 1.27 1.27)
							)
						)
					)
					(number "7"
						(effects
							(font
								(size 1.27 1.27)
							)
						)
					)
				)
				(pin power_in line
					(at 0 -7.62 0)
					(length 2.54)
					(name "GND"
						(effects
							(font
								(size 1.27 1.27)
							)
						)
					)
					(number "5"
						(effects
							(font
								(size 1.27 1.27)
							)
						)
					)
				)
				(pin power_in line
					(at 17.78 0 180)
					(length 2.54)
					(name "V+"
						(effects
							(font
								(size 1.27 1.27)
							)
						)
					)
					(number "1"
						(effects
							(font
								(size 1.27 1.27)
							)
						)
					)
				)
				(pin input line
					(at 17.78 -2.54 180)
					(length 2.54)
					(name "DIV"
						(effects
							(font
								(size 1.27 1.27)
							)
						)
					)
					(number "2"
						(effects
							(font
								(size 1.27 1.27)
							)
						)
					)
				)
				(pin output line
					(at 17.78 -5.08 180)
					(length 2.54)
					(name "OUT"
						(effects
							(font
								(size 1.27 1.27)
							)
						)
					)
					(number "6"
						(effects
							(font
								(size 1.27 1.27)
							)
						)
					)
				)
			)
		)
	(symbol "antmicroDCDCConverters:SIC437AED-T1-GE3"
			(exclude_from_sim no)
			(in_bom yes)
			(on_board yes)
			(property "Reference" "U"
				(at 33.02 -2.54 0)
				(effects
					(font
						(size 1.27 1.27)
						(thickness 0.15)
					)
					(justify left bottom)
				)
			)
			(property "Value" "SIC437AED-T1-GE3"
				(at 33.02 -7.62 0)
				(effects
					(font
						(size 1.27 1.27)
						(thickness 0.15)
					)
					(justify left bottom)
					(hide yes)
				)
			)
			(property "Footprint" "antmicro-footprints:MLP44-24L_4x4x0.75mm"
				(at 33.02 -10.16 0)
				(effects
					(font
						(size 1.27 1.27)
						(thickness 0.15)
					)
					(justify left bottom)
					(hide yes)
				)
			)
			(property "Datasheet" "https://www.vishay.com/docs/75921/sic437.pdf"
				(at 33.02 -12.7 0)
				(effects
					(font
						(size 1.27 1.27)
						(thickness 0.15)
					)
					(justify left bottom)
					(hide yes)
				)
			)
			(property "Description" "DC/DC Buck Step Down Regulator Adjustable, 4.5-28V In, 0.6V to 20V/12A Out, 1MHz, PowerPAK MLP44-24"
				(at 33.02 -22.86 0)
				(effects
					(font
						(size 1.27 1.27)
					)
					(justify left bottom)
					(hide yes)
				)
			)
			(property "Manufacturer" "Vishay"
				(at 33.02 -15.24 0)
				(effects
					(font
						(size 1.27 1.27)
						(thickness 0.15)
					)
					(justify left bottom)
					(hide yes)
				)
			)
			(property "MPN" "SIC437AED-T1-GE3"
				(at 33.02 -5.08 0)
				(effects
					(font
						(size 1.27 1.27)
						(thickness 0.15)
					)
					(justify left bottom)
				)
			)
			(property "Author" "Antmicro"
				(at 33.02 -17.78 0)
				(effects
					(font
						(size 1.27 1.27)
						(thickness 0.15)
					)
					(justify left bottom)
					(hide yes)
				)
			)
			(property "License" "Apache-2.0"
				(at 33.02 -20.32 0)
				(effects
					(font
						(size 1.27 1.27)
						(thickness 0.15)
					)
					(justify left bottom)
					(hide yes)
				)
			)
			(property "ki_keywords" "SMT, PMIC, IC, DC-DC, CONVERTER, SWITCHING, VOLTAGE"
				(at 0 0 0)
				(effects
					(font
						(size 1.27 1.27)
					)
					(hide yes)
				)
			)
			(symbol "SIC437AED-T1-GE3_1_1"
				(rectangle
					(start 2.54 2.54)
					(end 19.05 -22.86)
					(stroke
						(width 0.254)
						(type default)
					)
					(fill
						(type background)
					)
				)
				(pin power_in line
					(at 0 0 0)
					(length 2.54)
					(name "V_{IN}"
						(effects
							(font
								(size 1.27 1.27)
							)
						)
					)
					(number "1"
						(effects
							(font
								(size 1.27 1.27)
							)
						)
					)
				)
				(pin passive line
					(at 0 0 0)
					(length 2.54)
					(hide yes)
					(name "V_{IN}"
						(effects
							(font
								(size 1.27 1.27)
							)
						)
					)
					(number "2"
						(effects
							(font
								(size 1.27 1.27)
							)
						)
					)
				)
				(pin passive line
					(at 0 0 0)
					(length 2.54)
					(hide yes)
					(name "V_{IN}"
						(effects
							(font
								(size 1.27 1.27)
							)
						)
					)
					(number "22"
						(effects
							(font
								(size 1.27 1.27)
							)
						)
					)
				)
				(pin passive line
					(at 0 0 0)
					(length 2.54)
					(hide yes)
					(name "V_{IN}"
						(effects
							(font
								(size 1.27 1.27)
							)
						)
					)
					(number "26"
						(effects
							(font
								(size 1.27 1.27)
							)
						)
					)
				)
				(pin input line
					(at 0 -7.62 0)
					(length 2.54)
					(name "EN"
						(effects
							(font
								(size 1.27 1.27)
							)
						)
					)
					(number "19"
						(effects
							(font
								(size 1.27 1.27)
							)
						)
					)
				)
				(pin input line
					(at 0 -10.16 0)
					(length 2.54)
					(name "MODE1"
						(effects
							(font
								(size 1.27 1.27)
							)
						)
					)
					(number "21"
						(effects
							(font
								(size 1.27 1.27)
							)
						)
					)
				)
				(pin input line
					(at 0 -12.7 0)
					(length 2.54)
					(name "MODE2"
						(effects
							(font
								(size 1.27 1.27)
							)
						)
					)
					(number "20"
						(effects
							(font
								(size 1.27 1.27)
							)
						)
					)
				)
				(pin passive line
					(at 0 -15.24 0)
					(length 2.54)
					(name "V_{DD}"
						(effects
							(font
								(size 1.27 1.27)
							)
						)
					)
					(number "15"
						(effects
							(font
								(size 1.27 1.27)
							)
						)
					)
				)
				(pin passive line
					(at 0 -17.78 0)
					(length 2.54)
					(name "V_{DRV}"
						(effects
							(font
								(size 1.27 1.27)
							)
						)
					)
					(number "12"
						(effects
							(font
								(size 1.27 1.27)
							)
						)
					)
				)
				(pin output line
					(at 0 -20.32 0)
					(length 2.54)
					(name "P_{GOOD}"
						(effects
							(font
								(size 1.27 1.27)
							)
						)
					)
					(number "14"
						(effects
							(font
								(size 1.27 1.27)
							)
						)
					)
				)
				(pin passive line
					(at 21.59 0 180)
					(length 2.54)
					(name "BOOT"
						(effects
							(font
								(size 1.27 1.27)
							)
						)
					)
					(number "23"
						(effects
							(font
								(size 1.27 1.27)
							)
						)
					)
				)
				(pin passive line
					(at 21.59 -2.54 180)
					(length 2.54)
					(name "PHASE"
						(effects
							(font
								(size 1.27 1.27)
							)
						)
					)
					(number "24"
						(effects
							(font
								(size 1.27 1.27)
							)
						)
					)
				)
				(pin passive line
					(at 21.59 -5.08 180)
					(length 2.54)
					(name "SW"
						(effects
							(font
								(size 1.27 1.27)
							)
						)
					)
					(number "5"
						(effects
							(font
								(size 1.27 1.27)
							)
						)
					)
				)
				(pin passive line
					(at 21.59 -5.08 180)
					(length 2.54)
					(hide yes)
					(name "SW"
						(effects
							(font
								(size 1.27 1.27)
							)
						)
					)
					(number "6"
						(effects
							(font
								(size 1.27 1.27)
							)
						)
					)
				)
				(pin passive line
					(at 21.59 -5.08 180)
					(length 2.54)
					(hide yes)
					(name "SW"
						(effects
							(font
								(size 1.27 1.27)
							)
						)
					)
					(number "7"
						(effects
							(font
								(size 1.27 1.27)
							)
						)
					)
				)
				(pin passive line
					(at 21.59 -5.08 180)
					(length 2.54)
					(hide yes)
					(name "SW"
						(effects
							(font
								(size 1.27 1.27)
							)
						)
					)
					(number "8"
						(effects
							(font
								(size 1.27 1.27)
							)
						)
					)
				)
				(pin passive line
					(at 21.59 -5.08 180)
					(length 2.54)
					(hide yes)
					(name "SW"
						(effects
							(font
								(size 1.27 1.27)
							)
						)
					)
					(number "9"
						(effects
							(font
								(size 1.27 1.27)
							)
						)
					)
				)
				(pin passive line
					(at 21.59 -7.62 180)
					(length 2.54)
					(name "GL"
						(effects
							(font
								(size 1.27 1.27)
							)
						)
					)
					(number "10"
						(effects
							(font
								(size 1.27 1.27)
							)
						)
					)
				)
				(pin passive line
					(at 21.59 -7.62 180)
					(length 2.54)
					(hide yes)
					(name "GL"
						(effects
							(font
								(size 1.27 1.27)
							)
						)
					)
					(number "11"
						(effects
							(font
								(size 1.27 1.27)
							)
						)
					)
				)
				(pin passive line
					(at 21.59 -7.62 180)
					(length 2.54)
					(hide yes)
					(name "GL"
						(effects
							(font
								(size 1.27 1.27)
							)
						)
					)
					(number "28"
						(effects
							(font
								(size 1.27 1.27)
							)
						)
					)
				)
				(pin passive line
					(at 21.59 -10.16 180)
					(length 2.54)
					(name "V_{OUT}"
						(effects
							(font
								(size 1.27 1.27)
							)
						)
					)
					(number "18"
						(effects
							(font
								(size 1.27 1.27)
							)
						)
					)
				)
				(pin passive line
					(at 21.59 -12.7 180)
					(length 2.54)
					(name "FB"
						(effects
							(font
								(size 1.27 1.27)
							)
						)
					)
					(number "17"
						(effects
							(font
								(size 1.27 1.27)
							)
						)
					)
				)
				(pin power_in line
					(at 21.59 -17.78 180)
					(length 2.54)
					(name "A_{GND}"
						(effects
							(font
								(size 1.27 1.27)
							)
						)
					)
					(number "16"
						(effects
							(font
								(size 1.27 1.27)
							)
						)
					)
				)
				(pin passive line
					(at 21.59 -17.78 180)
					(length 2.54)
					(hide yes)
					(name "A_{GND}"
						(effects
							(font
								(size 1.27 1.27)
							)
						)
					)
					(number "25"
						(effects
							(font
								(size 1.27 1.27)
							)
						)
					)
				)
				(pin power_in line
					(at 21.59 -20.32 180)
					(length 2.54)
					(name "P_{GND}"
						(effects
							(font
								(size 1.27 1.27)
							)
						)
					)
					(number "13"
						(effects
							(font
								(size 1.27 1.27)
							)
						)
					)
				)
				(pin passive line
					(at 21.59 -20.32 180)
					(length 2.54)
					(hide yes)
					(name "P_{GND}"
						(effects
							(font
								(size 1.27 1.27)
							)
						)
					)
					(number "27"
						(effects
							(font
								(size 1.27 1.27)
							)
						)
					)
				)
				(pin passive line
					(at 21.59 -20.32 180)
					(length 2.54)
					(hide yes)
					(name "P_{GND}"
						(effects
							(font
								(size 1.27 1.27)
							)
						)
					)
					(number "3"
						(effects
							(font
								(size 1.27 1.27)
							)
						)
					)
				)
				(pin passive line
					(at 21.59 -20.32 180)
					(length 2.54)
					(hide yes)
					(name "P_{GND}"
						(effects
							(font
								(size 1.27 1.27)
							)
						)
					)
					(number "4"
						(effects
							(font
								(size 1.27 1.27)
							)
						)
					)
				)
			)
		)
	(symbol "antmicroDCDCConverters:TPS564247DRLR"
			(exclude_from_sim no)
			(in_bom yes)
			(on_board yes)
			(property "Reference" "U"
				(at 30.48 -5.08 0)
				(effects
					(font
						(size 1.27 1.27)
						(thickness 0.15)
					)
					(justify left bottom)
				)
			)
			(property "Value" "TPS564247DRLR"
				(at 30.48 -10.16 0)
				(effects
					(font
						(size 1.27 1.27)
						(thickness 0.15)
					)
					(justify left bottom)
					(hide yes)
				)
			)
			(property "Footprint" "antmicro-footprints:SOT-563"
				(at 30.48 -12.7 0)
				(effects
					(font
						(size 1.27 1.27)
						(thickness 0.15)
					)
					(justify left bottom)
					(hide yes)
				)
			)
			(property "Datasheet" "https://www.ti.com/lit/ds/symlink/tps564247.pdf?ts=1713526387938&ref_url=https%253A%252F%252Fwww.mouser.pl%252F"
				(at 30.48 -15.24 0)
				(effects
					(font
						(size 1.27 1.27)
						(thickness 0.15)
					)
					(justify left bottom)
					(hide yes)
				)
			)
			(property "Description" "Switching Voltage Regulators 3-V to 16-V input voltage, 4-A FCCM mode, synchronous buck converter in SOT-563 package 6-SOT-5X3 -40 to 125"
				(at 30.48 -25.4 0)
				(effects
					(font
						(size 1.27 1.27)
					)
					(justify left bottom)
					(hide yes)
				)
			)
			(property "Manufacturer" "Texas Instruments"
				(at 30.48 -17.78 0)
				(effects
					(font
						(size 1.27 1.27)
						(thickness 0.15)
					)
					(justify left bottom)
					(hide yes)
				)
			)
			(property "MPN" "TPS564247DRLR"
				(at 30.48 -7.62 0)
				(effects
					(font
						(size 1.27 1.27)
						(thickness 0.15)
					)
					(justify left bottom)
				)
			)
			(property "Author" "Antmicro"
				(at 30.48 -20.32 0)
				(effects
					(font
						(size 1.27 1.27)
						(thickness 0.15)
					)
					(justify left bottom)
					(hide yes)
				)
			)
			(property "License" "Apache-2.0"
				(at 30.48 -22.86 0)
				(effects
					(font
						(size 1.27 1.27)
						(thickness 0.15)
					)
					(justify left bottom)
					(hide yes)
				)
			)
			(property "ki_keywords" "SMT, PMIC, IC, VOLTAGE"
				(at 0 0 0)
				(effects
					(font
						(size 1.27 1.27)
					)
					(hide yes)
				)
			)
			(symbol "TPS564247DRLR_1_1"
				(rectangle
					(start 2.54 1.27)
					(end 12.7 -11.43)
					(stroke
						(width 0.254)
						(type default)
					)
					(fill
						(type background)
					)
				)
				(pin power_in line
					(at 0 0 0)
					(length 2.54)
					(name "V_{IN}"
						(effects
							(font
								(size 1.27 1.27)
							)
						)
					)
					(number "1"
						(effects
							(font
								(size 1.27 1.27)
							)
						)
					)
				)
				(pin passive line
					(at 0 -5.08 0)
					(length 2.54)
					(name "EN"
						(effects
							(font
								(size 1.27 1.27)
							)
						)
					)
					(number "5"
						(effects
							(font
								(size 1.27 1.27)
							)
						)
					)
				)
				(pin power_in line
					(at 0 -7.62 0)
					(length 2.54)
					(name "AGND"
						(effects
							(font
								(size 1.27 1.27)
							)
						)
					)
					(number "4"
						(effects
							(font
								(size 1.27 1.27)
							)
						)
					)
				)
				(pin power_in line
					(at 0 -10.16 0)
					(length 2.54)
					(name "GND"
						(effects
							(font
								(size 1.27 1.27)
							)
						)
					)
					(number "3"
						(effects
							(font
								(size 1.27 1.27)
							)
						)
					)
				)
				(pin passive line
					(at 15.24 0 180)
					(length 2.54)
					(name "SW"
						(effects
							(font
								(size 1.27 1.27)
							)
						)
					)
					(number "2"
						(effects
							(font
								(size 1.27 1.27)
							)
						)
					)
				)
				(pin passive line
					(at 15.24 -7.62 180)
					(length 2.54)
					(name "FB"
						(effects
							(font
								(size 1.27 1.27)
							)
						)
					)
					(number "6"
						(effects
							(font
								(size 1.27 1.27)
							)
						)
					)
				)
			)
		)
	(symbol "antmicroDiodesRectifiersSingle:RB521S30T1G"
			(pin_numbers
				(hide yes)
			)
			(pin_names
				(hide yes)
			)
			(exclude_from_sim no)
			(in_bom yes)
			(on_board yes)
			(property "Reference" "D"
				(at 22.86 -5.08 0)
				(effects
					(font
						(size 1.27 1.27)
						(thickness 0.15)
					)
					(justify left bottom)
				)
			)
			(property "Value" "RB521S30T1G"
				(at 22.86 -15.24 0)
				(effects
					(font
						(size 1.27 1.27)
						(thickness 0.15)
					)
					(justify left bottom)
					(hide yes)
				)
			)
			(property "Footprint" "antmicro-footprints:SOD-523"
				(at 22.86 -10.16 0)
				(effects
					(font
						(size 1.27 1.27)
						(thickness 0.15)
					)
					(justify left bottom)
					(hide yes)
				)
			)
			(property "Datasheet" "https://www.onsemi.com/pdf/datasheet/rb521s30t1-d.pdf"
				(at 22.86 -12.7 0)
				(effects
					(font
						(size 1.27 1.27)
						(thickness 0.15)
					)
					(justify left bottom)
					(hide yes)
				)
			)
			(property "Description" "Small Signal Schottky Diode, Single, 30 V, 200 mA, 500 mV, 1 A, 125 °C"
				(at 22.86 -25.4 0)
				(effects
					(font
						(size 1.27 1.27)
					)
					(justify left bottom)
					(hide yes)
				)
			)
			(property "MPN" "RB521S30T1G"
				(at 22.86 -7.62 0)
				(effects
					(font
						(size 1.27 1.27)
						(thickness 0.15)
					)
					(justify left bottom)
				)
			)
			(property "Manufacturer" "ON Semiconductor"
				(at 22.86 -17.78 0)
				(effects
					(font
						(size 1.27 1.27)
						(thickness 0.15)
					)
					(justify left bottom)
					(hide yes)
				)
			)
			(property "Author" "Antmicro"
				(at 22.86 -20.32 0)
				(effects
					(font
						(size 1.27 1.27)
						(thickness 0.15)
					)
					(justify left bottom)
					(hide yes)
				)
			)
			(property "License" "Apache-2.0"
				(at 22.86 -22.86 0)
				(effects
					(font
						(size 1.27 1.27)
						(thickness 0.15)
					)
					(justify left bottom)
					(hide yes)
				)
			)
			(property "ki_keywords" "SMT, SEMICONDUCTOR, DIODE, SCHOTTKY"
				(at 0 0 0)
				(effects
					(font
						(size 1.27 1.27)
					)
					(hide yes)
				)
			)
			(symbol "RB521S30T1G_0_1"
				(polyline
					(pts
						(xy 1.905 0) (xy 0.635 0)
					)
					(stroke
						(width 0)
						(type default)
					)
					(fill
						(type none)
					)
				)
				(polyline
					(pts
						(xy 4.445 0) (xy 3.175 0)
					)
					(stroke
						(width 0)
						(type default)
					)
					(fill
						(type none)
					)
				)
			)
			(symbol "RB521S30T1G_1_1"
				(polyline
					(pts
						(xy 1.778 1.016) (xy 1.778 -1.016)
					)
					(stroke
						(width 0.254)
						(type default)
					)
					(fill
						(type none)
					)
				)
				(polyline
					(pts
						(xy 1.778 1.016) (xy 1.397 1.016) (xy 1.397 0.762)
					)
					(stroke
						(width 0.254)
						(type default)
					)
					(fill
						(type none)
					)
				)
				(polyline
					(pts
						(xy 1.778 -1.016) (xy 2.159 -1.016) (xy 2.159 -0.762)
					)
					(stroke
						(width 0.254)
						(type default)
					)
					(fill
						(type none)
					)
				)
				(polyline
					(pts
						(xy 3.302 1.016) (xy 3.302 -1.016) (xy 1.778 0) (xy 3.302 1.016)
					)
					(stroke
						(width 0.254)
						(type default)
					)
					(fill
						(type outline)
					)
				)
				(pin passive line
					(at 0 0 0)
					(length 0.635)
					(name "C"
						(effects
							(font
								(size 1.27 1.27)
							)
						)
					)
					(number "1"
						(effects
							(font
								(size 1.27 1.27)
							)
						)
					)
				)
				(pin passive line
					(at 5.08 0 180)
					(length 0.635)
					(name "A"
						(effects
							(font
								(size 1.27 1.27)
							)
						)
					)
					(number "2"
						(effects
							(font
								(size 1.27 1.27)
							)
						)
					)
				)
			)
		)
	(symbol "antmicroFCCConnectors:Conn_FFC_WE_68715014522"
			(exclude_from_sim no)
			(in_bom yes)
			(on_board yes)
			(property "Reference" "J"
				(at 19.05 -5.08 0)
				(effects
					(font
						(size 1.27 1.27)
						(thickness 0.15)
					)
					(justify left bottom)
				)
			)
			(property "Value" "Conn_FFC_WE_68715014522"
				(at 19.05 -7.62 0)
				(effects
					(font
						(size 1.27 1.27)
						(thickness 0.15)
					)
					(justify left bottom)
					(hide yes)
				)
			)
			(property "Footprint" "antmicro-footprints:Conn_FFC_WE_68715014x22"
				(at 19.05 -10.16 0)
				(effects
					(font
						(size 1.27 1.27)
						(thickness 0.15)
					)
					(justify left bottom)
					(hide yes)
				)
			)
			(property "Datasheet" "https://www.we-online.com/components/products/datasheet/68715014522.pdf"
				(at 19.05 -12.7 0)
				(effects
					(font
						(size 1.27 1.27)
						(thickness 0.15)
					)
					(justify left bottom)
					(hide yes)
				)
			)
			(property "Description" "FFC connector"
				(at 19.05 -25.4 0)
				(effects
					(font
						(size 1.27 1.27)
					)
					(justify left bottom)
					(hide yes)
				)
			)
			(property "MPN" "68715014522"
				(at 19.05 -15.24 0)
				(effects
					(font
						(size 1.27 1.27)
						(thickness 0.15)
					)
					(justify left bottom)
				)
			)
			(property "Manufacturer" "Würth Elektronik"
				(at 19.05 -17.78 0)
				(effects
					(font
						(size 1.27 1.27)
						(thickness 0.15)
					)
					(justify left bottom)
					(hide yes)
				)
			)
			(property "Author" "Antmicro"
				(at 19.05 -20.32 0)
				(effects
					(font
						(size 1.27 1.27)
						(thickness 0.15)
					)
					(justify left bottom)
					(hide yes)
				)
			)
			(property "License" "Apache-2.0"
				(at 19.05 -22.86 0)
				(effects
					(font
						(size 1.27 1.27)
						(thickness 0.15)
					)
					(justify left bottom)
					(hide yes)
				)
			)
			(property "ki_keywords" "CONNECTOR"
				(at 0 0 0)
				(effects
					(font
						(size 1.27 1.27)
					)
					(hide yes)
				)
			)
			(symbol "Conn_FFC_WE_68715014522_1_1"
				(rectangle
					(start 3.81 1.27)
					(end 7.62 -132.08)
					(stroke
						(width 0.254)
						(type default)
					)
					(fill
						(type background)
					)
				)
				(rectangle
					(start 3.81 0.127)
					(end 5.08 -0.127)
					(stroke
						(width 0.254)
						(type default)
					)
					(fill
						(type background)
					)
				)
				(rectangle
					(start 3.81 -2.413)
					(end 5.08 -2.667)
					(stroke
						(width 0.254)
						(type default)
					)
					(fill
						(type background)
					)
				)
				(rectangle
					(start 3.81 -4.953)
					(end 5.08 -5.207)
					(stroke
						(width 0.254)
						(type default)
					)
					(fill
						(type background)
					)
				)
				(rectangle
					(start 3.81 -7.493)
					(end 5.08 -7.747)
					(stroke
						(width 0.254)
						(type default)
					)
					(fill
						(type background)
					)
				)
				(rectangle
					(start 3.81 -10.033)
					(end 5.08 -10.287)
					(stroke
						(width 0.254)
						(type default)
					)
					(fill
						(type background)
					)
				)
				(rectangle
					(start 3.81 -12.573)
					(end 5.08 -12.827)
					(stroke
						(width 0.254)
						(type default)
					)
					(fill
						(type background)
					)
				)
				(rectangle
					(start 3.81 -15.113)
					(end 5.08 -15.367)
					(stroke
						(width 0.254)
						(type default)
					)
					(fill
						(type background)
					)
				)
				(rectangle
					(start 3.81 -17.653)
					(end 5.08 -17.907)
					(stroke
						(width 0.254)
						(type default)
					)
					(fill
						(type background)
					)
				)
				(rectangle
					(start 3.81 -20.193)
					(end 5.08 -20.447)
					(stroke
						(width 0.254)
						(type default)
					)
					(fill
						(type background)
					)
				)
				(rectangle
					(start 3.81 -22.733)
					(end 5.08 -22.987)
					(stroke
						(width 0.254)
						(type default)
					)
					(fill
						(type background)
					)
				)
				(rectangle
					(start 3.81 -25.273)
					(end 5.08 -25.527)
					(stroke
						(width 0.254)
						(type default)
					)
					(fill
						(type background)
					)
				)
				(rectangle
					(start 3.81 -27.813)
					(end 5.08 -28.067)
					(stroke
						(width 0.254)
						(type default)
					)
					(fill
						(type background)
					)
				)
				(rectangle
					(start 3.81 -30.353)
					(end 5.08 -30.607)
					(stroke
						(width 0.254)
						(type default)
					)
					(fill
						(type background)
					)
				)
				(rectangle
					(start 3.81 -32.893)
					(end 5.08 -33.147)
					(stroke
						(width 0.254)
						(type default)
					)
					(fill
						(type background)
					)
				)
				(rectangle
					(start 3.81 -35.433)
					(end 5.08 -35.687)
					(stroke
						(width 0.254)
						(type default)
					)
					(fill
						(type background)
					)
				)
				(rectangle
					(start 3.81 -37.973)
					(end 5.08 -38.227)
					(stroke
						(width 0.254)
						(type default)
					)
					(fill
						(type background)
					)
				)
				(rectangle
					(start 3.81 -40.513)
					(end 5.08 -40.767)
					(stroke
						(width 0.254)
						(type default)
					)
					(fill
						(type background)
					)
				)
				(rectangle
					(start 3.81 -43.053)
					(end 5.08 -43.307)
					(stroke
						(width 0.254)
						(type default)
					)
					(fill
						(type background)
					)
				)
				(rectangle
					(start 3.81 -45.593)
					(end 5.08 -45.847)
					(stroke
						(width 0.254)
						(type default)
					)
					(fill
						(type background)
					)
				)
				(rectangle
					(start 3.81 -48.133)
					(end 5.08 -48.387)
					(stroke
						(width 0.254)
						(type default)
					)
					(fill
						(type background)
					)
				)
				(rectangle
					(start 3.81 -50.673)
					(end 5.08 -50.927)
					(stroke
						(width 0.254)
						(type default)
					)
					(fill
						(type background)
					)
				)
				(rectangle
					(start 3.81 -53.213)
					(end 5.08 -53.467)
					(stroke
						(width 0.254)
						(type default)
					)
					(fill
						(type background)
					)
				)
				(rectangle
					(start 3.81 -55.753)
					(end 5.08 -56.007)
					(stroke
						(width 0.254)
						(type default)
					)
					(fill
						(type background)
					)
				)
				(rectangle
					(start 3.81 -58.293)
					(end 5.08 -58.547)
					(stroke
						(width 0.254)
						(type default)
					)
					(fill
						(type background)
					)
				)
				(rectangle
					(start 3.81 -60.833)
					(end 5.08 -61.087)
					(stroke
						(width 0.254)
						(type default)
					)
					(fill
						(type background)
					)
				)
				(rectangle
					(start 3.81 -63.373)
					(end 5.08 -63.627)
					(stroke
						(width 0.254)
						(type default)
					)
					(fill
						(type background)
					)
				)
				(rectangle
					(start 3.81 -65.913)
					(end 5.08 -66.167)
					(stroke
						(width 0.254)
						(type default)
					)
					(fill
						(type background)
					)
				)
				(rectangle
					(start 3.81 -68.453)
					(end 5.08 -68.707)
					(stroke
						(width 0.254)
						(type default)
					)
					(fill
						(type background)
					)
				)
				(rectangle
					(start 3.81 -70.993)
					(end 5.08 -71.247)
					(stroke
						(width 0.254)
						(type default)
					)
					(fill
						(type background)
					)
				)
				(rectangle
					(start 3.81 -73.533)
					(end 5.08 -73.787)
					(stroke
						(width 0.254)
						(type default)
					)
					(fill
						(type background)
					)
				)
				(rectangle
					(start 3.81 -76.073)
					(end 5.08 -76.327)
					(stroke
						(width 0.254)
						(type default)
					)
					(fill
						(type background)
					)
				)
				(rectangle
					(start 3.81 -78.613)
					(end 5.08 -78.867)
					(stroke
						(width 0.254)
						(type default)
					)
					(fill
						(type background)
					)
				)
				(rectangle
					(start 3.81 -81.153)
					(end 5.08 -81.407)
					(stroke
						(width 0.254)
						(type default)
					)
					(fill
						(type background)
					)
				)
				(rectangle
					(start 3.81 -83.693)
					(end 5.08 -83.947)
					(stroke
						(width 0.254)
						(type default)
					)
					(fill
						(type background)
					)
				)
				(rectangle
					(start 3.81 -86.233)
					(end 5.08 -86.487)
					(stroke
						(width 0.254)
						(type default)
					)
					(fill
						(type background)
					)
				)
				(rectangle
					(start 3.81 -88.773)
					(end 5.08 -89.027)
					(stroke
						(width 0.254)
						(type default)
					)
					(fill
						(type background)
					)
				)
				(rectangle
					(start 3.81 -91.313)
					(end 5.08 -91.567)
					(stroke
						(width 0.254)
						(type default)
					)
					(fill
						(type background)
					)
				)
				(rectangle
					(start 3.81 -93.853)
					(end 5.08 -94.107)
					(stroke
						(width 0.254)
						(type default)
					)
					(fill
						(type background)
					)
				)
				(rectangle
					(start 3.81 -96.393)
					(end 5.08 -96.647)
					(stroke
						(width 0.254)
						(type default)
					)
					(fill
						(type background)
					)
				)
				(rectangle
					(start 3.81 -98.933)
					(end 5.08 -99.187)
					(stroke
						(width 0.254)
						(type default)
					)
					(fill
						(type background)
					)
				)
				(rectangle
					(start 3.81 -101.473)
					(end 5.08 -101.727)
					(stroke
						(width 0.254)
						(type default)
					)
					(fill
						(type background)
					)
				)
				(rectangle
					(start 3.81 -104.013)
					(end 5.08 -104.267)
					(stroke
						(width 0.254)
						(type default)
					)
					(fill
						(type background)
					)
				)
				(rectangle
					(start 3.81 -106.553)
					(end 5.08 -106.807)
					(stroke
						(width 0.254)
						(type default)
					)
					(fill
						(type background)
					)
				)
				(rectangle
					(start 3.81 -109.093)
					(end 5.08 -109.347)
					(stroke
						(width 0.254)
						(type default)
					)
					(fill
						(type background)
					)
				)
				(rectangle
					(start 3.81 -111.633)
					(end 5.08 -111.887)
					(stroke
						(width 0.254)
						(type default)
					)
					(fill
						(type background)
					)
				)
				(rectangle
					(start 3.81 -114.173)
					(end 5.08 -114.427)
					(stroke
						(width 0.254)
						(type default)
					)
					(fill
						(type background)
					)
				)
				(rectangle
					(start 3.81 -116.713)
					(end 5.08 -116.967)
					(stroke
						(width 0.254)
						(type default)
					)
					(fill
						(type background)
					)
				)
				(rectangle
					(start 3.81 -119.253)
					(end 5.08 -119.507)
					(stroke
						(width 0.254)
						(type default)
					)
					(fill
						(type background)
					)
				)
				(rectangle
					(start 3.81 -121.793)
					(end 5.08 -122.047)
					(stroke
						(width 0.254)
						(type default)
					)
					(fill
						(type background)
					)
				)
				(rectangle
					(start 3.81 -124.333)
					(end 5.08 -124.587)
					(stroke
						(width 0.254)
						(type default)
					)
					(fill
						(type background)
					)
				)
				(pin passive line
					(at 0 0 0)
					(length 3.81)
					(name "~"
						(effects
							(font
								(size 1.27 1.27)
							)
						)
					)
					(number "1"
						(effects
							(font
								(size 1.27 1.27)
							)
						)
					)
				)
				(pin passive line
					(at 0 -2.54 0)
					(length 3.81)
					(name "~"
						(effects
							(font
								(size 1.27 1.27)
							)
						)
					)
					(number "2"
						(effects
							(font
								(size 1.27 1.27)
							)
						)
					)
				)
				(pin passive line
					(at 0 -5.08 0)
					(length 3.81)
					(name "~"
						(effects
							(font
								(size 1.27 1.27)
							)
						)
					)
					(number "3"
						(effects
							(font
								(size 1.27 1.27)
							)
						)
					)
				)
				(pin passive line
					(at 0 -7.62 0)
					(length 3.81)
					(name "~"
						(effects
							(font
								(size 1.27 1.27)
							)
						)
					)
					(number "4"
						(effects
							(font
								(size 1.27 1.27)
							)
						)
					)
				)
				(pin passive line
					(at 0 -10.16 0)
					(length 3.81)
					(name "~"
						(effects
							(font
								(size 1.27 1.27)
							)
						)
					)
					(number "5"
						(effects
							(font
								(size 1.27 1.27)
							)
						)
					)
				)
				(pin passive line
					(at 0 -12.7 0)
					(length 3.81)
					(name "~"
						(effects
							(font
								(size 1.27 1.27)
							)
						)
					)
					(number "6"
						(effects
							(font
								(size 1.27 1.27)
							)
						)
					)
				)
				(pin passive line
					(at 0 -15.24 0)
					(length 3.81)
					(name "~"
						(effects
							(font
								(size 1.27 1.27)
							)
						)
					)
					(number "7"
						(effects
							(font
								(size 1.27 1.27)
							)
						)
					)
				)
				(pin passive line
					(at 0 -17.78 0)
					(length 3.81)
					(name "~"
						(effects
							(font
								(size 1.27 1.27)
							)
						)
					)
					(number "8"
						(effects
							(font
								(size 1.27 1.27)
							)
						)
					)
				)
				(pin passive line
					(at 0 -20.32 0)
					(length 3.81)
					(name "~"
						(effects
							(font
								(size 1.27 1.27)
							)
						)
					)
					(number "9"
						(effects
							(font
								(size 1.27 1.27)
							)
						)
					)
				)
				(pin passive line
					(at 0 -22.86 0)
					(length 3.81)
					(name "~"
						(effects
							(font
								(size 1.27 1.27)
							)
						)
					)
					(number "10"
						(effects
							(font
								(size 1.27 1.27)
							)
						)
					)
				)
				(pin passive line
					(at 0 -25.4 0)
					(length 3.81)
					(name "~"
						(effects
							(font
								(size 1.27 1.27)
							)
						)
					)
					(number "11"
						(effects
							(font
								(size 1.27 1.27)
							)
						)
					)
				)
				(pin passive line
					(at 0 -27.94 0)
					(length 3.81)
					(name "~"
						(effects
							(font
								(size 1.27 1.27)
							)
						)
					)
					(number "12"
						(effects
							(font
								(size 1.27 1.27)
							)
						)
					)
				)
				(pin passive line
					(at 0 -30.48 0)
					(length 3.81)
					(name "~"
						(effects
							(font
								(size 1.27 1.27)
							)
						)
					)
					(number "13"
						(effects
							(font
								(size 1.27 1.27)
							)
						)
					)
				)
				(pin passive line
					(at 0 -33.02 0)
					(length 3.81)
					(name "~"
						(effects
							(font
								(size 1.27 1.27)
							)
						)
					)
					(number "14"
						(effects
							(font
								(size 1.27 1.27)
							)
						)
					)
				)
				(pin passive line
					(at 0 -35.56 0)
					(length 3.81)
					(name "~"
						(effects
							(font
								(size 1.27 1.27)
							)
						)
					)
					(number "15"
						(effects
							(font
								(size 1.27 1.27)
							)
						)
					)
				)
				(pin passive line
					(at 0 -38.1 0)
					(length 3.81)
					(name "~"
						(effects
							(font
								(size 1.27 1.27)
							)
						)
					)
					(number "16"
						(effects
							(font
								(size 1.27 1.27)
							)
						)
					)
				)
				(pin passive line
					(at 0 -40.64 0)
					(length 3.81)
					(name "~"
						(effects
							(font
								(size 1.27 1.27)
							)
						)
					)
					(number "17"
						(effects
							(font
								(size 1.27 1.27)
							)
						)
					)
				)
				(pin passive line
					(at 0 -43.18 0)
					(length 3.81)
					(name "~"
						(effects
							(font
								(size 1.27 1.27)
							)
						)
					)
					(number "18"
						(effects
							(font
								(size 1.27 1.27)
							)
						)
					)
				)
				(pin passive line
					(at 0 -45.72 0)
					(length 3.81)
					(name "~"
						(effects
							(font
								(size 1.27 1.27)
							)
						)
					)
					(number "19"
						(effects
							(font
								(size 1.27 1.27)
							)
						)
					)
				)
				(pin passive line
					(at 0 -48.26 0)
					(length 3.81)
					(name "~"
						(effects
							(font
								(size 1.27 1.27)
							)
						)
					)
					(number "20"
						(effects
							(font
								(size 1.27 1.27)
							)
						)
					)
				)
				(pin passive line
					(at 0 -50.8 0)
					(length 3.81)
					(name "~"
						(effects
							(font
								(size 1.27 1.27)
							)
						)
					)
					(number "21"
						(effects
							(font
								(size 1.27 1.27)
							)
						)
					)
				)
				(pin passive line
					(at 0 -53.34 0)
					(length 3.81)
					(name "~"
						(effects
							(font
								(size 1.27 1.27)
							)
						)
					)
					(number "22"
						(effects
							(font
								(size 1.27 1.27)
							)
						)
					)
				)
				(pin passive line
					(at 0 -55.88 0)
					(length 3.81)
					(name "~"
						(effects
							(font
								(size 1.27 1.27)
							)
						)
					)
					(number "23"
						(effects
							(font
								(size 1.27 1.27)
							)
						)
					)
				)
				(pin passive line
					(at 0 -58.42 0)
					(length 3.81)
					(name "~"
						(effects
							(font
								(size 1.27 1.27)
							)
						)
					)
					(number "24"
						(effects
							(font
								(size 1.27 1.27)
							)
						)
					)
				)
				(pin passive line
					(at 0 -60.96 0)
					(length 3.81)
					(name "~"
						(effects
							(font
								(size 1.27 1.27)
							)
						)
					)
					(number "25"
						(effects
							(font
								(size 1.27 1.27)
							)
						)
					)
				)
				(pin passive line
					(at 0 -63.5 0)
					(length 3.81)
					(name "~"
						(effects
							(font
								(size 1.27 1.27)
							)
						)
					)
					(number "26"
						(effects
							(font
								(size 1.27 1.27)
							)
						)
					)
				)
				(pin passive line
					(at 0 -66.04 0)
					(length 3.81)
					(name "~"
						(effects
							(font
								(size 1.27 1.27)
							)
						)
					)
					(number "27"
						(effects
							(font
								(size 1.27 1.27)
							)
						)
					)
				)
				(pin passive line
					(at 0 -68.58 0)
					(length 3.81)
					(name "~"
						(effects
							(font
								(size 1.27 1.27)
							)
						)
					)
					(number "28"
						(effects
							(font
								(size 1.27 1.27)
							)
						)
					)
				)
				(pin passive line
					(at 0 -71.12 0)
					(length 3.81)
					(name "~"
						(effects
							(font
								(size 1.27 1.27)
							)
						)
					)
					(number "29"
						(effects
							(font
								(size 1.27 1.27)
							)
						)
					)
				)
				(pin passive line
					(at 0 -73.66 0)
					(length 3.81)
					(name "~"
						(effects
							(font
								(size 1.27 1.27)
							)
						)
					)
					(number "30"
						(effects
							(font
								(size 1.27 1.27)
							)
						)
					)
				)
				(pin passive line
					(at 0 -76.2 0)
					(length 3.81)
					(name "~"
						(effects
							(font
								(size 1.27 1.27)
							)
						)
					)
					(number "31"
						(effects
							(font
								(size 1.27 1.27)
							)
						)
					)
				)
				(pin passive line
					(at 0 -78.74 0)
					(length 3.81)
					(name "~"
						(effects
							(font
								(size 1.27 1.27)
							)
						)
					)
					(number "32"
						(effects
							(font
								(size 1.27 1.27)
							)
						)
					)
				)
				(pin passive line
					(at 0 -81.28 0)
					(length 3.81)
					(name "~"
						(effects
							(font
								(size 1.27 1.27)
							)
						)
					)
					(number "33"
						(effects
							(font
								(size 1.27 1.27)
							)
						)
					)
				)
				(pin passive line
					(at 0 -83.82 0)
					(length 3.81)
					(name "~"
						(effects
							(font
								(size 1.27 1.27)
							)
						)
					)
					(number "34"
						(effects
							(font
								(size 1.27 1.27)
							)
						)
					)
				)
				(pin passive line
					(at 0 -86.36 0)
					(length 3.81)
					(name "~"
						(effects
							(font
								(size 1.27 1.27)
							)
						)
					)
					(number "35"
						(effects
							(font
								(size 1.27 1.27)
							)
						)
					)
				)
				(pin passive line
					(at 0 -88.9 0)
					(length 3.81)
					(name "~"
						(effects
							(font
								(size 1.27 1.27)
							)
						)
					)
					(number "36"
						(effects
							(font
								(size 1.27 1.27)
							)
						)
					)
				)
				(pin passive line
					(at 0 -91.44 0)
					(length 3.81)
					(name "~"
						(effects
							(font
								(size 1.27 1.27)
							)
						)
					)
					(number "37"
						(effects
							(font
								(size 1.27 1.27)
							)
						)
					)
				)
				(pin passive line
					(at 0 -93.98 0)
					(length 3.81)
					(name "~"
						(effects
							(font
								(size 1.27 1.27)
							)
						)
					)
					(number "38"
						(effects
							(font
								(size 1.27 1.27)
							)
						)
					)
				)
				(pin passive line
					(at 0 -96.52 0)
					(length 3.81)
					(name "~"
						(effects
							(font
								(size 1.27 1.27)
							)
						)
					)
					(number "39"
						(effects
							(font
								(size 1.27 1.27)
							)
						)
					)
				)
				(pin passive line
					(at 0 -99.06 0)
					(length 3.81)
					(name "~"
						(effects
							(font
								(size 1.27 1.27)
							)
						)
					)
					(number "40"
						(effects
							(font
								(size 1.27 1.27)
							)
						)
					)
				)
				(pin passive line
					(at 0 -101.6 0)
					(length 3.81)
					(name "~"
						(effects
							(font
								(size 1.27 1.27)
							)
						)
					)
					(number "41"
						(effects
							(font
								(size 1.27 1.27)
							)
						)
					)
				)
				(pin passive line
					(at 0 -104.14 0)
					(length 3.81)
					(name "~"
						(effects
							(font
								(size 1.27 1.27)
							)
						)
					)
					(number "42"
						(effects
							(font
								(size 1.27 1.27)
							)
						)
					)
				)
				(pin passive line
					(at 0 -106.68 0)
					(length 3.81)
					(name "~"
						(effects
							(font
								(size 1.27 1.27)
							)
						)
					)
					(number "43"
						(effects
							(font
								(size 1.27 1.27)
							)
						)
					)
				)
				(pin passive line
					(at 0 -109.22 0)
					(length 3.81)
					(name "~"
						(effects
							(font
								(size 1.27 1.27)
							)
						)
					)
					(number "44"
						(effects
							(font
								(size 1.27 1.27)
							)
						)
					)
				)
				(pin passive line
					(at 0 -111.76 0)
					(length 3.81)
					(name "~"
						(effects
							(font
								(size 1.27 1.27)
							)
						)
					)
					(number "45"
						(effects
							(font
								(size 1.27 1.27)
							)
						)
					)
				)
				(pin passive line
					(at 0 -114.3 0)
					(length 3.81)
					(name "~"
						(effects
							(font
								(size 1.27 1.27)
							)
						)
					)
					(number "46"
						(effects
							(font
								(size 1.27 1.27)
							)
						)
					)
				)
				(pin passive line
					(at 0 -116.84 0)
					(length 3.81)
					(name "~"
						(effects
							(font
								(size 1.27 1.27)
							)
						)
					)
					(number "47"
						(effects
							(font
								(size 1.27 1.27)
							)
						)
					)
				)
				(pin passive line
					(at 0 -119.38 0)
					(length 3.81)
					(name "~"
						(effects
							(font
								(size 1.27 1.27)
							)
						)
					)
					(number "48"
						(effects
							(font
								(size 1.27 1.27)
							)
						)
					)
				)
				(pin passive line
					(at 0 -121.92 0)
					(length 3.81)
					(name "~"
						(effects
							(font
								(size 1.27 1.27)
							)
						)
					)
					(number "49"
						(effects
							(font
								(size 1.27 1.27)
							)
						)
					)
				)
				(pin passive line
					(at 0 -124.46 0)
					(length 3.81)
					(name "~"
						(effects
							(font
								(size 1.27 1.27)
							)
						)
					)
					(number "50"
						(effects
							(font
								(size 1.27 1.27)
							)
						)
					)
				)
				(pin passive line
					(at 0 -127 0)
					(length 3.81)
					(name "MP"
						(effects
							(font
								(size 1.27 1.27)
							)
						)
					)
					(number "MP1"
						(effects
							(font
								(size 1.27 1.27)
							)
						)
					)
				)
				(pin passive line
					(at 0 -129.54 0)
					(length 3.81)
					(name "MP"
						(effects
							(font
								(size 1.27 1.27)
							)
						)
					)
					(number "MP2"
						(effects
							(font
								(size 1.27 1.27)
							)
						)
					)
				)
			)
		)
	(symbol "antmicroFiducialMarks:Fiducial_1mm_Mask3mm"
			(exclude_from_sim no)
			(in_bom no)
			(on_board yes)
			(property "Reference" "FD"
				(at 7.62 0 0)
				(effects
					(font
						(size 1.27 1.27)
						(thickness 0.15)
					)
					(justify left bottom)
				)
			)
			(property "Value" "Fiducial_1mm_Mask3mm"
				(at 7.62 -2.54 0)
				(effects
					(font
						(size 1.27 1.27)
						(thickness 0.15)
					)
					(justify left bottom)
				)
			)
			(property "Footprint" "antmicro-footprints:Fiducial_1mm_Mask3mm"
				(at 7.62 -5.08 0)
				(effects
					(font
						(size 1.27 1.27)
						(thickness 0.15)
					)
					(justify left bottom)
					(hide yes)
				)
			)
			(property "Datasheet" ""
				(at 7.315 -9.22 0)
				(effects
					(font
						(size 1.27 1.27)
						(thickness 0.15)
					)
					(justify left bottom)
					(hide yes)
				)
			)
			(property "Description" "Fiducial mask"
				(at 7.62 -12.7 0)
				(effects
					(font
						(size 1.27 1.27)
					)
					(justify left bottom)
					(hide yes)
				)
			)
			(property "Author" "Antmicro"
				(at 7.62 -7.62 0)
				(effects
					(font
						(size 1.27 1.27)
						(thickness 0.15)
					)
					(justify left bottom)
					(hide yes)
				)
			)
			(property "License" "Apache-2.0"
				(at 7.62 -10.16 0)
				(effects
					(font
						(size 1.27 1.27)
						(thickness 0.15)
					)
					(justify left bottom)
					(hide yes)
				)
			)
			(symbol "Fiducial_1mm_Mask3mm_1_1"
				(circle
					(center 0 0)
					(radius 3.1623)
					(stroke
						(width 0.254)
						(type default)
					)
					(fill
						(type background)
					)
				)
			)
		)
	(symbol "antmicroFixedInductors:L_1u8_6.8A_WE-MAPI-4020"
			(pin_numbers
				(hide yes)
			)
			(pin_names
				(hide yes)
			)
			(exclude_from_sim no)
			(in_bom yes)
			(on_board yes)
			(property "Reference" "L"
				(at 13.97 0 0)
				(effects
					(font
						(size 1.27 1.27)
						(thickness 0.15)
					)
					(justify left bottom)
				)
			)
			(property "Value" "L_1u8_6.8A_WE-MAPI-4020"
				(at 13.97 -2.54 0)
				(effects
					(font
						(size 1.27 1.27)
						(thickness 0.15)
					)
					(justify left bottom)
					(hide yes)
				)
			)
			(property "Footprint" "antmicro-footprints:L_WE-MAPI-4020"
				(at 13.97 -7.62 0)
				(effects
					(font
						(size 1.27 1.27)
						(thickness 0.15)
					)
					(justify left bottom)
					(hide yes)
				)
			)
			(property "Datasheet" "https://www.we-online.com/components/products/datasheet/74438356018.pdf"
				(at 13.97 -10.16 0)
				(effects
					(font
						(size 1.27 1.27)
						(thickness 0.15)
					)
					(justify left bottom)
					(hide yes)
				)
			)
			(property "Description" "Power Inductors - SMD WE-MAPI 1.8uH 4.6A DCR=30mOhms AEC-Q200"
				(at 13.97 -30.48 0)
				(effects
					(font
						(size 1.27 1.27)
					)
					(justify left bottom)
					(hide yes)
				)
			)
			(property "Val" "1u8/6.8A"
				(at 13.97 -5.08 0)
				(effects
					(font
						(size 1.27 1.27)
						(thickness 0.15)
					)
					(justify left bottom)
				)
			)
			(property "Manufacturer" "Würth Elektronik"
				(at 13.97 -12.7 0)
				(effects
					(font
						(size 1.27 1.27)
						(thickness 0.15)
					)
					(justify left bottom)
					(hide yes)
				)
			)
			(property "MPN" "74438356018"
				(at 13.97 -15.24 0)
				(effects
					(font
						(size 1.27 1.27)
						(thickness 0.15)
					)
					(justify left bottom)
					(hide yes)
				)
			)
			(property "ISat" "6.5 A"
				(at 13.97 -16.51 0)
				(effects
					(font
						(size 1.27 1.27)
					)
					(justify left)
					(hide yes)
				)
			)
			(property "IMax" "6.8 A"
				(at 13.97 -20.32 0)
				(effects
					(font
						(size 1.27 1.27)
						(thickness 0.15)
					)
					(justify left bottom)
					(hide yes)
				)
			)
			(property "Size" "4.1x4.1mm"
				(at 13.97 -22.86 0)
				(effects
					(font
						(size 1.27 1.27)
						(thickness 0.15)
					)
					(justify left bottom)
					(hide yes)
				)
			)
			(property "Author" "Antmicro"
				(at 13.97 -25.4 0)
				(effects
					(font
						(size 1.27 1.27)
						(thickness 0.15)
					)
					(justify left bottom)
					(hide yes)
				)
			)
			(property "License" "Apache-2.0"
				(at 13.97 -27.94 0)
				(effects
					(font
						(size 1.27 1.27)
						(thickness 0.15)
					)
					(justify left bottom)
					(hide yes)
				)
			)
			(property "ki_keywords" "SMT, INDUCTOR, PASSIVE"
				(at 0 0 0)
				(effects
					(font
						(size 1.27 1.27)
					)
					(hide yes)
				)
			)
			(symbol "L_1u8_6.8A_WE-MAPI-4020_0_1"
				(arc
					(start 0.508 0)
					(mid 1.016 0.5058)
					(end 1.524 0)
					(stroke
						(width 0)
						(type default)
					)
					(fill
						(type none)
					)
				)
				(arc
					(start 1.524 0)
					(mid 2.032 0.5058)
					(end 2.54 0)
					(stroke
						(width 0)
						(type default)
					)
					(fill
						(type none)
					)
				)
				(arc
					(start 2.54 0)
					(mid 3.048 0.5058)
					(end 3.556 0)
					(stroke
						(width 0)
						(type default)
					)
					(fill
						(type none)
					)
				)
				(arc
					(start 3.556 0)
					(mid 4.064 0.5058)
					(end 4.572 0)
					(stroke
						(width 0)
						(type default)
					)
					(fill
						(type none)
					)
				)
			)
			(symbol "L_1u8_6.8A_WE-MAPI-4020_1_1"
				(pin passive line
					(at 0 0 0)
					(length 0.508)
					(name "~"
						(effects
							(font
								(size 1.27 1.27)
							)
						)
					)
					(number "1"
						(effects
							(font
								(size 1.27 1.27)
							)
						)
					)
				)
				(pin passive line
					(at 5.08 0 180)
					(length 0.508)
					(name "~"
						(effects
							(font
								(size 1.27 1.27)
							)
						)
					)
					(number "2"
						(effects
							(font
								(size 1.27 1.27)
							)
						)
					)
				)
			)
		)
	(symbol "antmicroFixedInductors:L_1u_20A_Bourns-SRP6050CA"
			(pin_numbers
				(hide yes)
			)
			(pin_names
				(hide yes)
			)
			(exclude_from_sim no)
			(in_bom yes)
			(on_board yes)
			(property "Reference" "L"
				(at 13.97 0 0)
				(effects
					(font
						(size 1.27 1.27)
						(thickness 0.15)
					)
					(justify left bottom)
				)
			)
			(property "Value" "L_1u_20A_Bourns-SRP6050CA"
				(at 13.97 -2.54 0)
				(effects
					(font
						(size 1.27 1.27)
						(thickness 0.15)
					)
					(justify left bottom)
					(hide yes)
				)
			)
			(property "Footprint" "antmicro-footprints:L_Bourns-SRP6050CA"
				(at 13.97 -7.62 0)
				(effects
					(font
						(size 1.27 1.27)
						(thickness 0.15)
					)
					(justify left bottom)
					(hide yes)
				)
			)
			(property "Datasheet" "https://www.bourns.com/docs/Product-Datasheets/SRP6050CA.pdf"
				(at 13.97 -10.16 0)
				(effects
					(font
						(size 1.27 1.27)
						(thickness 0.15)
					)
					(justify left bottom)
					(hide yes)
				)
			)
			(property "Description" "Power Inductor (SMT), 1 µH, 20 A, Shielded, 23 A, SRP6050CA"
				(at 13.97 -30.48 0)
				(effects
					(font
						(size 1.27 1.27)
					)
					(justify left bottom)
					(hide yes)
				)
			)
			(property "Val" "1u/20A"
				(at 13.97 -5.08 0)
				(effects
					(font
						(size 1.27 1.27)
						(thickness 0.15)
					)
					(justify left bottom)
				)
			)
			(property "Manufacturer" "Bourns"
				(at 13.97 -12.7 0)
				(effects
					(font
						(size 1.27 1.27)
						(thickness 0.15)
					)
					(justify left bottom)
					(hide yes)
				)
			)
			(property "MPN" "SRP6050CA-1R0M"
				(at 13.97 -15.24 0)
				(effects
					(font
						(size 1.27 1.27)
						(thickness 0.15)
					)
					(justify left bottom)
					(hide yes)
				)
			)
			(property "ISat" "23 A"
				(at 13.97 -16.51 0)
				(effects
					(font
						(size 1.27 1.27)
					)
					(justify left)
					(hide yes)
				)
			)
			(property "IMax" "20 A"
				(at 13.97 -20.32 0)
				(effects
					(font
						(size 1.27 1.27)
						(thickness 0.15)
					)
					(justify left bottom)
					(hide yes)
				)
			)
			(property "Size" "6.6x6.4"
				(at 13.97 -22.86 0)
				(effects
					(font
						(size 1.27 1.27)
						(thickness 0.15)
					)
					(justify left bottom)
					(hide yes)
				)
			)
			(property "Author" "Antmicro"
				(at 13.97 -25.4 0)
				(effects
					(font
						(size 1.27 1.27)
						(thickness 0.15)
					)
					(justify left bottom)
					(hide yes)
				)
			)
			(property "License" "Apache-2.0"
				(at 13.97 -27.94 0)
				(effects
					(font
						(size 1.27 1.27)
						(thickness 0.15)
					)
					(justify left bottom)
					(hide yes)
				)
			)
			(property "ki_keywords" "SMT, INDUCTOR, PASSIVE"
				(at 0 0 0)
				(effects
					(font
						(size 1.27 1.27)
					)
					(hide yes)
				)
			)
			(symbol "L_1u_20A_Bourns-SRP6050CA_0_1"
				(arc
					(start 0.508 0)
					(mid 1.016 0.5058)
					(end 1.524 0)
					(stroke
						(width 0)
						(type default)
					)
					(fill
						(type none)
					)
				)
				(arc
					(start 1.524 0)
					(mid 2.032 0.5058)
					(end 2.54 0)
					(stroke
						(width 0)
						(type default)
					)
					(fill
						(type none)
					)
				)
				(arc
					(start 2.54 0)
					(mid 3.048 0.5058)
					(end 3.556 0)
					(stroke
						(width 0)
						(type default)
					)
					(fill
						(type none)
					)
				)
				(arc
					(start 3.556 0)
					(mid 4.064 0.5058)
					(end 4.572 0)
					(stroke
						(width 0)
						(type default)
					)
					(fill
						(type none)
					)
				)
			)
			(symbol "L_1u_20A_Bourns-SRP6050CA_1_1"
				(pin passive line
					(at 0 0 0)
					(length 0.508)
					(name "~"
						(effects
							(font
								(size 1.27 1.27)
							)
						)
					)
					(number "1"
						(effects
							(font
								(size 1.27 1.27)
							)
						)
					)
				)
				(pin passive line
					(at 5.08 0 180)
					(length 0.508)
					(name "~"
						(effects
							(font
								(size 1.27 1.27)
							)
						)
					)
					(number "2"
						(effects
							(font
								(size 1.27 1.27)
							)
						)
					)
				)
			)
		)
	(symbol "antmicroFixedInductors:L_3u3_15.1A_Coilcraft-XAL7070"
			(pin_numbers
				(hide yes)
			)
			(pin_names
				(hide yes)
			)
			(exclude_from_sim no)
			(in_bom yes)
			(on_board yes)
			(property "Reference" "L"
				(at 13.97 0 0)
				(effects
					(font
						(size 1.27 1.27)
						(thickness 0.15)
					)
					(justify left bottom)
				)
			)
			(property "Value" "L_3u3_15.1A_Coilcraft-XAL7070"
				(at 13.97 -2.54 0)
				(effects
					(font
						(size 1.27 1.27)
						(thickness 0.15)
					)
					(justify left bottom)
					(hide yes)
				)
			)
			(property "Footprint" "antmicro-footprints:L_Coilcraft-XAL7070"
				(at 13.97 -7.62 0)
				(effects
					(font
						(size 1.27 1.27)
						(thickness 0.15)
					)
					(justify left bottom)
					(hide yes)
				)
			)
			(property "Datasheet" "https://www.coilcraft.com/en-us/products/power/shielded-inductors/molded-inductor/xal/xal7070/xal7070-332/"
				(at 13.97 -10.16 0)
				(effects
					(font
						(size 1.27 1.27)
						(thickness 0.15)
					)
					(justify left bottom)
					(hide yes)
				)
			)
			(property "Description" "Power Inductor (SMD), 3.3 µH, 15.1 A, Shielded, 19.4 A, XAL7070"
				(at 13.97 -30.48 0)
				(effects
					(font
						(size 1.27 1.27)
					)
					(justify left bottom)
					(hide yes)
				)
			)
			(property "Val" "3u3/15.1A"
				(at 13.97 -5.08 0)
				(effects
					(font
						(size 1.27 1.27)
						(thickness 0.15)
					)
					(justify left bottom)
				)
			)
			(property "Manufacturer" "Coilcraft"
				(at 13.97 -12.7 0)
				(effects
					(font
						(size 1.27 1.27)
						(thickness 0.15)
					)
					(justify left bottom)
					(hide yes)
				)
			)
			(property "MPN" "XAL7070-332MEB"
				(at 13.97 -15.24 0)
				(effects
					(font
						(size 1.27 1.27)
						(thickness 0.15)
					)
					(justify left bottom)
					(hide yes)
				)
			)
			(property "ISat" "19.4 A"
				(at 13.97 -16.51 0)
				(effects
					(font
						(size 1.27 1.27)
					)
					(justify left)
					(hide yes)
				)
			)
			(property "IMax" "15.1 A"
				(at 13.97 -20.32 0)
				(effects
					(font
						(size 1.27 1.27)
						(thickness 0.15)
					)
					(justify left bottom)
					(hide yes)
				)
			)
			(property "Size" "7.7x8"
				(at 13.97 -22.86 0)
				(effects
					(font
						(size 1.27 1.27)
						(thickness 0.15)
					)
					(justify left bottom)
					(hide yes)
				)
			)
			(property "Author" "Antmicro"
				(at 13.97 -25.4 0)
				(effects
					(font
						(size 1.27 1.27)
						(thickness 0.15)
					)
					(justify left bottom)
					(hide yes)
				)
			)
			(property "License" "Apache-2.0"
				(at 13.97 -27.94 0)
				(effects
					(font
						(size 1.27 1.27)
						(thickness 0.15)
					)
					(justify left bottom)
					(hide yes)
				)
			)
			(property "ki_keywords" "SMT, INDUCTOR, PASSIVE"
				(at 0 0 0)
				(effects
					(font
						(size 1.27 1.27)
					)
					(hide yes)
				)
			)
			(symbol "L_3u3_15.1A_Coilcraft-XAL7070_0_1"
				(arc
					(start 0.508 0)
					(mid 1.016 0.5058)
					(end 1.524 0)
					(stroke
						(width 0)
						(type default)
					)
					(fill
						(type none)
					)
				)
				(arc
					(start 1.524 0)
					(mid 2.032 0.5058)
					(end 2.54 0)
					(stroke
						(width 0)
						(type default)
					)
					(fill
						(type none)
					)
				)
				(arc
					(start 2.54 0)
					(mid 3.048 0.5058)
					(end 3.556 0)
					(stroke
						(width 0)
						(type default)
					)
					(fill
						(type none)
					)
				)
				(arc
					(start 3.556 0)
					(mid 4.064 0.5058)
					(end 4.572 0)
					(stroke
						(width 0)
						(type default)
					)
					(fill
						(type none)
					)
				)
			)
			(symbol "L_3u3_15.1A_Coilcraft-XAL7070_1_1"
				(pin passive line
					(at 0 0 0)
					(length 0.508)
					(name "~"
						(effects
							(font
								(size 1.27 1.27)
							)
						)
					)
					(number "1"
						(effects
							(font
								(size 1.27 1.27)
							)
						)
					)
				)
				(pin passive line
					(at 5.08 0 180)
					(length 0.508)
					(name "~"
						(effects
							(font
								(size 1.27 1.27)
							)
						)
					)
					(number "2"
						(effects
							(font
								(size 1.27 1.27)
							)
						)
					)
				)
			)
		)
	(symbol "antmicroFixedInductors:L_3u3_6A_Bourns-SRP7028A"
			(pin_numbers
				(hide yes)
			)
			(pin_names
				(hide yes)
			)
			(exclude_from_sim no)
			(in_bom yes)
			(on_board yes)
			(property "Reference" "L"
				(at 13.97 0 0)
				(effects
					(font
						(size 1.27 1.27)
						(thickness 0.15)
					)
					(justify left bottom)
				)
			)
			(property "Value" "L_3u3_6A_Bourns-SRP7028A"
				(at 13.97 -5.08 0)
				(effects
					(font
						(size 1.27 1.27)
						(thickness 0.15)
					)
					(justify left bottom)
					(hide yes)
				)
			)
			(property "Footprint" "antmicro-footprints:L_Bourns-SRP7028A"
				(at 13.97 -7.62 0)
				(effects
					(font
						(size 1.27 1.27)
						(thickness 0.15)
					)
					(justify left bottom)
					(hide yes)
				)
			)
			(property "Datasheet" "https://www.bourns.com/docs/Product-Datasheets/SRP7028A.pdf"
				(at 13.97 -10.16 0)
				(effects
					(font
						(size 1.27 1.27)
						(thickness 0.15)
					)
					(justify left bottom)
					(hide yes)
				)
			)
			(property "Description" "Power Inductor (SMD), 3.3 µH, 6 A, Shielded, 12 A, SRP7028A Series"
				(at 13.97 -30.48 0)
				(effects
					(font
						(size 1.27 1.27)
					)
					(justify left bottom)
					(hide yes)
				)
			)
			(property "Val" "3u3/6A"
				(at 13.97 -2.54 0)
				(effects
					(font
						(size 1.27 1.27)
						(thickness 0.15)
					)
					(justify left bottom)
				)
			)
			(property "Manufacturer" "Bourns"
				(at 13.97 -12.7 0)
				(effects
					(font
						(size 1.27 1.27)
						(thickness 0.15)
					)
					(justify left bottom)
					(hide yes)
				)
			)
			(property "MPN" "SRP7028A-3R3M"
				(at 13.97 -15.24 0)
				(effects
					(font
						(size 1.27 1.27)
						(thickness 0.15)
					)
					(justify left bottom)
					(hide yes)
				)
			)
			(property "ISat" "12 A"
				(at 13.97 -16.51 0)
				(effects
					(font
						(size 1.27 1.27)
					)
					(justify left)
					(hide yes)
				)
			)
			(property "IMax" "6 A"
				(at 13.97 -20.32 0)
				(effects
					(font
						(size 1.27 1.27)
						(thickness 0.15)
					)
					(justify left bottom)
					(hide yes)
				)
			)
			(property "Size" "7.3x6.6x2.8"
				(at 13.97 -22.86 0)
				(effects
					(font
						(size 1.27 1.27)
						(thickness 0.15)
					)
					(justify left bottom)
					(hide yes)
				)
			)
			(property "Author" "Antmicro"
				(at 13.97 -25.4 0)
				(effects
					(font
						(size 1.27 1.27)
						(thickness 0.15)
					)
					(justify left bottom)
					(hide yes)
				)
			)
			(property "License" "Apache-2.0"
				(at 13.97 -27.94 0)
				(effects
					(font
						(size 1.27 1.27)
						(thickness 0.15)
					)
					(justify left bottom)
					(hide yes)
				)
			)
			(property "ki_keywords" "SMT, INDUCTOR, PASSIVE"
				(at 0 0 0)
				(effects
					(font
						(size 1.27 1.27)
					)
					(hide yes)
				)
			)
			(symbol "L_3u3_6A_Bourns-SRP7028A_0_1"
				(arc
					(start 0.508 0)
					(mid 1.016 0.5058)
					(end 1.524 0)
					(stroke
						(width 0)
						(type default)
					)
					(fill
						(type none)
					)
				)
				(arc
					(start 1.524 0)
					(mid 2.032 0.5058)
					(end 2.54 0)
					(stroke
						(width 0)
						(type default)
					)
					(fill
						(type none)
					)
				)
				(arc
					(start 2.54 0)
					(mid 3.048 0.5058)
					(end 3.556 0)
					(stroke
						(width 0)
						(type default)
					)
					(fill
						(type none)
					)
				)
				(arc
					(start 3.556 0)
					(mid 4.064 0.5058)
					(end 4.572 0)
					(stroke
						(width 0)
						(type default)
					)
					(fill
						(type none)
					)
				)
			)
			(symbol "L_3u3_6A_Bourns-SRP7028A_1_1"
				(pin passive line
					(at 0 0 0)
					(length 0.508)
					(name "~"
						(effects
							(font
								(size 1.27 1.27)
							)
						)
					)
					(number "1"
						(effects
							(font
								(size 1.27 1.27)
							)
						)
					)
				)
				(pin passive line
					(at 5.08 0 180)
					(length 0.508)
					(name "~"
						(effects
							(font
								(size 1.27 1.27)
							)
						)
					)
					(number "2"
						(effects
							(font
								(size 1.27 1.27)
							)
						)
					)
				)
			)
		)
	(symbol "antmicroFixedInductors:L_560n_17.7A_Bourns-SRP5030CA"
			(pin_numbers
				(hide yes)
			)
			(pin_names
				(hide yes)
			)
			(exclude_from_sim no)
			(in_bom yes)
			(on_board yes)
			(property "Reference" "L"
				(at 13.97 0 0)
				(effects
					(font
						(size 1.27 1.27)
						(thickness 0.15)
					)
					(justify left bottom)
				)
			)
			(property "Value" "L_560n_17.7A_Bourns-SRP5030CA"
				(at 13.97 -2.54 0)
				(effects
					(font
						(size 1.27 1.27)
						(thickness 0.15)
					)
					(justify left bottom)
					(hide yes)
				)
			)
			(property "Footprint" "antmicro-footprints:L_Bourns-SRP5030CA"
				(at 13.97 -7.62 0)
				(effects
					(font
						(size 1.27 1.27)
						(thickness 0.15)
					)
					(justify left bottom)
					(hide yes)
				)
			)
			(property "Datasheet" "https://www.bourns.com/docs/Product-Datasheets/SRP5030CA.pdf"
				(at 13.97 -10.16 0)
				(effects
					(font
						(size 1.27 1.27)
						(thickness 0.15)
					)
					(justify left bottom)
					(hide yes)
				)
			)
			(property "Description" "Power Inductor (SMT), 560 nH, 17.7 A, Shielded, 22.2 A, SRP5030CA"
				(at 13.97 -30.48 0)
				(effects
					(font
						(size 1.27 1.27)
					)
					(justify left bottom)
					(hide yes)
				)
			)
			(property "Val" "560n/17.7A"
				(at 13.97 -5.08 0)
				(effects
					(font
						(size 1.27 1.27)
						(thickness 0.15)
					)
					(justify left bottom)
				)
			)
			(property "Manufacturer" "Bourns"
				(at 13.97 -12.7 0)
				(effects
					(font
						(size 1.27 1.27)
						(thickness 0.15)
					)
					(justify left bottom)
					(hide yes)
				)
			)
			(property "MPN" "SRP5030CA-R56M"
				(at 13.97 -15.24 0)
				(effects
					(font
						(size 1.27 1.27)
						(thickness 0.15)
					)
					(justify left bottom)
					(hide yes)
				)
			)
			(property "ISat" "22.2 A"
				(at 13.97 -16.51 0)
				(effects
					(font
						(size 1.27 1.27)
					)
					(justify left)
					(hide yes)
				)
			)
			(property "IMax" "17.7 A"
				(at 13.97 -20.32 0)
				(effects
					(font
						(size 1.27 1.27)
						(thickness 0.15)
					)
					(justify left bottom)
					(hide yes)
				)
			)
			(property "Size" "5.5x5.3"
				(at 13.97 -22.86 0)
				(effects
					(font
						(size 1.27 1.27)
						(thickness 0.15)
					)
					(justify left bottom)
					(hide yes)
				)
			)
			(property "Author" "Antmicro"
				(at 13.97 -25.4 0)
				(effects
					(font
						(size 1.27 1.27)
						(thickness 0.15)
					)
					(justify left bottom)
					(hide yes)
				)
			)
			(property "License" "Apache-2.0"
				(at 13.97 -27.94 0)
				(effects
					(font
						(size 1.27 1.27)
						(thickness 0.15)
					)
					(justify left bottom)
					(hide yes)
				)
			)
			(property "ki_keywords" "SMT, INDUCTOR, PASSIVE"
				(at 0 0 0)
				(effects
					(font
						(size 1.27 1.27)
					)
					(hide yes)
				)
			)
			(symbol "L_560n_17.7A_Bourns-SRP5030CA_0_1"
				(arc
					(start 0.508 0)
					(mid 1.016 0.5058)
					(end 1.524 0)
					(stroke
						(width 0)
						(type default)
					)
					(fill
						(type none)
					)
				)
				(arc
					(start 1.524 0)
					(mid 2.032 0.5058)
					(end 2.54 0)
					(stroke
						(width 0)
						(type default)
					)
					(fill
						(type none)
					)
				)
				(arc
					(start 2.54 0)
					(mid 3.048 0.5058)
					(end 3.556 0)
					(stroke
						(width 0)
						(type default)
					)
					(fill
						(type none)
					)
				)
				(arc
					(start 3.556 0)
					(mid 4.064 0.5058)
					(end 4.572 0)
					(stroke
						(width 0)
						(type default)
					)
					(fill
						(type none)
					)
				)
			)
			(symbol "L_560n_17.7A_Bourns-SRP5030CA_1_1"
				(pin passive line
					(at 0 0 0)
					(length 0.508)
					(name "~"
						(effects
							(font
								(size 1.27 1.27)
							)
						)
					)
					(number "1"
						(effects
							(font
								(size 1.27 1.27)
							)
						)
					)
				)
				(pin passive line
					(at 5.08 0 180)
					(length 0.508)
					(name "~"
						(effects
							(font
								(size 1.27 1.27)
							)
						)
					)
					(number "2"
						(effects
							(font
								(size 1.27 1.27)
							)
						)
					)
				)
			)
		)
	(symbol "antmicroFixedInductors:L_6u8_6.1A_MPS-MPL-AL5050"
			(pin_numbers
				(hide yes)
			)
			(pin_names
				(hide yes)
			)
			(exclude_from_sim no)
			(in_bom yes)
			(on_board yes)
			(property "Reference" "L"
				(at 13.97 0 0)
				(effects
					(font
						(size 1.27 1.27)
						(thickness 0.15)
					)
					(justify left bottom)
				)
			)
			(property "Value" "L_6u8_6.1A_MPS-MPL-AL5050"
				(at 13.97 -2.54 0)
				(effects
					(font
						(size 1.27 1.27)
						(thickness 0.15)
					)
					(justify left bottom)
					(hide yes)
				)
			)
			(property "Footprint" "antmicro-footprints:L_MPS-MPL-AL5050"
				(at 13.97 -7.62 0)
				(effects
					(font
						(size 1.27 1.27)
						(thickness 0.15)
					)
					(justify left bottom)
					(hide yes)
				)
			)
			(property "Datasheet" "https://www.monolithicpower.com/en/documentview/productdocument/index/version/2/document_type/Datasheet/lang/en/sku/MPL-AL5050-6R8/document_id/5811/"
				(at 13.97 -10.16 0)
				(effects
					(font
						(size 1.27 1.27)
						(thickness 0.15)
					)
					(justify left bottom)
					(hide yes)
				)
			)
			(property "Description" "Power Inductor (SMT), 6.8 µH, 6.1 A, Shielded, 7.6 A, MPL-AL"
				(at 13.97 -30.48 0)
				(effects
					(font
						(size 1.27 1.27)
					)
					(justify left bottom)
					(hide yes)
				)
			)
			(property "Val" "6u8/6.1A"
				(at 13.97 -5.08 0)
				(effects
					(font
						(size 1.27 1.27)
						(thickness 0.15)
					)
					(justify left bottom)
				)
			)
			(property "Manufacturer" "Monolithic Power Systems"
				(at 13.97 -12.7 0)
				(effects
					(font
						(size 1.27 1.27)
						(thickness 0.15)
					)
					(justify left bottom)
					(hide yes)
				)
			)
			(property "MPN" "MPL-AL5050-6R8"
				(at 13.97 -15.24 0)
				(effects
					(font
						(size 1.27 1.27)
						(thickness 0.15)
					)
					(justify left bottom)
					(hide yes)
				)
			)
			(property "ISat" "7.6 A"
				(at 13.97 -16.51 0)
				(effects
					(font
						(size 1.27 1.27)
					)
					(justify left)
					(hide yes)
				)
			)
			(property "IMax" "6.1 A"
				(at 13.97 -20.32 0)
				(effects
					(font
						(size 1.27 1.27)
						(thickness 0.15)
					)
					(justify left bottom)
					(hide yes)
				)
			)
			(property "Size" "5.5x5.3"
				(at 13.97 -22.86 0)
				(effects
					(font
						(size 1.27 1.27)
						(thickness 0.15)
					)
					(justify left bottom)
					(hide yes)
				)
			)
			(property "Author" "Antmicro"
				(at 13.97 -25.4 0)
				(effects
					(font
						(size 1.27 1.27)
						(thickness 0.15)
					)
					(justify left bottom)
					(hide yes)
				)
			)
			(property "License" "Apache-2.0"
				(at 13.97 -27.94 0)
				(effects
					(font
						(size 1.27 1.27)
						(thickness 0.15)
					)
					(justify left bottom)
					(hide yes)
				)
			)
			(property "ki_keywords" "SMT, INDUCTOR, PASSIVE"
				(at 0 0 0)
				(effects
					(font
						(size 1.27 1.27)
					)
					(hide yes)
				)
			)
			(symbol "L_6u8_6.1A_MPS-MPL-AL5050_0_1"
				(arc
					(start 0.508 0)
					(mid 1.016 0.5058)
					(end 1.524 0)
					(stroke
						(width 0)
						(type default)
					)
					(fill
						(type none)
					)
				)
				(arc
					(start 1.524 0)
					(mid 2.032 0.5058)
					(end 2.54 0)
					(stroke
						(width 0)
						(type default)
					)
					(fill
						(type none)
					)
				)
				(arc
					(start 2.54 0)
					(mid 3.048 0.5058)
					(end 3.556 0)
					(stroke
						(width 0)
						(type default)
					)
					(fill
						(type none)
					)
				)
				(arc
					(start 3.556 0)
					(mid 4.064 0.5058)
					(end 4.572 0)
					(stroke
						(width 0)
						(type default)
					)
					(fill
						(type none)
					)
				)
			)
			(symbol "L_6u8_6.1A_MPS-MPL-AL5050_1_1"
				(pin passive line
					(at 0 0 0)
					(length 0.508)
					(name "~"
						(effects
							(font
								(size 1.27 1.27)
							)
						)
					)
					(number "1"
						(effects
							(font
								(size 1.27 1.27)
							)
						)
					)
				)
				(pin passive line
					(at 5.08 0 180)
					(length 0.508)
					(name "~"
						(effects
							(font
								(size 1.27 1.27)
							)
						)
					)
					(number "2"
						(effects
							(font
								(size 1.27 1.27)
							)
						)
					)
				)
			)
		)
	(symbol "antmicroInterfaceControllers:FT230X_QFN"
			(exclude_from_sim no)
			(in_bom yes)
			(on_board yes)
			(property "Reference" "U"
				(at 39.37 -7.62 0)
				(effects
					(font
						(size 1.27 1.27)
						(thickness 0.15)
					)
					(justify left bottom)
				)
			)
			(property "Value" "FT230X_QFN"
				(at 39.37 -10.16 0)
				(effects
					(font
						(size 1.27 1.27)
						(thickness 0.15)
					)
					(justify left bottom)
					(hide yes)
				)
			)
			(property "Footprint" "antmicro-footprints:QFN-16-1EP_4x4mm_P0.65mm"
				(at 39.37 -12.7 0)
				(effects
					(font
						(size 1.27 1.27)
						(thickness 0.15)
					)
					(justify left bottom)
					(hide yes)
				)
			)
			(property "Datasheet" "https://ftdichip.com/wp-content/uploads/2021/10/DS_FT230X.pdf"
				(at 39.37 -15.24 0)
				(effects
					(font
						(size 1.27 1.27)
						(thickness 0.15)
					)
					(justify left bottom)
					(hide yes)
				)
			)
			(property "Description" "USB Interface, USB-UART Converter, USB 2.0, 2.97 V, 5.5 V, QFN, 16 Pins"
				(at 39.37 -27.94 0)
				(effects
					(font
						(size 1.27 1.27)
					)
					(justify left bottom)
					(hide yes)
				)
			)
			(property "MPN" "FT230XQ-R"
				(at 39.37 -20.32 0)
				(effects
					(font
						(size 1.27 1.27)
						(thickness 0.15)
					)
					(justify left bottom)
				)
			)
			(property "Manufacturer" "FTDI Chip"
				(at 39.37 -17.78 0)
				(effects
					(font
						(size 1.27 1.27)
						(thickness 0.15)
					)
					(justify left bottom)
					(hide yes)
				)
			)
			(property "Author" "Antmicro"
				(at 39.37 -22.86 0)
				(effects
					(font
						(size 1.27 1.27)
						(thickness 0.15)
					)
					(justify left bottom)
					(hide yes)
				)
			)
			(property "License" "Apache-2.0"
				(at 39.37 -25.4 0)
				(effects
					(font
						(size 1.27 1.27)
						(thickness 0.15)
					)
					(justify left bottom)
					(hide yes)
				)
			)
			(property "ki_keywords" "SMT, INTERFACE, IC, CONTROLLER, USB, UART"
				(at 0 0 0)
				(effects
					(font
						(size 1.27 1.27)
					)
					(hide yes)
				)
			)
			(symbol "FT230X_QFN_1_1"
				(rectangle
					(start 2.54 2.54)
					(end 20.32 -22.86)
					(stroke
						(width 0.254)
						(type default)
					)
					(fill
						(type background)
					)
				)
				(pin power_in line
					(at 0 0 0)
					(length 2.54)
					(name "V_{CC}"
						(effects
							(font
								(size 1.27 1.27)
							)
						)
					)
					(number "10"
						(effects
							(font
								(size 1.27 1.27)
							)
						)
					)
				)
				(pin power_in line
					(at 0 -2.54 0)
					(length 2.54)
					(name "V_{CCIO}"
						(effects
							(font
								(size 1.27 1.27)
							)
						)
					)
					(number "1"
						(effects
							(font
								(size 1.27 1.27)
							)
						)
					)
				)
				(pin passive line
					(at 0 -5.08 0)
					(length 2.54)
					(name "3V3_{OUT}"
						(effects
							(font
								(size 1.27 1.27)
							)
						)
					)
					(number "8"
						(effects
							(font
								(size 1.27 1.27)
							)
						)
					)
				)
				(pin input line
					(at 0 -8.89 0)
					(length 2.54)
					(name "D+"
						(effects
							(font
								(size 1.27 1.27)
							)
						)
					)
					(number "6"
						(effects
							(font
								(size 1.27 1.27)
							)
						)
					)
				)
				(pin input line
					(at 0 -11.43 0)
					(length 2.54)
					(name "D-"
						(effects
							(font
								(size 1.27 1.27)
							)
						)
					)
					(number "7"
						(effects
							(font
								(size 1.27 1.27)
							)
						)
					)
				)
				(pin input line
					(at 0 -15.24 0)
					(length 2.54)
					(name "~{RESET}"
						(effects
							(font
								(size 1.27 1.27)
							)
						)
					)
					(number "9"
						(effects
							(font
								(size 1.27 1.27)
							)
						)
					)
				)
				(pin power_in line
					(at 0 -20.32 0)
					(length 2.54)
					(name "GND"
						(effects
							(font
								(size 1.27 1.27)
							)
						)
					)
					(number "13"
						(effects
							(font
								(size 1.27 1.27)
							)
						)
					)
				)
				(pin passive line
					(at 0 -20.32 0)
					(length 2.54)
					(hide yes)
					(name "GND"
						(effects
							(font
								(size 1.27 1.27)
							)
						)
					)
					(number "17"
						(effects
							(font
								(size 1.27 1.27)
							)
						)
					)
				)
				(pin passive line
					(at 0 -20.32 0)
					(length 2.54)
					(hide yes)
					(name "GND"
						(effects
							(font
								(size 1.27 1.27)
							)
						)
					)
					(number "3"
						(effects
							(font
								(size 1.27 1.27)
							)
						)
					)
				)
				(pin output line
					(at 22.86 0 180)
					(length 2.54)
					(name "TXD"
						(effects
							(font
								(size 1.27 1.27)
							)
						)
					)
					(number "15"
						(effects
							(font
								(size 1.27 1.27)
							)
						)
					)
				)
				(pin input line
					(at 22.86 -2.54 180)
					(length 2.54)
					(name "RXD"
						(effects
							(font
								(size 1.27 1.27)
							)
						)
					)
					(number "2"
						(effects
							(font
								(size 1.27 1.27)
							)
						)
					)
				)
				(pin output line
					(at 22.86 -5.08 180)
					(length 2.54)
					(name "~{RTS}"
						(effects
							(font
								(size 1.27 1.27)
							)
						)
					)
					(number "16"
						(effects
							(font
								(size 1.27 1.27)
							)
						)
					)
				)
				(pin input line
					(at 22.86 -7.62 180)
					(length 2.54)
					(name "~{CTS}"
						(effects
							(font
								(size 1.27 1.27)
							)
						)
					)
					(number "4"
						(effects
							(font
								(size 1.27 1.27)
							)
						)
					)
				)
				(pin bidirectional line
					(at 22.86 -12.7 180)
					(length 2.54)
					(name "CBUS0"
						(effects
							(font
								(size 1.27 1.27)
							)
						)
					)
					(number "12"
						(effects
							(font
								(size 1.27 1.27)
							)
						)
					)
				)
				(pin bidirectional line
					(at 22.86 -15.24 180)
					(length 2.54)
					(name "CBUS1"
						(effects
							(font
								(size 1.27 1.27)
							)
						)
					)
					(number "11"
						(effects
							(font
								(size 1.27 1.27)
							)
						)
					)
				)
				(pin bidirectional line
					(at 22.86 -17.78 180)
					(length 2.54)
					(name "CBUS2"
						(effects
							(font
								(size 1.27 1.27)
							)
						)
					)
					(number "5"
						(effects
							(font
								(size 1.27 1.27)
							)
						)
					)
				)
				(pin bidirectional line
					(at 22.86 -20.32 180)
					(length 2.54)
					(name "CBUS3"
						(effects
							(font
								(size 1.27 1.27)
							)
						)
					)
					(number "14"
						(effects
							(font
								(size 1.27 1.27)
							)
						)
					)
				)
			)
		)
	(symbol "antmicroInterfaceControllers:HD3SS3220IRNHR"
			(exclude_from_sim no)
			(in_bom yes)
			(on_board yes)
			(property "Reference" "U"
				(at 41.91 -5.08 0)
				(effects
					(font
						(size 1.27 1.27)
						(thickness 0.15)
					)
					(justify left bottom)
				)
			)
			(property "Value" "HD3SS3220IRNHR"
				(at 41.91 -7.62 0)
				(effects
					(font
						(size 1.27 1.27)
						(thickness 0.15)
					)
					(justify left bottom)
					(hide yes)
				)
			)
			(property "Footprint" "antmicro-footprints:WQFN-30-1EP_4.6x2.6mm_P0.4mm"
				(at 41.91 -10.16 0)
				(effects
					(font
						(size 1.27 1.27)
						(thickness 0.15)
					)
					(justify left bottom)
					(hide yes)
				)
			)
			(property "Datasheet" "https://www.ti.com/lit/ds/symlink/hd3ss3220.pdf?ts=1663000043694&ref_url=https%253A%252F%252Fwww.google.com%252F"
				(at 41.91 -12.7 0)
				(effects
					(font
						(size 1.27 1.27)
						(thickness 0.15)
					)
					(justify left bottom)
					(hide yes)
				)
			)
			(property "Description" "USB Interface IC 10-Gbps USB 3.1 Type-C 2:1 mux with DRP Controller 30-WQFN -40°C to 85°C"
				(at 41.91 -25.4 0)
				(effects
					(font
						(size 1.27 1.27)
					)
					(justify left bottom)
					(hide yes)
				)
			)
			(property "Manufacturer" "Texas Instruments"
				(at 41.91 -15.24 0)
				(effects
					(font
						(size 1.27 1.27)
						(thickness 0.15)
					)
					(justify left bottom)
					(hide yes)
				)
			)
			(property "MPN" "HD3SS3220IRNHR"
				(at 41.91 -17.78 0)
				(effects
					(font
						(size 1.27 1.27)
						(thickness 0.15)
					)
					(justify left bottom)
				)
			)
			(property "Author" "Antmicro"
				(at 41.91 -20.32 0)
				(effects
					(font
						(size 1.27 1.27)
						(thickness 0.15)
					)
					(justify left bottom)
					(hide yes)
				)
			)
			(property "License" "Apache-2.0"
				(at 41.91 -22.86 0)
				(effects
					(font
						(size 1.27 1.27)
						(thickness 0.15)
					)
					(justify left bottom)
					(hide yes)
				)
			)
			(property "ki_keywords" "SMT, CONTROLLER, IC, INTERFACE"
				(at 0 0 0)
				(effects
					(font
						(size 1.27 1.27)
					)
					(hide yes)
				)
			)
			(symbol "HD3SS3220IRNHR_1_1"
				(rectangle
					(start 2.54 2.54)
					(end 25.4 -64.77)
					(stroke
						(width 0.254)
						(type default)
					)
					(fill
						(type background)
					)
				)
				(pin passive line
					(at 0 0 0)
					(length 2.54)
					(name "VDD5"
						(effects
							(font
								(size 1.27 1.27)
							)
						)
					)
					(number "30"
						(effects
							(font
								(size 1.27 1.27)
							)
						)
					)
				)
				(pin passive line
					(at 0 -2.54 0)
					(length 2.54)
					(name "VCC33"
						(effects
							(font
								(size 1.27 1.27)
							)
						)
					)
					(number "8"
						(effects
							(font
								(size 1.27 1.27)
							)
						)
					)
				)
				(pin passive line
					(at 0 -15.24 0)
					(length 2.54)
					(name "CURRENT_MODE"
						(effects
							(font
								(size 1.27 1.27)
							)
						)
					)
					(number "3"
						(effects
							(font
								(size 1.27 1.27)
							)
						)
					)
				)
				(pin passive line
					(at 0 -17.78 0)
					(length 2.54)
					(name "PORT"
						(effects
							(font
								(size 1.27 1.27)
							)
						)
					)
					(number "4"
						(effects
							(font
								(size 1.27 1.27)
							)
						)
					)
				)
				(pin passive line
					(at 0 -20.32 0)
					(length 2.54)
					(name "ENn_MUX"
						(effects
							(font
								(size 1.27 1.27)
							)
						)
					)
					(number "12"
						(effects
							(font
								(size 1.27 1.27)
							)
						)
					)
				)
				(pin passive line
					(at 0 -22.86 0)
					(length 2.54)
					(name "ENn_CC"
						(effects
							(font
								(size 1.27 1.27)
							)
						)
					)
					(number "29"
						(effects
							(font
								(size 1.27 1.27)
							)
						)
					)
				)
				(pin passive line
					(at 0 -35.56 0)
					(length 2.54)
					(name "RX-"
						(effects
							(font
								(size 1.27 1.27)
							)
						)
					)
					(number "10"
						(effects
							(font
								(size 1.27 1.27)
							)
						)
					)
				)
				(pin passive line
					(at 0 -38.1 0)
					(length 2.54)
					(name "RX+"
						(effects
							(font
								(size 1.27 1.27)
							)
						)
					)
					(number "9"
						(effects
							(font
								(size 1.27 1.27)
							)
						)
					)
				)
				(pin passive line
					(at 0 -43.18 0)
					(length 2.54)
					(name "TX-"
						(effects
							(font
								(size 1.27 1.27)
							)
						)
					)
					(number "7"
						(effects
							(font
								(size 1.27 1.27)
							)
						)
					)
				)
				(pin passive line
					(at 0 -45.72 0)
					(length 2.54)
					(name "TX+"
						(effects
							(font
								(size 1.27 1.27)
							)
						)
					)
					(number "6"
						(effects
							(font
								(size 1.27 1.27)
							)
						)
					)
				)
				(pin passive line
					(at 0 -50.8 0)
					(length 2.54)
					(name "ADDR"
						(effects
							(font
								(size 1.27 1.27)
							)
						)
					)
					(number "22"
						(effects
							(font
								(size 1.27 1.27)
							)
						)
					)
				)
				(pin passive line
					(at 0 -53.34 0)
					(length 2.54)
					(name "SDA/OUT1"
						(effects
							(font
								(size 1.27 1.27)
							)
						)
					)
					(number "25"
						(effects
							(font
								(size 1.27 1.27)
							)
						)
					)
				)
				(pin passive line
					(at 0 -55.88 0)
					(length 2.54)
					(name "SCL/OUT2"
						(effects
							(font
								(size 1.27 1.27)
							)
						)
					)
					(number "26"
						(effects
							(font
								(size 1.27 1.27)
							)
						)
					)
				)
				(pin passive line
					(at 0 -58.42 0)
					(length 2.54)
					(name "INT_N/OUT3"
						(effects
							(font
								(size 1.27 1.27)
							)
						)
					)
					(number "23"
						(effects
							(font
								(size 1.27 1.27)
							)
						)
					)
				)
				(pin passive line
					(at 0 -62.23 0)
					(length 2.54)
					(name "GND"
						(effects
							(font
								(size 1.27 1.27)
							)
						)
					)
					(number "13"
						(effects
							(font
								(size 1.27 1.27)
							)
						)
					)
				)
				(pin passive line
					(at 0 -62.23 0)
					(length 2.54)
					(hide yes)
					(name "GND"
						(effects
							(font
								(size 1.27 1.27)
							)
						)
					)
					(number "28"
						(effects
							(font
								(size 1.27 1.27)
							)
						)
					)
				)
				(pin passive line
					(at 0 -62.23 0)
					(length 2.54)
					(hide yes)
					(name "GND"
						(effects
							(font
								(size 1.27 1.27)
							)
						)
					)
					(number "31"
						(effects
							(font
								(size 1.27 1.27)
							)
						)
					)
				)
				(pin passive line
					(at 27.94 0 180)
					(length 2.54)
					(name "DIR"
						(effects
							(font
								(size 1.27 1.27)
							)
						)
					)
					(number "11"
						(effects
							(font
								(size 1.27 1.27)
							)
						)
					)
				)
				(pin passive line
					(at 27.94 -2.54 180)
					(length 2.54)
					(name "ID"
						(effects
							(font
								(size 1.27 1.27)
							)
						)
					)
					(number "27"
						(effects
							(font
								(size 1.27 1.27)
							)
						)
					)
				)
				(pin passive line
					(at 27.94 -5.08 180)
					(length 2.54)
					(name "VCONN_FAULT_N"
						(effects
							(font
								(size 1.27 1.27)
							)
						)
					)
					(number "24"
						(effects
							(font
								(size 1.27 1.27)
							)
						)
					)
				)
				(pin passive line
					(at 27.94 -10.16 180)
					(length 2.54)
					(name "VBUS_DET"
						(effects
							(font
								(size 1.27 1.27)
							)
						)
					)
					(number "5"
						(effects
							(font
								(size 1.27 1.27)
							)
						)
					)
				)
				(pin passive line
					(at 27.94 -15.24 180)
					(length 2.54)
					(name "CC1"
						(effects
							(font
								(size 1.27 1.27)
							)
						)
					)
					(number "2"
						(effects
							(font
								(size 1.27 1.27)
							)
						)
					)
				)
				(pin passive line
					(at 27.94 -17.78 180)
					(length 2.54)
					(name "CC2"
						(effects
							(font
								(size 1.27 1.27)
							)
						)
					)
					(number "1"
						(effects
							(font
								(size 1.27 1.27)
							)
						)
					)
				)
				(pin passive line
					(at 27.94 -35.56 180)
					(length 2.54)
					(name "RX1-"
						(effects
							(font
								(size 1.27 1.27)
							)
						)
					)
					(number "14"
						(effects
							(font
								(size 1.27 1.27)
							)
						)
					)
				)
				(pin passive line
					(at 27.94 -38.1 180)
					(length 2.54)
					(name "RX1+"
						(effects
							(font
								(size 1.27 1.27)
							)
						)
					)
					(number "15"
						(effects
							(font
								(size 1.27 1.27)
							)
						)
					)
				)
				(pin passive line
					(at 27.94 -43.18 180)
					(length 2.54)
					(name "TX1-"
						(effects
							(font
								(size 1.27 1.27)
							)
						)
					)
					(number "16"
						(effects
							(font
								(size 1.27 1.27)
							)
						)
					)
				)
				(pin passive line
					(at 27.94 -45.72 180)
					(length 2.54)
					(name "TX1+"
						(effects
							(font
								(size 1.27 1.27)
							)
						)
					)
					(number "17"
						(effects
							(font
								(size 1.27 1.27)
							)
						)
					)
				)
				(pin passive line
					(at 27.94 -50.8 180)
					(length 2.54)
					(name "RX2-"
						(effects
							(font
								(size 1.27 1.27)
							)
						)
					)
					(number "18"
						(effects
							(font
								(size 1.27 1.27)
							)
						)
					)
				)
				(pin passive line
					(at 27.94 -53.34 180)
					(length 2.54)
					(name "RX2+"
						(effects
							(font
								(size 1.27 1.27)
							)
						)
					)
					(number "19"
						(effects
							(font
								(size 1.27 1.27)
							)
						)
					)
				)
				(pin passive line
					(at 27.94 -58.42 180)
					(length 2.54)
					(name "TX2-"
						(effects
							(font
								(size 1.27 1.27)
							)
						)
					)
					(number "20"
						(effects
							(font
								(size 1.27 1.27)
							)
						)
					)
				)
				(pin passive line
					(at 27.94 -60.96 180)
					(length 2.54)
					(name "TX2+"
						(effects
							(font
								(size 1.27 1.27)
							)
						)
					)
					(number "21"
						(effects
							(font
								(size 1.27 1.27)
							)
						)
					)
				)
			)
		)
	(symbol "antmicroInterfaceControllers:SLB9673AU20FW2610XTMA1"
			(exclude_from_sim no)
			(in_bom yes)
			(on_board yes)
			(property "Reference" "U"
				(at 50.8 -5.08 0)
				(effects
					(font
						(size 1.27 1.27)
						(thickness 0.15)
					)
					(justify left bottom)
				)
			)
			(property "Value" "SLB9673AU20FW2610XTMA1"
				(at 50.8 -17.78 0)
				(effects
					(font
						(size 1.27 1.27)
						(thickness 0.15)
					)
					(justify left bottom)
					(hide yes)
				)
			)
			(property "Footprint" "antmicro-footprints:QFN-32-1EP_5x5mm"
				(at 50.8 -20.32 0)
				(effects
					(font
						(size 1.27 1.27)
						(thickness 0.15)
					)
					(justify left bottom)
					(hide yes)
				)
			)
			(property "Datasheet" "https://eu.mouser.com/datasheet/2/196/Infineon_OPTIGA_TPM_SLB_9673_FW26_DataSheet_v01_30-3363760.pdf"
				(at 50.8 -22.86 0)
				(effects
					(font
						(size 1.27 1.27)
						(thickness 0.15)
					)
					(justify left bottom)
					(hide yes)
				)
			)
			(property "Description" "Security ICs / Authentication ICs"
				(at 50.8 -25.4 0)
				(effects
					(font
						(size 1.27 1.27)
					)
					(justify left bottom)
					(hide yes)
				)
			)
			(property "MPN" "SLB9673AU20FW2610XTMA1"
				(at 50.8 -7.62 0)
				(effects
					(font
						(size 1.27 1.27)
						(thickness 0.15)
					)
					(justify left bottom)
				)
			)
			(property "Manufacturer" "Infineon"
				(at 50.8 -10.16 0)
				(effects
					(font
						(size 1.27 1.27)
						(thickness 0.15)
					)
					(justify left bottom)
					(hide yes)
				)
			)
			(property "Author" "Antmicro"
				(at 50.8 -12.7 0)
				(effects
					(font
						(size 1.27 1.27)
						(thickness 0.15)
					)
					(justify left bottom)
					(hide yes)
				)
			)
			(property "License" "Apache-2.0"
				(at 50.8 -15.24 0)
				(effects
					(font
						(size 1.27 1.27)
						(thickness 0.15)
					)
					(justify left bottom)
					(hide yes)
				)
			)
			(property "ki_keywords" "IC"
				(at 0 0 0)
				(effects
					(font
						(size 1.27 1.27)
					)
					(hide yes)
				)
			)
			(symbol "SLB9673AU20FW2610XTMA1_1_1"
				(rectangle
					(start 2.54 2.54)
					(end 33.02 -43.18)
					(stroke
						(width 0.254)
						(type default)
					)
					(fill
						(type background)
					)
				)
				(pin power_in line
					(at 0 0 0)
					(length 2.54)
					(name "VDD"
						(effects
							(font
								(size 1.27 1.27)
							)
						)
					)
					(number "1"
						(effects
							(font
								(size 1.27 1.27)
							)
						)
					)
				)
				(pin passive line
					(at 0 0 0)
					(length 2.54)
					(hide yes)
					(name "VDD"
						(effects
							(font
								(size 1.27 1.27)
							)
						)
					)
					(number "14"
						(effects
							(font
								(size 1.27 1.27)
							)
						)
					)
				)
				(pin passive line
					(at 0 0 0)
					(length 2.54)
					(hide yes)
					(name "VDD"
						(effects
							(font
								(size 1.27 1.27)
							)
						)
					)
					(number "22"
						(effects
							(font
								(size 1.27 1.27)
							)
						)
					)
				)
				(pin passive line
					(at 0 -2.54 0)
					(length 2.54)
					(name "TEST#"
						(effects
							(font
								(size 1.27 1.27)
							)
						)
					)
					(number "20"
						(effects
							(font
								(size 1.27 1.27)
							)
						)
					)
				)
				(pin passive line
					(at 0 -5.08 0)
					(length 2.54)
					(name "NCI/VDD"
						(effects
							(font
								(size 1.27 1.27)
							)
						)
					)
					(number "8"
						(effects
							(font
								(size 1.27 1.27)
							)
						)
					)
				)
				(pin passive line
					(at 0 -10.16 0)
					(length 2.54)
					(name "SCL"
						(effects
							(font
								(size 1.27 1.27)
							)
						)
					)
					(number "30"
						(effects
							(font
								(size 1.27 1.27)
							)
						)
					)
				)
				(pin passive line
					(at 0 -12.7 0)
					(length 2.54)
					(name "SDA"
						(effects
							(font
								(size 1.27 1.27)
							)
						)
					)
					(number "29"
						(effects
							(font
								(size 1.27 1.27)
							)
						)
					)
				)
				(pin passive line
					(at 0 -15.24 0)
					(length 2.54)
					(name "RST#"
						(effects
							(font
								(size 1.27 1.27)
							)
						)
					)
					(number "17"
						(effects
							(font
								(size 1.27 1.27)
							)
						)
					)
				)
				(pin passive line
					(at 0 -20.32 0)
					(length 2.54)
					(name "I2C_PIRQ#"
						(effects
							(font
								(size 1.27 1.27)
							)
						)
					)
					(number "18"
						(effects
							(font
								(size 1.27 1.27)
							)
						)
					)
				)
				(pin passive line
					(at 0 -25.4 0)
					(length 2.54)
					(name "GPIO_00"
						(effects
							(font
								(size 1.27 1.27)
							)
						)
					)
					(number "3"
						(effects
							(font
								(size 1.27 1.27)
							)
						)
					)
				)
				(pin passive line
					(at 0 -27.94 0)
					(length 2.54)
					(name "GPIO_01"
						(effects
							(font
								(size 1.27 1.27)
							)
						)
					)
					(number "4"
						(effects
							(font
								(size 1.27 1.27)
							)
						)
					)
				)
				(pin passive line
					(at 0 -30.48 0)
					(length 2.54)
					(name "GPIO_02"
						(effects
							(font
								(size 1.27 1.27)
							)
						)
					)
					(number "7"
						(effects
							(font
								(size 1.27 1.27)
							)
						)
					)
				)
				(pin passive line
					(at 0 -35.56 0)
					(length 2.54)
					(name "EP"
						(effects
							(font
								(size 1.27 1.27)
							)
						)
					)
					(number "33"
						(effects
							(font
								(size 1.27 1.27)
							)
						)
					)
				)
				(pin passive line
					(at 0 -38.1 0)
					(length 2.54)
					(name "NCI/GND"
						(effects
							(font
								(size 1.27 1.27)
							)
						)
					)
					(number "16"
						(effects
							(font
								(size 1.27 1.27)
							)
						)
					)
				)
				(pin power_in line
					(at 0 -40.64 0)
					(length 2.54)
					(name "GND"
						(effects
							(font
								(size 1.27 1.27)
							)
						)
					)
					(number "2"
						(effects
							(font
								(size 1.27 1.27)
							)
						)
					)
				)
				(pin passive line
					(at 0 -40.64 0)
					(length 2.54)
					(hide yes)
					(name "GND"
						(effects
							(font
								(size 1.27 1.27)
							)
						)
					)
					(number "23"
						(effects
							(font
								(size 1.27 1.27)
							)
						)
					)
				)
				(pin passive line
					(at 0 -40.64 0)
					(length 2.54)
					(hide yes)
					(name "GND"
						(effects
							(font
								(size 1.27 1.27)
							)
						)
					)
					(number "32"
						(effects
							(font
								(size 1.27 1.27)
							)
						)
					)
				)
				(pin passive line
					(at 0 -40.64 0)
					(length 2.54)
					(hide yes)
					(name "GND"
						(effects
							(font
								(size 1.27 1.27)
							)
						)
					)
					(number "9"
						(effects
							(font
								(size 1.27 1.27)
							)
						)
					)
				)
				(pin no_connect line
					(at 33.02 -5.08 180)
					(length 2.54)
					(hide yes)
					(name "NCI"
						(effects
							(font
								(size 1.27 1.27)
							)
						)
					)
					(number "31"
						(effects
							(font
								(size 1.27 1.27)
							)
						)
					)
				)
				(pin no_connect line
					(at 33.02 -7.62 180)
					(length 2.54)
					(hide yes)
					(name "NCI"
						(effects
							(font
								(size 1.27 1.27)
							)
						)
					)
					(number "28"
						(effects
							(font
								(size 1.27 1.27)
							)
						)
					)
				)
				(pin no_connect line
					(at 33.02 -10.16 180)
					(length 2.54)
					(hide yes)
					(name "NCI"
						(effects
							(font
								(size 1.27 1.27)
							)
						)
					)
					(number "27"
						(effects
							(font
								(size 1.27 1.27)
							)
						)
					)
				)
				(pin no_connect line
					(at 33.02 -12.7 180)
					(length 2.54)
					(hide yes)
					(name "NCI"
						(effects
							(font
								(size 1.27 1.27)
							)
						)
					)
					(number "26"
						(effects
							(font
								(size 1.27 1.27)
							)
						)
					)
				)
				(pin no_connect line
					(at 33.02 -15.24 180)
					(length 2.54)
					(hide yes)
					(name "NCI"
						(effects
							(font
								(size 1.27 1.27)
							)
						)
					)
					(number "25"
						(effects
							(font
								(size 1.27 1.27)
							)
						)
					)
				)
				(pin no_connect line
					(at 33.02 -17.78 180)
					(length 2.54)
					(hide yes)
					(name "NC"
						(effects
							(font
								(size 1.27 1.27)
							)
						)
					)
					(number "19"
						(effects
							(font
								(size 1.27 1.27)
							)
						)
					)
				)
				(pin no_connect line
					(at 33.02 -20.32 180)
					(length 2.54)
					(hide yes)
					(name "NC"
						(effects
							(font
								(size 1.27 1.27)
							)
						)
					)
					(number "21"
						(effects
							(font
								(size 1.27 1.27)
							)
						)
					)
				)
				(pin no_connect line
					(at 33.02 -22.86 180)
					(length 2.54)
					(hide yes)
					(name "NC"
						(effects
							(font
								(size 1.27 1.27)
							)
						)
					)
					(number "24"
						(effects
							(font
								(size 1.27 1.27)
							)
						)
					)
				)
				(pin no_connect line
					(at 33.02 -25.4 180)
					(length 2.54)
					(hide yes)
					(name "NC"
						(effects
							(font
								(size 1.27 1.27)
							)
						)
					)
					(number "6"
						(effects
							(font
								(size 1.27 1.27)
							)
						)
					)
				)
				(pin no_connect line
					(at 33.02 -27.94 180)
					(length 2.54)
					(hide yes)
					(name "NCI"
						(effects
							(font
								(size 1.27 1.27)
							)
						)
					)
					(number "10"
						(effects
							(font
								(size 1.27 1.27)
							)
						)
					)
				)
				(pin no_connect line
					(at 33.02 -30.48 180)
					(length 2.54)
					(hide yes)
					(name "NCI"
						(effects
							(font
								(size 1.27 1.27)
							)
						)
					)
					(number "11"
						(effects
							(font
								(size 1.27 1.27)
							)
						)
					)
				)
				(pin no_connect line
					(at 33.02 -33.02 180)
					(length 2.54)
					(hide yes)
					(name "NCI"
						(effects
							(font
								(size 1.27 1.27)
							)
						)
					)
					(number "5"
						(effects
							(font
								(size 1.27 1.27)
							)
						)
					)
				)
				(pin no_connect line
					(at 33.02 -35.56 180)
					(length 2.54)
					(hide yes)
					(name "NCI"
						(effects
							(font
								(size 1.27 1.27)
							)
						)
					)
					(number "12"
						(effects
							(font
								(size 1.27 1.27)
							)
						)
					)
				)
				(pin no_connect line
					(at 33.02 -38.1 180)
					(length 2.54)
					(hide yes)
					(name "NCI"
						(effects
							(font
								(size 1.27 1.27)
							)
						)
					)
					(number "13"
						(effects
							(font
								(size 1.27 1.27)
							)
						)
					)
				)
				(pin no_connect line
					(at 33.02 -40.64 180)
					(length 2.54)
					(hide yes)
					(name "NCI"
						(effects
							(font
								(size 1.27 1.27)
							)
						)
					)
					(number "15"
						(effects
							(font
								(size 1.27 1.27)
							)
						)
					)
				)
			)
		)
	(symbol "antmicroInterfaceControllers:TPS65988DHRSHR"
			(exclude_from_sim no)
			(in_bom yes)
			(on_board yes)
			(property "Reference" "U"
				(at 49.53 -2.54 0)
				(effects
					(font
						(size 1.27 1.27)
						(thickness 0.15)
					)
					(justify left bottom)
				)
			)
			(property "Value" "TPS65988DHRSHR"
				(at 49.53 -5.08 0)
				(effects
					(font
						(size 1.27 1.27)
						(thickness 0.15)
					)
					(justify left bottom)
					(hide yes)
				)
			)
			(property "Footprint" "antmicro-footprints:IC_TPS65987DDHRSHR"
				(at 49.53 -7.62 0)
				(effects
					(font
						(size 1.27 1.27)
						(thickness 0.15)
					)
					(justify left bottom)
					(hide yes)
				)
			)
			(property "Datasheet" "https://www.ti.com/lit/ds/symlink/tps65988.pdf?ts=1662726631004&ref_url=https%253A%252F%252Fwww.ti.com%252Fproduct%252FTPS65988"
				(at 49.53 -10.16 0)
				(effects
					(font
						(size 1.27 1.27)
						(thickness 0.15)
					)
					(justify left bottom)
					(hide yes)
				)
			)
			(property "Description" "USB, Type-C Controller PMIC 56-VQFN (7x7)"
				(at 49.53 -22.86 0)
				(effects
					(font
						(size 1.27 1.27)
					)
					(justify left bottom)
					(hide yes)
				)
			)
			(property "MPN" "TPS65988DHRSHR "
				(at 49.53 -12.7 0)
				(effects
					(font
						(size 1.27 1.27)
						(thickness 0.15)
					)
					(justify left bottom)
				)
			)
			(property "Manufacturer" "Texas Instruments"
				(at 49.53 -15.24 0)
				(effects
					(font
						(size 1.27 1.27)
						(thickness 0.15)
					)
					(justify left bottom)
					(hide yes)
				)
			)
			(property "License" "Apache-2.0"
				(at 49.53 -17.78 0)
				(effects
					(font
						(size 1.27 1.27)
						(thickness 0.15)
					)
					(justify left bottom)
					(hide yes)
				)
			)
			(property "Author" "Antmicro"
				(at 49.53 -20.32 0)
				(effects
					(font
						(size 1.27 1.27)
						(thickness 0.15)
					)
					(justify left bottom)
					(hide yes)
				)
			)
			(property "ki_locked" ""
				(at 0 0 0)
				(effects
					(font
						(size 1.27 1.27)
					)
				)
			)
			(property "ki_keywords" "SMT, CONTROLLER, IC, USB"
				(at 0 0 0)
				(effects
					(font
						(size 1.27 1.27)
					)
					(hide yes)
				)
			)
			(symbol "TPS65988DHRSHR_1_1"
				(rectangle
					(start 2.54 2.54)
					(end 33.02 -69.85)
					(stroke
						(width 0.254)
						(type default)
					)
					(fill
						(type background)
					)
				)
				(pin power_in line
					(at 0 0 0)
					(length 2.54)
					(name "VIN_3V3"
						(effects
							(font
								(size 1.27 1.27)
							)
						)
					)
					(number "5"
						(effects
							(font
								(size 1.27 1.27)
							)
						)
					)
				)
				(pin power_out line
					(at 0 -2.54 0)
					(length 2.54)
					(name "LDO_1V8"
						(effects
							(font
								(size 1.27 1.27)
							)
						)
					)
					(number "35"
						(effects
							(font
								(size 1.27 1.27)
							)
						)
					)
				)
				(pin power_out line
					(at 0 -5.08 0)
					(length 2.54)
					(name "LDO_3V3"
						(effects
							(font
								(size 1.27 1.27)
							)
						)
					)
					(number "9"
						(effects
							(font
								(size 1.27 1.27)
							)
						)
					)
				)
				(pin input line
					(at 0 -13.97 0)
					(length 2.54)
					(name "HRESET"
						(effects
							(font
								(size 1.27 1.27)
							)
						)
					)
					(number "44"
						(effects
							(font
								(size 1.27 1.27)
							)
						)
					)
				)
				(pin input line
					(at 0 -22.86 0)
					(length 2.54)
					(name "ADCIN1"
						(effects
							(font
								(size 1.27 1.27)
							)
						)
					)
					(number "6"
						(effects
							(font
								(size 1.27 1.27)
							)
						)
					)
				)
				(pin input line
					(at 0 -34.29 0)
					(length 2.54)
					(name "ADCIN2"
						(effects
							(font
								(size 1.27 1.27)
							)
						)
					)
					(number "10"
						(effects
							(font
								(size 1.27 1.27)
							)
						)
					)
				)
				(pin power_in line
					(at 0 -64.77 0)
					(length 2.54)
					(name "GND"
						(effects
							(font
								(size 1.27 1.27)
							)
						)
					)
					(number "20"
						(effects
							(font
								(size 1.27 1.27)
							)
						)
					)
				)
				(pin passive line
					(at 0 -64.77 0)
					(length 2.54)
					(hide yes)
					(name "GND"
						(effects
							(font
								(size 1.27 1.27)
							)
						)
					)
					(number "51"
						(effects
							(font
								(size 1.27 1.27)
							)
						)
					)
				)
				(pin power_in line
					(at 0 -67.31 0)
					(length 2.54)
					(name "GND_EP"
						(effects
							(font
								(size 1.27 1.27)
							)
						)
					)
					(number "59"
						(effects
							(font
								(size 1.27 1.27)
							)
						)
					)
				)
				(pin bidirectional line
					(at 35.56 0 180)
					(length 2.54)
					(name "GPIO0"
						(effects
							(font
								(size 1.27 1.27)
							)
						)
					)
					(number "16"
						(effects
							(font
								(size 1.27 1.27)
							)
						)
					)
				)
				(pin bidirectional line
					(at 35.56 -2.54 180)
					(length 2.54)
					(name "GPIO1"
						(effects
							(font
								(size 1.27 1.27)
							)
						)
					)
					(number "17"
						(effects
							(font
								(size 1.27 1.27)
							)
						)
					)
				)
				(pin bidirectional line
					(at 35.56 -5.08 180)
					(length 2.54)
					(name "GPIO2"
						(effects
							(font
								(size 1.27 1.27)
							)
						)
					)
					(number "18"
						(effects
							(font
								(size 1.27 1.27)
							)
						)
					)
				)
				(pin bidirectional line
					(at 35.56 -7.62 180)
					(length 2.54)
					(name "HPD1"
						(effects
							(font
								(size 1.27 1.27)
							)
						)
					)
					(number "30"
						(effects
							(font
								(size 1.27 1.27)
							)
						)
					)
					(alternate "GPIO3" bidirectional line)
				)
				(pin bidirectional line
					(at 35.56 -10.16 180)
					(length 2.54)
					(name "HPD2"
						(effects
							(font
								(size 1.27 1.27)
							)
						)
					)
					(number "31"
						(effects
							(font
								(size 1.27 1.27)
							)
						)
					)
					(alternate "GPIO4" bidirectional line)
				)
				(pin bidirectional line
					(at 35.56 -13.97 180)
					(length 2.54)
					(name "I2C3_SCL"
						(effects
							(font
								(size 1.27 1.27)
							)
						)
					)
					(number "21"
						(effects
							(font
								(size 1.27 1.27)
							)
						)
					)
					(alternate "GPIO5" bidirectional line)
				)
				(pin bidirectional line
					(at 35.56 -16.51 180)
					(length 2.54)
					(name "I2C3_SDA"
						(effects
							(font
								(size 1.27 1.27)
							)
						)
					)
					(number "22"
						(effects
							(font
								(size 1.27 1.27)
							)
						)
					)
					(alternate "GPIO6" bidirectional line)
				)
				(pin bidirectional line
					(at 35.56 -19.05 180)
					(length 2.54)
					(name "~{I2C3_IRQ}"
						(effects
							(font
								(size 1.27 1.27)
							)
						)
					)
					(number "23"
						(effects
							(font
								(size 1.27 1.27)
							)
						)
					)
					(alternate "GPIO7" bidirectional line)
				)
				(pin bidirectional line
					(at 35.56 -22.86 180)
					(length 2.54)
					(name "SPI_POCI"
						(effects
							(font
								(size 1.27 1.27)
							)
						)
					)
					(number "36"
						(effects
							(font
								(size 1.27 1.27)
							)
						)
					)
					(alternate "GPIO8" bidirectional line)
				)
				(pin bidirectional line
					(at 35.56 -25.4 180)
					(length 2.54)
					(name "SPI_PICO"
						(effects
							(font
								(size 1.27 1.27)
							)
						)
					)
					(number "37"
						(effects
							(font
								(size 1.27 1.27)
							)
						)
					)
					(alternate "GPIO9" bidirectional line)
				)
				(pin bidirectional line
					(at 35.56 -27.94 180)
					(length 2.54)
					(name "SPI_CLK"
						(effects
							(font
								(size 1.27 1.27)
							)
						)
					)
					(number "38"
						(effects
							(font
								(size 1.27 1.27)
							)
						)
					)
					(alternate "GPIO10" bidirectional line)
				)
				(pin bidirectional line
					(at 35.56 -30.48 180)
					(length 2.54)
					(name "~{SPI_CS}"
						(effects
							(font
								(size 1.27 1.27)
							)
						)
					)
					(number "39"
						(effects
							(font
								(size 1.27 1.27)
							)
						)
					)
					(alternate "GPIO11" bidirectional line)
				)
				(pin bidirectional line
					(at 35.56 -34.29 180)
					(length 2.54)
					(name "GPIO12"
						(effects
							(font
								(size 1.27 1.27)
							)
						)
					)
					(number "40"
						(effects
							(font
								(size 1.27 1.27)
							)
						)
					)
				)
				(pin bidirectional line
					(at 35.56 -36.83 180)
					(length 2.54)
					(name "GPIO13"
						(effects
							(font
								(size 1.27 1.27)
							)
						)
					)
					(number "41"
						(effects
							(font
								(size 1.27 1.27)
							)
						)
					)
				)
				(pin bidirectional line
					(at 35.56 -39.37 180)
					(length 2.54)
					(name "PWM1"
						(effects
							(font
								(size 1.27 1.27)
							)
						)
					)
					(number "42"
						(effects
							(font
								(size 1.27 1.27)
							)
						)
					)
					(alternate "GPIO14" bidirectional line)
				)
				(pin bidirectional line
					(at 35.56 -41.91 180)
					(length 2.54)
					(name "PWM2"
						(effects
							(font
								(size 1.27 1.27)
							)
						)
					)
					(number "43"
						(effects
							(font
								(size 1.27 1.27)
							)
						)
					)
					(alternate "GPIO15" bidirectional line)
				)
				(pin bidirectional line
					(at 35.56 -44.45 180)
					(length 2.54)
					(name "PP_EXT1"
						(effects
							(font
								(size 1.27 1.27)
							)
						)
					)
					(number "48"
						(effects
							(font
								(size 1.27 1.27)
							)
						)
					)
					(alternate "GPIO16" bidirectional line)
				)
				(pin bidirectional line
					(at 35.56 -46.99 180)
					(length 2.54)
					(name "PP_EXT2"
						(effects
							(font
								(size 1.27 1.27)
							)
						)
					)
					(number "49"
						(effects
							(font
								(size 1.27 1.27)
							)
						)
					)
					(alternate "GPIO17" bidirectional line)
				)
				(pin output line
					(at 35.56 -52.07 180)
					(length 2.54)
					(name "~{I2C1_IRQ}"
						(effects
							(font
								(size 1.27 1.27)
							)
						)
					)
					(number "29"
						(effects
							(font
								(size 1.27 1.27)
							)
						)
					)
				)
				(pin bidirectional line
					(at 35.56 -54.61 180)
					(length 2.54)
					(name "I2C1_SCL"
						(effects
							(font
								(size 1.27 1.27)
							)
						)
					)
					(number "27"
						(effects
							(font
								(size 1.27 1.27)
							)
						)
					)
				)
				(pin bidirectional line
					(at 35.56 -57.15 180)
					(length 2.54)
					(name "I2C1_SDA"
						(effects
							(font
								(size 1.27 1.27)
							)
						)
					)
					(number "28"
						(effects
							(font
								(size 1.27 1.27)
							)
						)
					)
				)
				(pin output line
					(at 35.56 -62.23 180)
					(length 2.54)
					(name "~{I2C2_IRQ}"
						(effects
							(font
								(size 1.27 1.27)
							)
						)
					)
					(number "34"
						(effects
							(font
								(size 1.27 1.27)
							)
						)
					)
				)
				(pin bidirectional line
					(at 35.56 -64.77 180)
					(length 2.54)
					(name "I2C2_SCL"
						(effects
							(font
								(size 1.27 1.27)
							)
						)
					)
					(number "32"
						(effects
							(font
								(size 1.27 1.27)
							)
						)
					)
				)
				(pin bidirectional line
					(at 35.56 -67.31 180)
					(length 2.54)
					(name "I2C2_SDA"
						(effects
							(font
								(size 1.27 1.27)
							)
						)
					)
					(number "33"
						(effects
							(font
								(size 1.27 1.27)
							)
						)
					)
				)
			)
			(symbol "TPS65988DHRSHR_2_1"
				(rectangle
					(start 2.54 3.81)
					(end 29.21 -19.05)
					(stroke
						(width 0.254)
						(type default)
					)
					(fill
						(type background)
					)
				)
				(polyline
					(pts
						(xy 11.303 0) (xy 13.208 0)
					)
					(stroke
						(width 0.254)
						(type default)
					)
					(fill
						(type background)
					)
				)
				(polyline
					(pts
						(xy 13.208 0) (xy 16.002 1.651)
					)
					(stroke
						(width 0.254)
						(type default)
					)
					(fill
						(type background)
					)
				)
				(circle
					(center 13.208 0)
					(radius 0.1796)
					(stroke
						(width 0.254)
						(type default)
					)
					(fill
						(type background)
					)
				)
				(circle
					(center 16.637 0)
					(radius 0.1796)
					(stroke
						(width 0.254)
						(type default)
					)
					(fill
						(type background)
					)
				)
				(polyline
					(pts
						(xy 19.177 0) (xy 16.637 0)
					)
					(stroke
						(width 0.254)
						(type default)
					)
					(fill
						(type background)
					)
				)
				(pin bidirectional line
					(at 0 0 0)
					(length 2.54)
					(name "VBUS1"
						(effects
							(font
								(size 1.27 1.27)
							)
						)
					)
					(number "13"
						(effects
							(font
								(size 1.27 1.27)
							)
						)
					)
				)
				(pin bidirectional line
					(at 0 -5.08 0)
					(length 2.54)
					(name "C1_CC1"
						(effects
							(font
								(size 1.27 1.27)
							)
						)
					)
					(number "24"
						(effects
							(font
								(size 1.27 1.27)
							)
						)
					)
				)
				(pin bidirectional line
					(at 0 -7.62 0)
					(length 2.54)
					(name "C1_CC2"
						(effects
							(font
								(size 1.27 1.27)
							)
						)
					)
					(number "26"
						(effects
							(font
								(size 1.27 1.27)
							)
						)
					)
				)
				(pin bidirectional line
					(at 0 -12.7 0)
					(length 2.54)
					(name "C1_USB_N"
						(effects
							(font
								(size 1.27 1.27)
							)
						)
					)
					(number "53"
						(effects
							(font
								(size 1.27 1.27)
							)
						)
					)
					(alternate "GPIO19" bidirectional line)
				)
				(pin bidirectional line
					(at 0 -15.24 0)
					(length 2.54)
					(name "C1_USB_P"
						(effects
							(font
								(size 1.27 1.27)
							)
						)
					)
					(number "50"
						(effects
							(font
								(size 1.27 1.27)
							)
						)
					)
					(alternate "GPIO18" bidirectional line)
				)
				(pin bidirectional line
					(at 31.75 0 180)
					(length 2.54)
					(name "PP_HV1"
						(effects
							(font
								(size 1.27 1.27)
							)
						)
					)
					(number "11"
						(effects
							(font
								(size 1.27 1.27)
							)
						)
					)
				)
				(pin power_in line
					(at 31.75 -3.81 180)
					(length 2.54)
					(name "PP1_CABLE"
						(effects
							(font
								(size 1.27 1.27)
							)
						)
					)
					(number "25"
						(effects
							(font
								(size 1.27 1.27)
							)
						)
					)
				)
				(pin passive line
					(at 31.75 -15.24 180)
					(length 2.54)
					(name "DRAIN1"
						(effects
							(font
								(size 1.27 1.27)
							)
						)
					)
					(number "15"
						(effects
							(font
								(size 1.27 1.27)
							)
						)
					)
				)
				(pin passive line
					(at 31.75 -15.24 180)
					(length 2.54)
					(hide yes)
					(name "DRAIN1"
						(effects
							(font
								(size 1.27 1.27)
							)
						)
					)
					(number "19"
						(effects
							(font
								(size 1.27 1.27)
							)
						)
					)
				)
				(pin passive line
					(at 31.75 -15.24 180)
					(length 2.54)
					(hide yes)
					(name "DRAIN1"
						(effects
							(font
								(size 1.27 1.27)
							)
						)
					)
					(number "58"
						(effects
							(font
								(size 1.27 1.27)
							)
						)
					)
				)
				(pin passive line
					(at 31.75 -15.24 180)
					(length 2.54)
					(hide yes)
					(name "DRAIN1"
						(effects
							(font
								(size 1.27 1.27)
							)
						)
					)
					(number "8"
						(effects
							(font
								(size 1.27 1.27)
							)
						)
					)
				)
			)
			(symbol "TPS65988DHRSHR_3_1"
				(rectangle
					(start 2.54 3.81)
					(end 29.21 -19.05)
					(stroke
						(width 0.254)
						(type default)
					)
					(fill
						(type background)
					)
				)
				(polyline
					(pts
						(xy 11.557 0) (xy 13.462 0)
					)
					(stroke
						(width 0.254)
						(type default)
					)
					(fill
						(type background)
					)
				)
				(polyline
					(pts
						(xy 13.462 0) (xy 16.256 1.651)
					)
					(stroke
						(width 0.254)
						(type default)
					)
					(fill
						(type background)
					)
				)
				(circle
					(center 13.462 0)
					(radius 0.1796)
					(stroke
						(width 0.254)
						(type default)
					)
					(fill
						(type background)
					)
				)
				(circle
					(center 16.891 0)
					(radius 0.1796)
					(stroke
						(width 0.254)
						(type default)
					)
					(fill
						(type background)
					)
				)
				(polyline
					(pts
						(xy 19.431 0) (xy 16.891 0)
					)
					(stroke
						(width 0.254)
						(type default)
					)
					(fill
						(type background)
					)
				)
				(pin bidirectional line
					(at 0 0 0)
					(length 2.54)
					(name "VBUS2"
						(effects
							(font
								(size 1.27 1.27)
							)
						)
					)
					(number "3"
						(effects
							(font
								(size 1.27 1.27)
							)
						)
					)
				)
				(pin bidirectional line
					(at 0 -5.08 0)
					(length 2.54)
					(name "C2_CC1"
						(effects
							(font
								(size 1.27 1.27)
							)
						)
					)
					(number "45"
						(effects
							(font
								(size 1.27 1.27)
							)
						)
					)
				)
				(pin bidirectional line
					(at 0 -7.62 0)
					(length 2.54)
					(name "C2_CC2"
						(effects
							(font
								(size 1.27 1.27)
							)
						)
					)
					(number "47"
						(effects
							(font
								(size 1.27 1.27)
							)
						)
					)
				)
				(pin bidirectional line
					(at 0 -12.7 0)
					(length 2.54)
					(name "C2_USB_N"
						(effects
							(font
								(size 1.27 1.27)
							)
						)
					)
					(number "55"
						(effects
							(font
								(size 1.27 1.27)
							)
						)
					)
					(alternate "GPIO21" bidirectional line)
				)
				(pin bidirectional line
					(at 0 -15.24 0)
					(length 2.54)
					(name "C2_USB_P"
						(effects
							(font
								(size 1.27 1.27)
							)
						)
					)
					(number "54"
						(effects
							(font
								(size 1.27 1.27)
							)
						)
					)
					(alternate "GPIO20" bidirectional line)
				)
				(pin bidirectional line
					(at 31.75 0 180)
					(length 2.54)
					(name "PP_HV2"
						(effects
							(font
								(size 1.27 1.27)
							)
						)
					)
					(number "1"
						(effects
							(font
								(size 1.27 1.27)
							)
						)
					)
				)
				(pin power_in line
					(at 31.75 -3.81 180)
					(length 2.54)
					(name "PP2_CABLE"
						(effects
							(font
								(size 1.27 1.27)
							)
						)
					)
					(number "46"
						(effects
							(font
								(size 1.27 1.27)
							)
						)
					)
				)
				(pin passive line
					(at 31.75 -15.24 180)
					(length 2.54)
					(name "DRAIN2"
						(effects
							(font
								(size 1.27 1.27)
							)
						)
					)
					(number "52"
						(effects
							(font
								(size 1.27 1.27)
							)
						)
					)
				)
				(pin passive line
					(at 31.75 -15.24 180)
					(length 2.54)
					(hide yes)
					(name "DRAIN2"
						(effects
							(font
								(size 1.27 1.27)
							)
						)
					)
					(number "56"
						(effects
							(font
								(size 1.27 1.27)
							)
						)
					)
				)
				(pin passive line
					(at 31.75 -15.24 180)
					(length 2.54)
					(hide yes)
					(name "DRAIN2"
						(effects
							(font
								(size 1.27 1.27)
							)
						)
					)
					(number "57"
						(effects
							(font
								(size 1.27 1.27)
							)
						)
					)
				)
				(pin passive line
					(at 31.75 -15.24 180)
					(length 2.54)
					(hide yes)
					(name "DRAIN2"
						(effects
							(font
								(size 1.27 1.27)
							)
						)
					)
					(number "7"
						(effects
							(font
								(size 1.27 1.27)
							)
						)
					)
				)
			)
		)
	(symbol "antmicroInterfaceControllers:TUSB1046-DCIRNQ"
			(exclude_from_sim no)
			(in_bom yes)
			(on_board yes)
			(property "Reference" "U"
				(at 38.1 -2.54 0)
				(effects
					(font
						(size 1.27 1.27)
						(thickness 0.15)
					)
					(justify left bottom)
				)
			)
			(property "Value" "TUSB1046-DCIRNQ"
				(at 38.1 -5.08 0)
				(effects
					(font
						(size 1.27 1.27)
						(thickness 0.15)
					)
					(justify left bottom)
					(hide yes)
				)
			)
			(property "Footprint" "antmicro-footprints:WQFN-40_1EP_6x3mm_Pitch0.4mm_EP4.7x2.7mm"
				(at 38.1 -7.62 0)
				(effects
					(font
						(size 1.27 1.27)
						(thickness 0.15)
					)
					(justify left bottom)
					(hide yes)
				)
			)
			(property "Datasheet" "https://www.ti.com/lit/ds/sllsew2d/sllsew2d.pdf?ts=1662107117482&ref_url=https%253A%252F%252Fwww.google.com%252F"
				(at 38.1 -10.16 0)
				(effects
					(font
						(size 1.27 1.27)
						(thickness 0.15)
					)
					(justify left bottom)
					(hide yes)
				)
			)
			(property "Description" "Analog & Digital Crosspoint ICs USB Type-C DP ALT Mode, 10-Gbps linear redriver crosspoint switch 40-WQFN 0°C to 70°C"
				(at 38.1 -22.86 0)
				(effects
					(font
						(size 1.27 1.27)
					)
					(justify left bottom)
					(hide yes)
				)
			)
			(property "MPN" "TUSB1046-DCIRNQT"
				(at 38.1 -12.7 0)
				(effects
					(font
						(size 1.27 1.27)
						(thickness 0.15)
					)
					(justify left bottom)
				)
			)
			(property "Manufacturer" "Texas Instruments"
				(at 38.1 -15.24 0)
				(effects
					(font
						(size 1.27 1.27)
						(thickness 0.15)
					)
					(justify left bottom)
					(hide yes)
				)
			)
			(property "Author" "Antmicro"
				(at 38.1 -17.78 0)
				(effects
					(font
						(size 1.27 1.27)
						(thickness 0.15)
					)
					(justify left bottom)
					(hide yes)
				)
			)
			(property "License" "Apache-2.0"
				(at 38.1 -20.32 0)
				(effects
					(font
						(size 1.27 1.27)
						(thickness 0.15)
					)
					(justify left bottom)
					(hide yes)
				)
			)
			(property "ki_keywords" "IC"
				(at 0 0 0)
				(effects
					(font
						(size 1.27 1.27)
					)
					(hide yes)
				)
			)
			(symbol "TUSB1046-DCIRNQ_1_1"
				(rectangle
					(start 2.54 2.54)
					(end 22.86 -76.2)
					(stroke
						(width 0.254)
						(type default)
					)
					(fill
						(type background)
					)
				)
				(pin power_in line
					(at 0 0 0)
					(length 2.54)
					(name "VCC"
						(effects
							(font
								(size 1.27 1.27)
							)
						)
					)
					(number "1"
						(effects
							(font
								(size 1.27 1.27)
							)
						)
					)
				)
				(pin passive line
					(at 0 0 0)
					(length 2.54)
					(hide yes)
					(name "VCC"
						(effects
							(font
								(size 1.27 1.27)
							)
						)
					)
					(number "20"
						(effects
							(font
								(size 1.27 1.27)
							)
						)
					)
				)
				(pin passive line
					(at 0 0 0)
					(length 2.54)
					(hide yes)
					(name "VCC"
						(effects
							(font
								(size 1.27 1.27)
							)
						)
					)
					(number "28"
						(effects
							(font
								(size 1.27 1.27)
							)
						)
					)
				)
				(pin passive line
					(at 0 0 0)
					(length 2.54)
					(hide yes)
					(name "VCC"
						(effects
							(font
								(size 1.27 1.27)
							)
						)
					)
					(number "6"
						(effects
							(font
								(size 1.27 1.27)
							)
						)
					)
				)
				(pin input line
					(at 0 -2.54 0)
					(length 2.54)
					(name "FLIP/SCL"
						(effects
							(font
								(size 1.27 1.27)
							)
						)
					)
					(number "21"
						(effects
							(font
								(size 1.27 1.27)
							)
						)
					)
				)
				(pin input line
					(at 0 -5.08 0)
					(length 2.54)
					(name "CTL0/SDA"
						(effects
							(font
								(size 1.27 1.27)
							)
						)
					)
					(number "22"
						(effects
							(font
								(size 1.27 1.27)
							)
						)
					)
				)
				(pin input line
					(at 0 -7.62 0)
					(length 2.54)
					(name "CTL1/HPDIN"
						(effects
							(font
								(size 1.27 1.27)
							)
						)
					)
					(number "23"
						(effects
							(font
								(size 1.27 1.27)
							)
						)
					)
				)
				(pin output line
					(at 0 -15.24 0)
					(length 2.54)
					(name "SSRX_P"
						(effects
							(font
								(size 1.27 1.27)
							)
						)
					)
					(number "5"
						(effects
							(font
								(size 1.27 1.27)
							)
						)
					)
				)
				(pin output line
					(at 0 -17.78 0)
					(length 2.54)
					(name "SSRX_N"
						(effects
							(font
								(size 1.27 1.27)
							)
						)
					)
					(number "4"
						(effects
							(font
								(size 1.27 1.27)
							)
						)
					)
				)
				(pin input line
					(at 0 -22.86 0)
					(length 2.54)
					(name "SSTX_P"
						(effects
							(font
								(size 1.27 1.27)
							)
						)
					)
					(number "8"
						(effects
							(font
								(size 1.27 1.27)
							)
						)
					)
				)
				(pin input line
					(at 0 -25.4 0)
					(length 2.54)
					(name "SSTX_N"
						(effects
							(font
								(size 1.27 1.27)
							)
						)
					)
					(number "7"
						(effects
							(font
								(size 1.27 1.27)
							)
						)
					)
				)
				(pin bidirectional line
					(at 0 -30.48 0)
					(length 2.54)
					(name "AUX_P"
						(effects
							(font
								(size 1.27 1.27)
							)
						)
					)
					(number "24"
						(effects
							(font
								(size 1.27 1.27)
							)
						)
					)
				)
				(pin bidirectional line
					(at 0 -33.02 0)
					(length 2.54)
					(name "AUX_N"
						(effects
							(font
								(size 1.27 1.27)
							)
						)
					)
					(number "25"
						(effects
							(font
								(size 1.27 1.27)
							)
						)
					)
				)
				(pin input line
					(at 0 -40.64 0)
					(length 2.54)
					(name "DP0_P"
						(effects
							(font
								(size 1.27 1.27)
							)
						)
					)
					(number "9"
						(effects
							(font
								(size 1.27 1.27)
							)
						)
					)
				)
				(pin input line
					(at 0 -43.18 0)
					(length 2.54)
					(name "DP0_N"
						(effects
							(font
								(size 1.27 1.27)
							)
						)
					)
					(number "10"
						(effects
							(font
								(size 1.27 1.27)
							)
						)
					)
				)
				(pin input line
					(at 0 -48.26 0)
					(length 2.54)
					(name "DP1_P"
						(effects
							(font
								(size 1.27 1.27)
							)
						)
					)
					(number "12"
						(effects
							(font
								(size 1.27 1.27)
							)
						)
					)
				)
				(pin input line
					(at 0 -50.8 0)
					(length 2.54)
					(name "DP1_N"
						(effects
							(font
								(size 1.27 1.27)
							)
						)
					)
					(number "13"
						(effects
							(font
								(size 1.27 1.27)
							)
						)
					)
				)
				(pin input line
					(at 0 -55.88 0)
					(length 2.54)
					(name "DP2_P"
						(effects
							(font
								(size 1.27 1.27)
							)
						)
					)
					(number "15"
						(effects
							(font
								(size 1.27 1.27)
							)
						)
					)
				)
				(pin input line
					(at 0 -58.42 0)
					(length 2.54)
					(name "DP2_N"
						(effects
							(font
								(size 1.27 1.27)
							)
						)
					)
					(number "16"
						(effects
							(font
								(size 1.27 1.27)
							)
						)
					)
				)
				(pin input line
					(at 0 -63.5 0)
					(length 2.54)
					(name "DP3_P"
						(effects
							(font
								(size 1.27 1.27)
							)
						)
					)
					(number "18"
						(effects
							(font
								(size 1.27 1.27)
							)
						)
					)
				)
				(pin input line
					(at 0 -66.04 0)
					(length 2.54)
					(name "DP3_N"
						(effects
							(font
								(size 1.27 1.27)
							)
						)
					)
					(number "19"
						(effects
							(font
								(size 1.27 1.27)
							)
						)
					)
				)
				(pin bidirectional line
					(at 0 -71.12 0)
					(length 2.54)
					(name "CAD_SNK/RSVD1"
						(effects
							(font
								(size 1.27 1.27)
							)
						)
					)
					(number "29"
						(effects
							(font
								(size 1.27 1.27)
							)
						)
					)
					(alternate "CAD_SNK" bidirectional line)
					(alternate "RSVD1" no_connect line)
				)
				(pin bidirectional line
					(at 0 -73.66 0)
					(length 2.54)
					(name "HPDIN/RSVD2"
						(effects
							(font
								(size 1.27 1.27)
							)
						)
					)
					(number "32"
						(effects
							(font
								(size 1.27 1.27)
							)
						)
					)
					(alternate "HPDIN" bidirectional line)
					(alternate "RSVD2" no_connect line)
				)
				(pin input line
					(at 25.4 0 180)
					(length 2.54)
					(name "RX1_P"
						(effects
							(font
								(size 1.27 1.27)
							)
						)
					)
					(number "30"
						(effects
							(font
								(size 1.27 1.27)
							)
						)
					)
				)
				(pin input line
					(at 25.4 -2.54 180)
					(length 2.54)
					(name "RX1_N"
						(effects
							(font
								(size 1.27 1.27)
							)
						)
					)
					(number "31"
						(effects
							(font
								(size 1.27 1.27)
							)
						)
					)
				)
				(pin output line
					(at 25.4 -7.62 180)
					(length 2.54)
					(name "TX1_P"
						(effects
							(font
								(size 1.27 1.27)
							)
						)
					)
					(number "33"
						(effects
							(font
								(size 1.27 1.27)
							)
						)
					)
				)
				(pin output line
					(at 25.4 -10.16 180)
					(length 2.54)
					(name "TX1_N"
						(effects
							(font
								(size 1.27 1.27)
							)
						)
					)
					(number "34"
						(effects
							(font
								(size 1.27 1.27)
							)
						)
					)
				)
				(pin input line
					(at 25.4 -15.24 180)
					(length 2.54)
					(name "RX2_P"
						(effects
							(font
								(size 1.27 1.27)
							)
						)
					)
					(number "40"
						(effects
							(font
								(size 1.27 1.27)
							)
						)
					)
				)
				(pin input line
					(at 25.4 -17.78 180)
					(length 2.54)
					(name "RX2_N"
						(effects
							(font
								(size 1.27 1.27)
							)
						)
					)
					(number "39"
						(effects
							(font
								(size 1.27 1.27)
							)
						)
					)
				)
				(pin output line
					(at 25.4 -22.86 180)
					(length 2.54)
					(name "TX2_P"
						(effects
							(font
								(size 1.27 1.27)
							)
						)
					)
					(number "37"
						(effects
							(font
								(size 1.27 1.27)
							)
						)
					)
				)
				(pin output line
					(at 25.4 -25.4 180)
					(length 2.54)
					(name "TX2_N"
						(effects
							(font
								(size 1.27 1.27)
							)
						)
					)
					(number "36"
						(effects
							(font
								(size 1.27 1.27)
							)
						)
					)
				)
				(pin bidirectional line
					(at 25.4 -30.48 180)
					(length 2.54)
					(name "SBU1"
						(effects
							(font
								(size 1.27 1.27)
							)
						)
					)
					(number "27"
						(effects
							(font
								(size 1.27 1.27)
							)
						)
					)
				)
				(pin bidirectional line
					(at 25.4 -33.02 180)
					(length 2.54)
					(name "SBU2"
						(effects
							(font
								(size 1.27 1.27)
							)
						)
					)
					(number "26"
						(effects
							(font
								(size 1.27 1.27)
							)
						)
					)
				)
				(pin input line
					(at 25.4 -48.26 180)
					(length 2.54)
					(name "I2C_EN"
						(effects
							(font
								(size 1.27 1.27)
							)
						)
					)
					(number "17"
						(effects
							(font
								(size 1.27 1.27)
							)
						)
					)
				)
				(pin input line
					(at 25.4 -50.8 180)
					(length 2.54)
					(name "SSEQ0/A0"
						(effects
							(font
								(size 1.27 1.27)
							)
						)
					)
					(number "11"
						(effects
							(font
								(size 1.27 1.27)
							)
						)
					)
				)
				(pin input line
					(at 25.4 -53.34 180)
					(length 2.54)
					(name "SSEQ1"
						(effects
							(font
								(size 1.27 1.27)
							)
						)
					)
					(number "3"
						(effects
							(font
								(size 1.27 1.27)
							)
						)
					)
				)
				(pin input line
					(at 25.4 -55.88 180)
					(length 2.54)
					(name "DPEQ0/A1"
						(effects
							(font
								(size 1.27 1.27)
							)
						)
					)
					(number "14"
						(effects
							(font
								(size 1.27 1.27)
							)
						)
					)
				)
				(pin input line
					(at 25.4 -58.42 180)
					(length 2.54)
					(name "DPEQ1"
						(effects
							(font
								(size 1.27 1.27)
							)
						)
					)
					(number "2"
						(effects
							(font
								(size 1.27 1.27)
							)
						)
					)
				)
				(pin input line
					(at 25.4 -60.96 180)
					(length 2.54)
					(name "EQ0"
						(effects
							(font
								(size 1.27 1.27)
							)
						)
					)
					(number "38"
						(effects
							(font
								(size 1.27 1.27)
							)
						)
					)
				)
				(pin input line
					(at 25.4 -63.5 180)
					(length 2.54)
					(name "EQ1"
						(effects
							(font
								(size 1.27 1.27)
							)
						)
					)
					(number "35"
						(effects
							(font
								(size 1.27 1.27)
							)
						)
					)
				)
				(pin power_in line
					(at 25.4 -73.66 180)
					(length 2.54)
					(name "GND"
						(effects
							(font
								(size 1.27 1.27)
							)
						)
					)
					(number "41"
						(effects
							(font
								(size 1.27 1.27)
							)
						)
					)
				)
			)
		)
	(symbol "antmicroInterfaceControllers:USB7252C"
			(exclude_from_sim no)
			(in_bom yes)
			(on_board yes)
			(property "Reference" "U"
				(at 71.12 -2.54 0)
				(effects
					(font
						(size 1.27 1.27)
						(thickness 0.15)
					)
					(justify left bottom)
				)
			)
			(property "Value" "USB7252C"
				(at 71.12 -7.62 0)
				(effects
					(font
						(size 1.27 1.27)
						(thickness 0.15)
					)
					(justify left bottom)
					(hide yes)
				)
			)
			(property "Footprint" "antmicro-footprints:VQFN-100-1EP_12x12x0.85mm_P0.4mm"
				(at 71.12 -10.16 0)
				(effects
					(font
						(size 1.27 1.27)
						(thickness 0.15)
					)
					(justify left bottom)
					(hide yes)
				)
			)
			(property "Datasheet" "https://ww1.microchip.com/downloads/en/DeviceDoc/00003852A.pdf"
				(at 71.12 -12.7 0)
				(effects
					(font
						(size 1.27 1.27)
						(thickness 0.15)
					)
					(justify left bottom)
					(hide yes)
				)
			)
			(property "Description" "4-Port USB 3.2 Hub, 2x Type-C with Power Delivery support, 1x USB 3.2, 1x USB 2.0"
				(at 71.12 -25.4 0)
				(effects
					(font
						(size 1.27 1.27)
						(thickness 0.15)
					)
					(justify left bottom)
					(hide yes)
				)
			)
			(property "MPN" "USB7252CT-I/KDX "
				(at 71.12 -5.08 0)
				(effects
					(font
						(size 1.27 1.27)
						(thickness 0.15)
					)
					(justify left bottom)
				)
			)
			(property "Manufacturer" "Microchip Technology"
				(at 71.12 -17.78 0)
				(effects
					(font
						(size 1.27 1.27)
						(thickness 0.15)
					)
					(justify left bottom)
					(hide yes)
				)
			)
			(property "Author" "Antmicro"
				(at 71.12 -20.32 0)
				(effects
					(font
						(size 1.27 1.27)
						(thickness 0.15)
					)
					(justify left bottom)
					(hide yes)
				)
			)
			(property "License" "Apache-2.0"
				(at 71.12 -22.86 0)
				(effects
					(font
						(size 1.27 1.27)
						(thickness 0.15)
					)
					(justify left bottom)
					(hide yes)
				)
			)
			(property "ki_keywords" "INTERFACE, CONTROLLER, IC, USB, HUB"
				(at 0 0 0)
				(effects
					(font
						(size 1.27 1.27)
					)
					(hide yes)
				)
			)
			(symbol "USB7252C_1_1"
				(rectangle
					(start 3.81 2.54)
					(end 52.07 -128.27)
					(stroke
						(width 0.254)
						(type default)
					)
					(fill
						(type background)
					)
				)
				(polyline
					(pts
						(xy 3.81 -6.604) (xy 25.4 -6.604) (xy 25.4 -28.194) (xy 3.81 -28.194)
					)
					(stroke
						(width 0.254)
						(type solid)
					)
					(fill
						(type background)
					)
				)
				(polyline
					(pts
						(xy 29.718 -35.56) (xy 29.718 -72.898) (xy 52.07 -72.898)
					)
					(stroke
						(width 0.254)
						(type solid)
					)
					(fill
						(type background)
					)
				)
				(polyline
					(pts
						(xy 29.718 -72.898) (xy 29.718 -92.71) (xy 52.07 -92.71)
					)
					(stroke
						(width 0.254)
						(type solid)
					)
					(fill
						(type background)
					)
				)
				(polyline
					(pts
						(xy 29.718 -92.71) (xy 29.718 -103.124) (xy 52.07 -103.124)
					)
					(stroke
						(width 0.254)
						(type solid)
					)
					(fill
						(type background)
					)
				)
				(polyline
					(pts
						(xy 51.054 2.54) (xy 29.718 2.54) (xy 29.718 -35.56) (xy 52.07 -35.56)
					)
					(stroke
						(width 0.254)
						(type solid)
					)
					(fill
						(type background)
					)
				)
				(text "UP PORT"
					(at 16.51 -27.686 0)
					(effects
						(font
							(size 1.27 1.27)
							(thickness 0.15)
						)
						(justify left bottom)
					)
				)
				(text "PORT 1\n"
					(at 30.226 -35.052 0)
					(effects
						(font
							(size 1.27 1.27)
							(thickness 0.15)
						)
						(justify left bottom)
					)
				)
				(text "PORT 2\n"
					(at 30.226 -72.39 0)
					(effects
						(font
							(size 1.27 1.27)
							(thickness 0.15)
						)
						(justify left bottom)
					)
				)
				(text "PORT 3\n"
					(at 30.226 -92.202 0)
					(effects
						(font
							(size 1.27 1.27)
							(thickness 0.15)
						)
						(justify left bottom)
					)
				)
				(text "PORT 4\n"
					(at 30.226 -102.616 0)
					(effects
						(font
							(size 1.27 1.27)
							(thickness 0.15)
						)
						(justify left bottom)
					)
				)
				(pin power_in line
					(at 0 0 0)
					(length 3.81)
					(name "VCORE"
						(effects
							(font
								(size 1.27 1.27)
							)
						)
					)
					(number "18"
						(effects
							(font
								(size 1.27 1.27)
							)
						)
					)
				)
				(pin power_in line
					(at 0 0 0)
					(length 3.81)
					(hide yes)
					(name "VCORE"
						(effects
							(font
								(size 1.27 1.27)
							)
						)
					)
					(number "25"
						(effects
							(font
								(size 1.27 1.27)
							)
						)
					)
				)
				(pin power_in line
					(at 0 0 0)
					(length 3.81)
					(hide yes)
					(name "VCORE"
						(effects
							(font
								(size 1.27 1.27)
							)
						)
					)
					(number "33"
						(effects
							(font
								(size 1.27 1.27)
							)
						)
					)
				)
				(pin power_in line
					(at 0 0 0)
					(length 3.81)
					(hide yes)
					(name "VCORE"
						(effects
							(font
								(size 1.27 1.27)
							)
						)
					)
					(number "39"
						(effects
							(font
								(size 1.27 1.27)
							)
						)
					)
				)
				(pin power_in line
					(at 0 0 0)
					(length 3.81)
					(hide yes)
					(name "VCORE"
						(effects
							(font
								(size 1.27 1.27)
							)
						)
					)
					(number "55"
						(effects
							(font
								(size 1.27 1.27)
							)
						)
					)
				)
				(pin power_in line
					(at 0 0 0)
					(length 3.81)
					(hide yes)
					(name "VCORE"
						(effects
							(font
								(size 1.27 1.27)
							)
						)
					)
					(number "78"
						(effects
							(font
								(size 1.27 1.27)
							)
						)
					)
				)
				(pin power_in line
					(at 0 0 0)
					(length 3.81)
					(hide yes)
					(name "VCORE"
						(effects
							(font
								(size 1.27 1.27)
							)
						)
					)
					(number "85"
						(effects
							(font
								(size 1.27 1.27)
							)
						)
					)
				)
				(pin power_in line
					(at 0 0 0)
					(length 3.81)
					(hide yes)
					(name "VCORE"
						(effects
							(font
								(size 1.27 1.27)
							)
						)
					)
					(number "9"
						(effects
							(font
								(size 1.27 1.27)
							)
						)
					)
				)
				(pin power_in line
					(at 0 0 0)
					(length 3.81)
					(hide yes)
					(name "VCORE"
						(effects
							(font
								(size 1.27 1.27)
							)
						)
					)
					(number "93"
						(effects
							(font
								(size 1.27 1.27)
							)
						)
					)
				)
				(pin power_in line
					(at 0 -2.54 0)
					(length 3.81)
					(name "VDD33"
						(effects
							(font
								(size 1.27 1.27)
							)
						)
					)
					(number "26"
						(effects
							(font
								(size 1.27 1.27)
							)
						)
					)
				)
				(pin power_in line
					(at 0 -2.54 0)
					(length 3.81)
					(hide yes)
					(name "VDD33"
						(effects
							(font
								(size 1.27 1.27)
							)
						)
					)
					(number "42"
						(effects
							(font
								(size 1.27 1.27)
							)
						)
					)
				)
				(pin power_in line
					(at 0 -2.54 0)
					(length 3.81)
					(hide yes)
					(name "VDD33"
						(effects
							(font
								(size 1.27 1.27)
							)
						)
					)
					(number "53"
						(effects
							(font
								(size 1.27 1.27)
							)
						)
					)
				)
				(pin power_in line
					(at 0 -2.54 0)
					(length 3.81)
					(hide yes)
					(name "VDD33"
						(effects
							(font
								(size 1.27 1.27)
							)
						)
					)
					(number "62"
						(effects
							(font
								(size 1.27 1.27)
							)
						)
					)
				)
				(pin power_in line
					(at 0 -2.54 0)
					(length 3.81)
					(hide yes)
					(name "VDD33"
						(effects
							(font
								(size 1.27 1.27)
							)
						)
					)
					(number "67"
						(effects
							(font
								(size 1.27 1.27)
							)
						)
					)
				)
				(pin power_in line
					(at 0 -2.54 0)
					(length 3.81)
					(hide yes)
					(name "VDD33"
						(effects
							(font
								(size 1.27 1.27)
							)
						)
					)
					(number "79"
						(effects
							(font
								(size 1.27 1.27)
							)
						)
					)
				)
				(pin power_in line
					(at 0 -2.54 0)
					(length 3.81)
					(hide yes)
					(name "VDD33"
						(effects
							(font
								(size 1.27 1.27)
							)
						)
					)
					(number "88"
						(effects
							(font
								(size 1.27 1.27)
							)
						)
					)
				)
				(pin power_in line
					(at 0 -2.54 0)
					(length 3.81)
					(hide yes)
					(name "VDD33"
						(effects
							(font
								(size 1.27 1.27)
							)
						)
					)
					(number "99"
						(effects
							(font
								(size 1.27 1.27)
							)
						)
					)
				)
				(pin input line
					(at 0 -5.08 0)
					(length 3.81)
					(name "RESET_N"
						(effects
							(font
								(size 1.27 1.27)
							)
						)
					)
					(number "1"
						(effects
							(font
								(size 1.27 1.27)
							)
						)
					)
				)
				(pin bidirectional line
					(at 0 -10.16 0)
					(length 3.81)
					(name "VBUS_MON_UP"
						(effects
							(font
								(size 1.27 1.27)
							)
						)
					)
					(number "80"
						(effects
							(font
								(size 1.27 1.27)
							)
						)
					)
				)
				(pin bidirectional line
					(at 0 -12.7 0)
					(length 3.81)
					(name "USB3UP_TXDP"
						(effects
							(font
								(size 1.27 1.27)
							)
						)
					)
					(number "91"
						(effects
							(font
								(size 1.27 1.27)
							)
						)
					)
				)
				(pin bidirectional line
					(at 0 -15.24 0)
					(length 3.81)
					(name "USB3UP_TXDM"
						(effects
							(font
								(size 1.27 1.27)
							)
						)
					)
					(number "92"
						(effects
							(font
								(size 1.27 1.27)
							)
						)
					)
				)
				(pin bidirectional line
					(at 0 -17.78 0)
					(length 3.81)
					(name "USB3UP_RXDP"
						(effects
							(font
								(size 1.27 1.27)
							)
						)
					)
					(number "94"
						(effects
							(font
								(size 1.27 1.27)
							)
						)
					)
				)
				(pin bidirectional line
					(at 0 -20.32 0)
					(length 3.81)
					(name "USB3UP_RXDM"
						(effects
							(font
								(size 1.27 1.27)
							)
						)
					)
					(number "95"
						(effects
							(font
								(size 1.27 1.27)
							)
						)
					)
				)
				(pin bidirectional line
					(at 0 -22.86 0)
					(length 3.81)
					(name "USB2UP_DP"
						(effects
							(font
								(size 1.27 1.27)
							)
						)
					)
					(number "89"
						(effects
							(font
								(size 1.27 1.27)
							)
						)
					)
				)
				(pin bidirectional line
					(at 0 -25.4 0)
					(length 3.81)
					(name "USB2UP_DM"
						(effects
							(font
								(size 1.27 1.27)
							)
						)
					)
					(number "90"
						(effects
							(font
								(size 1.27 1.27)
							)
						)
					)
				)
				(pin bidirectional line
					(at 0 -31.75 0)
					(length 3.81)
					(name "PF2"
						(effects
							(font
								(size 1.27 1.27)
							)
						)
					)
					(number "43"
						(effects
							(font
								(size 1.27 1.27)
							)
						)
					)
				)
				(pin bidirectional line
					(at 0 -34.29 0)
					(length 3.81)
					(name "PF3"
						(effects
							(font
								(size 1.27 1.27)
							)
						)
					)
					(number "44"
						(effects
							(font
								(size 1.27 1.27)
							)
						)
					)
				)
				(pin bidirectional line
					(at 0 -36.83 0)
					(length 3.81)
					(name "PF4"
						(effects
							(font
								(size 1.27 1.27)
							)
						)
					)
					(number "45"
						(effects
							(font
								(size 1.27 1.27)
							)
						)
					)
				)
				(pin bidirectional line
					(at 0 -39.37 0)
					(length 3.81)
					(name "PF5"
						(effects
							(font
								(size 1.27 1.27)
							)
						)
					)
					(number "46"
						(effects
							(font
								(size 1.27 1.27)
							)
						)
					)
				)
				(pin bidirectional line
					(at 0 -41.91 0)
					(length 3.81)
					(name "PF6"
						(effects
							(font
								(size 1.27 1.27)
							)
						)
					)
					(number "47"
						(effects
							(font
								(size 1.27 1.27)
							)
						)
					)
				)
				(pin bidirectional line
					(at 0 -44.45 0)
					(length 3.81)
					(name "PF7"
						(effects
							(font
								(size 1.27 1.27)
							)
						)
					)
					(number "48"
						(effects
							(font
								(size 1.27 1.27)
							)
						)
					)
				)
				(pin bidirectional line
					(at 0 -46.99 0)
					(length 3.81)
					(name "PF8"
						(effects
							(font
								(size 1.27 1.27)
							)
						)
					)
					(number "49"
						(effects
							(font
								(size 1.27 1.27)
							)
						)
					)
				)
				(pin bidirectional line
					(at 0 -49.53 0)
					(length 3.81)
					(name "PF9"
						(effects
							(font
								(size 1.27 1.27)
							)
						)
					)
					(number "50"
						(effects
							(font
								(size 1.27 1.27)
							)
						)
					)
				)
				(pin bidirectional line
					(at 0 -52.07 0)
					(length 3.81)
					(name "PF10"
						(effects
							(font
								(size 1.27 1.27)
							)
						)
					)
					(number "51"
						(effects
							(font
								(size 1.27 1.27)
							)
						)
					)
				)
				(pin bidirectional line
					(at 0 -54.61 0)
					(length 3.81)
					(name "PF11"
						(effects
							(font
								(size 1.27 1.27)
							)
						)
					)
					(number "52"
						(effects
							(font
								(size 1.27 1.27)
							)
						)
					)
				)
				(pin bidirectional line
					(at 0 -57.15 0)
					(length 3.81)
					(name "PF12"
						(effects
							(font
								(size 1.27 1.27)
							)
						)
					)
					(number "54"
						(effects
							(font
								(size 1.27 1.27)
							)
						)
					)
				)
				(pin bidirectional line
					(at 0 -59.69 0)
					(length 3.81)
					(name "PF13"
						(effects
							(font
								(size 1.27 1.27)
							)
						)
					)
					(number "56"
						(effects
							(font
								(size 1.27 1.27)
							)
						)
					)
				)
				(pin bidirectional line
					(at 0 -62.23 0)
					(length 3.81)
					(name "PF14"
						(effects
							(font
								(size 1.27 1.27)
							)
						)
					)
					(number "57"
						(effects
							(font
								(size 1.27 1.27)
							)
						)
					)
				)
				(pin bidirectional line
					(at 0 -64.77 0)
					(length 3.81)
					(name "PF15"
						(effects
							(font
								(size 1.27 1.27)
							)
						)
					)
					(number "58"
						(effects
							(font
								(size 1.27 1.27)
							)
						)
					)
				)
				(pin bidirectional line
					(at 0 -67.31 0)
					(length 3.81)
					(name "PF16"
						(effects
							(font
								(size 1.27 1.27)
							)
						)
					)
					(number "59"
						(effects
							(font
								(size 1.27 1.27)
							)
						)
					)
				)
				(pin bidirectional line
					(at 0 -69.85 0)
					(length 3.81)
					(name "PF17"
						(effects
							(font
								(size 1.27 1.27)
							)
						)
					)
					(number "60"
						(effects
							(font
								(size 1.27 1.27)
							)
						)
					)
				)
				(pin bidirectional line
					(at 0 -72.39 0)
					(length 3.81)
					(name "PF18"
						(effects
							(font
								(size 1.27 1.27)
							)
						)
					)
					(number "61"
						(effects
							(font
								(size 1.27 1.27)
							)
						)
					)
				)
				(pin bidirectional line
					(at 0 -74.93 0)
					(length 3.81)
					(name "PF19"
						(effects
							(font
								(size 1.27 1.27)
							)
						)
					)
					(number "66"
						(effects
							(font
								(size 1.27 1.27)
							)
						)
					)
				)
				(pin bidirectional line
					(at 0 -77.47 0)
					(length 3.81)
					(name "PF26"
						(effects
							(font
								(size 1.27 1.27)
							)
						)
					)
					(number "75"
						(effects
							(font
								(size 1.27 1.27)
							)
						)
					)
				)
				(pin bidirectional line
					(at 0 -80.01 0)
					(length 3.81)
					(name "PF27"
						(effects
							(font
								(size 1.27 1.27)
							)
						)
					)
					(number "76"
						(effects
							(font
								(size 1.27 1.27)
							)
						)
					)
				)
				(pin bidirectional line
					(at 0 -82.55 0)
					(length 3.81)
					(name "PF28"
						(effects
							(font
								(size 1.27 1.27)
							)
						)
					)
					(number "77"
						(effects
							(font
								(size 1.27 1.27)
							)
						)
					)
				)
				(pin bidirectional line
					(at 0 -85.09 0)
					(length 3.81)
					(name "PF29"
						(effects
							(font
								(size 1.27 1.27)
							)
						)
					)
					(number "74"
						(effects
							(font
								(size 1.27 1.27)
							)
						)
					)
				)
				(pin bidirectional line
					(at 0 -87.63 0)
					(length 3.81)
					(name "PF30"
						(effects
							(font
								(size 1.27 1.27)
							)
						)
					)
					(number "2"
						(effects
							(font
								(size 1.27 1.27)
							)
						)
					)
				)
				(pin bidirectional line
					(at 0 -90.17 0)
					(length 3.81)
					(name "PF31"
						(effects
							(font
								(size 1.27 1.27)
							)
						)
					)
					(number "3"
						(effects
							(font
								(size 1.27 1.27)
							)
						)
					)
				)
				(pin input line
					(at 0 -92.71 0)
					(length 3.81)
					(name "XTALI"
						(effects
							(font
								(size 1.27 1.27)
							)
						)
					)
					(number "98"
						(effects
							(font
								(size 1.27 1.27)
							)
						)
					)
					(alternate "CLK_IN" passive line)
				)
				(pin output line
					(at 0 -95.25 0)
					(length 3.81)
					(name "XTALO"
						(effects
							(font
								(size 1.27 1.27)
							)
						)
					)
					(number "97"
						(effects
							(font
								(size 1.27 1.27)
							)
						)
					)
				)
				(pin input line
					(at 0 -97.79 0)
					(length 3.81)
					(name "CFG_STRAP1"
						(effects
							(font
								(size 1.27 1.27)
							)
						)
					)
					(number "21"
						(effects
							(font
								(size 1.27 1.27)
							)
						)
					)
				)
				(pin input line
					(at 0 -100.33 0)
					(length 3.81)
					(name "CFG_STRAP2"
						(effects
							(font
								(size 1.27 1.27)
							)
						)
					)
					(number "22"
						(effects
							(font
								(size 1.27 1.27)
							)
						)
					)
				)
				(pin input line
					(at 0 -102.87 0)
					(length 3.81)
					(name "CFG_STRAP3"
						(effects
							(font
								(size 1.27 1.27)
							)
						)
					)
					(number "23"
						(effects
							(font
								(size 1.27 1.27)
							)
						)
					)
				)
				(pin passive line
					(at 0 -109.22 0)
					(length 3.81)
					(name "TEST1"
						(effects
							(font
								(size 1.27 1.27)
							)
						)
					)
					(number "63"
						(effects
							(font
								(size 1.27 1.27)
							)
						)
					)
				)
				(pin passive line
					(at 0 -111.76 0)
					(length 3.81)
					(name "TEST2"
						(effects
							(font
								(size 1.27 1.27)
							)
						)
					)
					(number "64"
						(effects
							(font
								(size 1.27 1.27)
							)
						)
					)
				)
				(pin passive line
					(at 0 -114.3 0)
					(length 3.81)
					(name "TEST3"
						(effects
							(font
								(size 1.27 1.27)
							)
						)
					)
					(number "65"
						(effects
							(font
								(size 1.27 1.27)
							)
						)
					)
				)
				(pin bidirectional line
					(at 0 -116.84 0)
					(length 3.81)
					(name "TESTEN"
						(effects
							(font
								(size 1.27 1.27)
							)
						)
					)
					(number "24"
						(effects
							(font
								(size 1.27 1.27)
							)
						)
					)
				)
				(pin input line
					(at 0 -121.92 0)
					(length 3.81)
					(name "RBIAS"
						(effects
							(font
								(size 1.27 1.27)
							)
						)
					)
					(number "100"
						(effects
							(font
								(size 1.27 1.27)
							)
						)
					)
				)
				(pin power_in line
					(at 0 -124.46 0)
					(length 3.81)
					(name "VSS"
						(effects
							(font
								(size 1.27 1.27)
							)
						)
					)
					(number "101"
						(effects
							(font
								(size 1.27 1.27)
							)
						)
					)
				)
				(pin no_connect line
					(at 3.81 -106.68 0)
					(length 3.81)
					(hide yes)
					(name "ATEST"
						(effects
							(font
								(size 1.27 1.27)
							)
						)
					)
					(number "96"
						(effects
							(font
								(size 1.27 1.27)
							)
						)
					)
				)
				(pin bidirectional line
					(at 55.88 -1.27 180)
					(length 3.81)
					(name "DP1_VBUS_MON"
						(effects
							(font
								(size 1.27 1.27)
							)
						)
					)
					(number "4"
						(effects
							(font
								(size 1.27 1.27)
							)
						)
					)
				)
				(pin bidirectional line
					(at 55.88 -3.81 180)
					(length 3.81)
					(name "DP1_CC1"
						(effects
							(font
								(size 1.27 1.27)
							)
						)
					)
					(number "12"
						(effects
							(font
								(size 1.27 1.27)
							)
						)
					)
				)
				(pin bidirectional line
					(at 55.88 -6.35 180)
					(length 3.81)
					(name "DP1_CC2"
						(effects
							(font
								(size 1.27 1.27)
							)
						)
					)
					(number "13"
						(effects
							(font
								(size 1.27 1.27)
							)
						)
					)
				)
				(pin bidirectional line
					(at 55.88 -8.89 180)
					(length 3.81)
					(name "USB3DN_RXDP1A"
						(effects
							(font
								(size 1.27 1.27)
							)
						)
					)
					(number "10"
						(effects
							(font
								(size 1.27 1.27)
							)
						)
					)
				)
				(pin bidirectional line
					(at 55.88 -11.43 180)
					(length 3.81)
					(name "USB3DN_RXDM1A"
						(effects
							(font
								(size 1.27 1.27)
							)
						)
					)
					(number "11"
						(effects
							(font
								(size 1.27 1.27)
							)
						)
					)
				)
				(pin bidirectional line
					(at 55.88 -13.97 180)
					(length 3.81)
					(name "USB3DN_TXDP1A"
						(effects
							(font
								(size 1.27 1.27)
							)
						)
					)
					(number "7"
						(effects
							(font
								(size 1.27 1.27)
							)
						)
					)
				)
				(pin bidirectional line
					(at 55.88 -16.51 180)
					(length 3.81)
					(name "USB3DN_TXDM1A"
						(effects
							(font
								(size 1.27 1.27)
							)
						)
					)
					(number "8"
						(effects
							(font
								(size 1.27 1.27)
							)
						)
					)
				)
				(pin bidirectional line
					(at 55.88 -19.05 180)
					(length 3.81)
					(name "USB3DN_RXDP1B"
						(effects
							(font
								(size 1.27 1.27)
							)
						)
					)
					(number "19"
						(effects
							(font
								(size 1.27 1.27)
							)
						)
					)
				)
				(pin bidirectional line
					(at 55.88 -21.59 180)
					(length 3.81)
					(name "USB3DN_RXDM1B"
						(effects
							(font
								(size 1.27 1.27)
							)
						)
					)
					(number "20"
						(effects
							(font
								(size 1.27 1.27)
							)
						)
					)
				)
				(pin bidirectional line
					(at 55.88 -24.13 180)
					(length 3.81)
					(name "USB3DN_TXDP1B"
						(effects
							(font
								(size 1.27 1.27)
							)
						)
					)
					(number "16"
						(effects
							(font
								(size 1.27 1.27)
							)
						)
					)
				)
				(pin bidirectional line
					(at 55.88 -26.67 180)
					(length 3.81)
					(name "USB3DN_TXDM1B"
						(effects
							(font
								(size 1.27 1.27)
							)
						)
					)
					(number "17"
						(effects
							(font
								(size 1.27 1.27)
							)
						)
					)
				)
				(pin bidirectional line
					(at 55.88 -29.21 180)
					(length 3.81)
					(name "USB2DN_DP1"
						(effects
							(font
								(size 1.27 1.27)
							)
						)
					)
					(number "5"
						(effects
							(font
								(size 1.27 1.27)
							)
						)
					)
					(alternate "PRT_DIS_P1" passive line)
				)
				(pin bidirectional line
					(at 55.88 -31.75 180)
					(length 3.81)
					(name "USB2DN_DM1"
						(effects
							(font
								(size 1.27 1.27)
							)
						)
					)
					(number "6"
						(effects
							(font
								(size 1.27 1.27)
							)
						)
					)
					(alternate "PRT_DIS_M1" passive line)
				)
				(pin bidirectional line
					(at 55.88 -39.37 180)
					(length 3.81)
					(name "DP2_VBUS_MON"
						(effects
							(font
								(size 1.27 1.27)
							)
						)
					)
					(number "36"
						(effects
							(font
								(size 1.27 1.27)
							)
						)
					)
				)
				(pin bidirectional line
					(at 55.88 -41.91 180)
					(length 3.81)
					(name "DP2_CC1"
						(effects
							(font
								(size 1.27 1.27)
							)
						)
					)
					(number "27"
						(effects
							(font
								(size 1.27 1.27)
							)
						)
					)
				)
				(pin bidirectional line
					(at 55.88 -44.45 180)
					(length 3.81)
					(name "DP2_CC2"
						(effects
							(font
								(size 1.27 1.27)
							)
						)
					)
					(number "28"
						(effects
							(font
								(size 1.27 1.27)
							)
						)
					)
				)
				(pin bidirectional line
					(at 55.88 -46.99 180)
					(length 3.81)
					(name "USB3DN_RXDP2A"
						(effects
							(font
								(size 1.27 1.27)
							)
						)
					)
					(number "34"
						(effects
							(font
								(size 1.27 1.27)
							)
						)
					)
				)
				(pin bidirectional line
					(at 55.88 -49.53 180)
					(length 3.81)
					(name "USB3DN_RXDM2A"
						(effects
							(font
								(size 1.27 1.27)
							)
						)
					)
					(number "35"
						(effects
							(font
								(size 1.27 1.27)
							)
						)
					)
				)
				(pin bidirectional line
					(at 55.88 -52.07 180)
					(length 3.81)
					(name "USB3DN_TXDP2A"
						(effects
							(font
								(size 1.27 1.27)
							)
						)
					)
					(number "31"
						(effects
							(font
								(size 1.27 1.27)
							)
						)
					)
				)
				(pin bidirectional line
					(at 55.88 -54.61 180)
					(length 3.81)
					(name "USB3DN_TXDM2A"
						(effects
							(font
								(size 1.27 1.27)
							)
						)
					)
					(number "32"
						(effects
							(font
								(size 1.27 1.27)
							)
						)
					)
				)
				(pin bidirectional line
					(at 55.88 -57.15 180)
					(length 3.81)
					(name "USB3DN_RXDP2B"
						(effects
							(font
								(size 1.27 1.27)
							)
						)
					)
					(number "40"
						(effects
							(font
								(size 1.27 1.27)
							)
						)
					)
				)
				(pin bidirectional line
					(at 55.88 -59.69 180)
					(length 3.81)
					(name "USB3DN_RXDM2B"
						(effects
							(font
								(size 1.27 1.27)
							)
						)
					)
					(number "41"
						(effects
							(font
								(size 1.27 1.27)
							)
						)
					)
				)
				(pin bidirectional line
					(at 55.88 -62.23 180)
					(length 3.81)
					(name "USB3DN_TXDP2B"
						(effects
							(font
								(size 1.27 1.27)
							)
						)
					)
					(number "37"
						(effects
							(font
								(size 1.27 1.27)
							)
						)
					)
				)
				(pin bidirectional line
					(at 55.88 -64.77 180)
					(length 3.81)
					(name "USB3DN_TXDM2B"
						(effects
							(font
								(size 1.27 1.27)
							)
						)
					)
					(number "38"
						(effects
							(font
								(size 1.27 1.27)
							)
						)
					)
				)
				(pin bidirectional line
					(at 55.88 -67.31 180)
					(length 3.81)
					(name "USB2DN_DP2"
						(effects
							(font
								(size 1.27 1.27)
							)
						)
					)
					(number "29"
						(effects
							(font
								(size 1.27 1.27)
							)
						)
					)
					(alternate "PRT_DIS_P2" passive line)
				)
				(pin bidirectional line
					(at 55.88 -69.85 180)
					(length 3.81)
					(name "USB2DN_DM2"
						(effects
							(font
								(size 1.27 1.27)
							)
						)
					)
					(number "30"
						(effects
							(font
								(size 1.27 1.27)
							)
						)
					)
					(alternate "PRT_DIS_M2" passive line)
				)
				(pin bidirectional line
					(at 55.88 -76.2 180)
					(length 3.81)
					(name "USB3DN_TXDP3"
						(effects
							(font
								(size 1.27 1.27)
							)
						)
					)
					(number "83"
						(effects
							(font
								(size 1.27 1.27)
							)
						)
					)
				)
				(pin bidirectional line
					(at 55.88 -78.74 180)
					(length 3.81)
					(name "USB3DN_TXDM3"
						(effects
							(font
								(size 1.27 1.27)
							)
						)
					)
					(number "84"
						(effects
							(font
								(size 1.27 1.27)
							)
						)
					)
				)
				(pin bidirectional line
					(at 55.88 -81.28 180)
					(length 3.81)
					(name "USB3DN_RXDP3"
						(effects
							(font
								(size 1.27 1.27)
							)
						)
					)
					(number "86"
						(effects
							(font
								(size 1.27 1.27)
							)
						)
					)
				)
				(pin bidirectional line
					(at 55.88 -83.82 180)
					(length 3.81)
					(name "USB3DN_RXDM3"
						(effects
							(font
								(size 1.27 1.27)
							)
						)
					)
					(number "87"
						(effects
							(font
								(size 1.27 1.27)
							)
						)
					)
				)
				(pin bidirectional line
					(at 55.88 -86.36 180)
					(length 3.81)
					(name "USB2DN_DP3"
						(effects
							(font
								(size 1.27 1.27)
							)
						)
					)
					(number "81"
						(effects
							(font
								(size 1.27 1.27)
							)
						)
					)
					(alternate "PRT_DIS_P3" passive line)
				)
				(pin bidirectional line
					(at 55.88 -88.9 180)
					(length 3.81)
					(name "USB2DN_DM3"
						(effects
							(font
								(size 1.27 1.27)
							)
						)
					)
					(number "82"
						(effects
							(font
								(size 1.27 1.27)
							)
						)
					)
					(alternate "PRT_DIS_M3" passive line)
				)
				(pin bidirectional line
					(at 55.88 -96.52 180)
					(length 3.81)
					(name "USB2DN_DP4"
						(effects
							(font
								(size 1.27 1.27)
							)
						)
					)
					(number "14"
						(effects
							(font
								(size 1.27 1.27)
							)
						)
					)
					(alternate "PRT_DIS_P4" passive line)
				)
				(pin bidirectional line
					(at 55.88 -99.06 180)
					(length 3.81)
					(name "USB2DN_DM4"
						(effects
							(font
								(size 1.27 1.27)
							)
						)
					)
					(number "15"
						(effects
							(font
								(size 1.27 1.27)
							)
						)
					)
					(alternate "PRT_DIS_M4" passive line)
				)
				(pin bidirectional line
					(at 55.88 -111.76 180)
					(length 3.81)
					(name "SPI_CLK"
						(effects
							(font
								(size 1.27 1.27)
							)
						)
					)
					(number "68"
						(effects
							(font
								(size 1.27 1.27)
							)
						)
					)
					(alternate "PF21" passive line)
				)
				(pin bidirectional line
					(at 55.88 -114.3 180)
					(length 3.81)
					(name "SPI_CE_N"
						(effects
							(font
								(size 1.27 1.27)
							)
						)
					)
					(number "69"
						(effects
							(font
								(size 1.27 1.27)
							)
						)
					)
					(alternate "CFG_NON_REM" passive line)
					(alternate "PF20" passive line)
				)
				(pin bidirectional line
					(at 55.88 -116.84 180)
					(length 3.81)
					(name "SPI_D0"
						(effects
							(font
								(size 1.27 1.27)
							)
						)
					)
					(number "70"
						(effects
							(font
								(size 1.27 1.27)
							)
						)
					)
					(alternate "CFG_BC_EN" passive line)
					(alternate "PF22" passive line)
				)
				(pin bidirectional line
					(at 55.88 -119.38 180)
					(length 3.81)
					(name "SPI_D1"
						(effects
							(font
								(size 1.27 1.27)
							)
						)
					)
					(number "71"
						(effects
							(font
								(size 1.27 1.27)
							)
						)
					)
					(alternate "PF23" passive line)
				)
				(pin bidirectional line
					(at 55.88 -121.92 180)
					(length 3.81)
					(name "SPI_D2"
						(effects
							(font
								(size 1.27 1.27)
							)
						)
					)
					(number "72"
						(effects
							(font
								(size 1.27 1.27)
							)
						)
					)
					(alternate "PF24" passive line)
				)
				(pin bidirectional line
					(at 55.88 -124.46 180)
					(length 3.81)
					(name "SPI_D3"
						(effects
							(font
								(size 1.27 1.27)
							)
						)
					)
					(number "73"
						(effects
							(font
								(size 1.27 1.27)
							)
						)
					)
					(alternate "PF25" passive line)
				)
			)
		)
	(symbol "antmicroInterfaceIOExpanders:PCAL6408A_VQFN"
			(exclude_from_sim no)
			(in_bom yes)
			(on_board yes)
			(property "Reference" "U"
				(at 35.56 -2.54 0)
				(effects
					(font
						(size 1.27 1.27)
						(thickness 0.15)
					)
					(justify left bottom)
				)
			)
			(property "Value" "PCAL6408A_VQFN"
				(at 35.56 -7.62 0)
				(effects
					(font
						(size 1.27 1.27)
						(thickness 0.15)
					)
					(justify left bottom)
					(hide yes)
				)
			)
			(property "Footprint" "antmicro-footprints:VQFN-16-1EP_3x3mm_P0.5mm_EP1.68x1.68mm"
				(at 35.56 -10.16 0)
				(effects
					(font
						(size 1.27 1.27)
						(thickness 0.15)
					)
					(justify left bottom)
					(hide yes)
				)
			)
			(property "Datasheet" "https://eu.mouser.com/datasheet/2/302/PCAL6408A-3139197.pdf"
				(at 35.56 -12.7 0)
				(effects
					(font
						(size 1.27 1.27)
						(thickness 0.15)
					)
					(justify left bottom)
					(hide yes)
				)
			)
			(property "Description" "I/O Expander, 8 bit, I2C, 1.65-5.5 V, HVQFN, 16 Pins"
				(at 35.56 -22.86 0)
				(effects
					(font
						(size 1.27 1.27)
					)
					(justify left bottom)
					(hide yes)
				)
			)
			(property "MPN" "PCAL6408ABSHP"
				(at 35.56 -5.08 0)
				(effects
					(font
						(size 1.27 1.27)
						(thickness 0.15)
					)
					(justify left bottom)
				)
			)
			(property "Manufacturer" "NXP"
				(at 35.56 -15.24 0)
				(effects
					(font
						(size 1.27 1.27)
						(thickness 0.15)
					)
					(justify left bottom)
					(hide yes)
				)
			)
			(property "Author" "Antmicro"
				(at 35.56 -17.78 0)
				(effects
					(font
						(size 1.27 1.27)
						(thickness 0.15)
					)
					(justify left bottom)
					(hide yes)
				)
			)
			(property "License" "Apache-2.0"
				(at 35.56 -20.32 0)
				(effects
					(font
						(size 1.27 1.27)
						(thickness 0.15)
					)
					(justify left bottom)
					(hide yes)
				)
			)
			(property "ki_keywords" "SMT, INTERFACE, IC, I2C"
				(at 0 0 0)
				(effects
					(font
						(size 1.27 1.27)
					)
					(hide yes)
				)
			)
			(symbol "PCAL6408A_VQFN_1_1"
				(rectangle
					(start 2.54 2.54)
					(end 17.78 -25.4)
					(stroke
						(width 0.254)
						(type default)
					)
					(fill
						(type background)
					)
				)
				(pin power_in line
					(at 0 0 0)
					(length 2.54)
					(name "VDD_{(P)}"
						(effects
							(font
								(size 1.27 1.27)
							)
						)
					)
					(number "14"
						(effects
							(font
								(size 1.27 1.27)
							)
						)
					)
				)
				(pin power_in line
					(at 0 -2.54 0)
					(length 2.54)
					(name "VDD_{(I2C)}"
						(effects
							(font
								(size 1.27 1.27)
							)
						)
					)
					(number "15"
						(effects
							(font
								(size 1.27 1.27)
							)
						)
					)
				)
				(pin output line
					(at 0 -6.35 0)
					(length 2.54)
					(name "~{INT}"
						(effects
							(font
								(size 1.27 1.27)
							)
						)
					)
					(number "11"
						(effects
							(font
								(size 1.27 1.27)
							)
						)
					)
				)
				(pin bidirectional line
					(at 0 -10.16 0)
					(length 2.54)
					(name "SDA"
						(effects
							(font
								(size 1.27 1.27)
							)
						)
					)
					(number "13"
						(effects
							(font
								(size 1.27 1.27)
							)
						)
					)
				)
				(pin input line
					(at 0 -12.7 0)
					(length 2.54)
					(name "SCL"
						(effects
							(font
								(size 1.27 1.27)
							)
						)
					)
					(number "12"
						(effects
							(font
								(size 1.27 1.27)
							)
						)
					)
				)
				(pin input line
					(at 0 -16.51 0)
					(length 2.54)
					(name "~{RESET}"
						(effects
							(font
								(size 1.27 1.27)
							)
						)
					)
					(number "1"
						(effects
							(font
								(size 1.27 1.27)
							)
						)
					)
				)
				(pin passive line
					(at 0 -20.32 0)
					(length 2.54)
					(name "ADDR"
						(effects
							(font
								(size 1.27 1.27)
							)
						)
					)
					(number "16"
						(effects
							(font
								(size 1.27 1.27)
							)
						)
					)
				)
				(pin bidirectional line
					(at 20.32 0 180)
					(length 2.54)
					(name "P0"
						(effects
							(font
								(size 1.27 1.27)
							)
						)
					)
					(number "2"
						(effects
							(font
								(size 1.27 1.27)
							)
						)
					)
				)
				(pin bidirectional line
					(at 20.32 -2.54 180)
					(length 2.54)
					(name "P1"
						(effects
							(font
								(size 1.27 1.27)
							)
						)
					)
					(number "3"
						(effects
							(font
								(size 1.27 1.27)
							)
						)
					)
				)
				(pin bidirectional line
					(at 20.32 -5.08 180)
					(length 2.54)
					(name "P2"
						(effects
							(font
								(size 1.27 1.27)
							)
						)
					)
					(number "4"
						(effects
							(font
								(size 1.27 1.27)
							)
						)
					)
				)
				(pin bidirectional line
					(at 20.32 -7.62 180)
					(length 2.54)
					(name "P3"
						(effects
							(font
								(size 1.27 1.27)
							)
						)
					)
					(number "5"
						(effects
							(font
								(size 1.27 1.27)
							)
						)
					)
				)
				(pin bidirectional line
					(at 20.32 -10.16 180)
					(length 2.54)
					(name "P4"
						(effects
							(font
								(size 1.27 1.27)
							)
						)
					)
					(number "7"
						(effects
							(font
								(size 1.27 1.27)
							)
						)
					)
				)
				(pin bidirectional line
					(at 20.32 -12.7 180)
					(length 2.54)
					(name "P5"
						(effects
							(font
								(size 1.27 1.27)
							)
						)
					)
					(number "8"
						(effects
							(font
								(size 1.27 1.27)
							)
						)
					)
				)
				(pin bidirectional line
					(at 20.32 -15.24 180)
					(length 2.54)
					(name "P6"
						(effects
							(font
								(size 1.27 1.27)
							)
						)
					)
					(number "9"
						(effects
							(font
								(size 1.27 1.27)
							)
						)
					)
				)
				(pin bidirectional line
					(at 20.32 -17.78 180)
					(length 2.54)
					(name "P7"
						(effects
							(font
								(size 1.27 1.27)
							)
						)
					)
					(number "10"
						(effects
							(font
								(size 1.27 1.27)
							)
						)
					)
				)
				(pin power_in line
					(at 20.32 -20.32 180)
					(length 2.54)
					(name "EP"
						(effects
							(font
								(size 1.27 1.27)
							)
						)
					)
					(number "17"
						(effects
							(font
								(size 1.27 1.27)
							)
						)
					)
				)
				(pin power_in line
					(at 20.32 -22.86 180)
					(length 2.54)
					(name "V_{ss}"
						(effects
							(font
								(size 1.27 1.27)
							)
						)
					)
					(number "6"
						(effects
							(font
								(size 1.27 1.27)
							)
						)
					)
				)
			)
		)
	(symbol "antmicroLEDIndicationDiscrete:LED_G_0603_LTST-C190GKT"
			(pin_numbers
				(hide yes)
			)
			(pin_names
				(hide yes)
			)
			(exclude_from_sim no)
			(in_bom yes)
			(on_board yes)
			(property "Reference" "D"
				(at 22.86 -2.54 0)
				(effects
					(font
						(size 1.27 1.27)
						(thickness 0.15)
					)
					(justify left bottom)
				)
			)
			(property "Value" "LED_G_0603_LTST-C190GKT"
				(at 22.86 -7.62 0)
				(effects
					(font
						(size 1.27 1.27)
						(thickness 0.15)
					)
					(justify left bottom)
					(hide yes)
				)
			)
			(property "Footprint" "antmicro-footprints:LED_0603_1608Metric_G"
				(at 22.86 -10.16 0)
				(effects
					(font
						(size 1.27 1.27)
						(thickness 0.15)
					)
					(justify left bottom)
					(hide yes)
				)
			)
			(property "Datasheet" "https://media.digikey.com/pdf/Data%20Sheets/Lite-On%20PDFs/LTST-C190GKT.pdf"
				(at 22.86 -12.7 0)
				(effects
					(font
						(size 1.27 1.27)
						(thickness 0.15)
					)
					(justify left bottom)
					(hide yes)
				)
			)
			(property "Description" "LED, Green, SMD, 0603, 20 mA, 2.1 V, 569 nm"
				(at 22.86 -25.4 0)
				(effects
					(font
						(size 1.27 1.27)
					)
					(justify left bottom)
					(hide yes)
				)
			)
			(property "MPN" "LTST-C190GKT"
				(at 22.86 -15.24 0)
				(effects
					(font
						(size 1.27 1.27)
						(thickness 0.15)
					)
					(justify left bottom)
					(hide yes)
				)
			)
			(property "Manufacturer" "Lite-On"
				(at 22.86 -17.78 0)
				(effects
					(font
						(size 1.27 1.27)
						(thickness 0.15)
					)
					(justify left bottom)
					(hide yes)
				)
			)
			(property "Color" "Green"
				(at 22.86 -5.08 0)
				(effects
					(font
						(size 1.27 1.27)
					)
					(justify left bottom)
				)
			)
			(property "Author" "Antmicro"
				(at 22.86 -20.32 0)
				(effects
					(font
						(size 1.27 1.27)
						(thickness 0.15)
					)
					(justify left bottom)
					(hide yes)
				)
			)
			(property "License" "Apache-2.0"
				(at 22.86 -22.86 0)
				(effects
					(font
						(size 1.27 1.27)
						(thickness 0.15)
					)
					(justify left bottom)
					(hide yes)
				)
			)
			(property "ki_keywords" "SMT, DIODE, SEMICONDUCTOR, LED"
				(at 0 0 0)
				(effects
					(font
						(size 1.27 1.27)
					)
					(hide yes)
				)
			)
			(symbol "LED_G_0603_LTST-C190GKT_0_1"
				(polyline
					(pts
						(xy 1.905 0) (xy 0.635 0)
					)
					(stroke
						(width 0)
						(type default)
					)
					(fill
						(type none)
					)
				)
				(polyline
					(pts
						(xy 4.445 0) (xy 3.175 0)
					)
					(stroke
						(width 0)
						(type default)
					)
					(fill
						(type none)
					)
				)
			)
			(symbol "LED_G_0603_LTST-C190GKT_1_1"
				(polyline
					(pts
						(xy 1.143 2.286) (xy 1.143 1.778) (xy 1.143 2.286) (xy 1.651 2.286) (xy 1.143 2.286) (xy 2.159 1.27)
					)
					(stroke
						(width 0.254)
						(type default)
					)
					(fill
						(type none)
					)
				)
				(polyline
					(pts
						(xy 1.778 1.016) (xy 1.778 -1.016)
					)
					(stroke
						(width 0.254)
						(type default)
					)
					(fill
						(type none)
					)
				)
				(polyline
					(pts
						(xy 2.159 2.54) (xy 2.159 2.032) (xy 2.159 2.54) (xy 2.667 2.54) (xy 2.159 2.54) (xy 3.048 1.651)
					)
					(stroke
						(width 0.254)
						(type default)
					)
					(fill
						(type none)
					)
				)
				(polyline
					(pts
						(xy 3.302 1.016) (xy 3.302 -1.016) (xy 1.778 0) (xy 3.302 1.016)
					)
					(stroke
						(width 0.254)
						(type default)
					)
					(fill
						(type outline)
					)
				)
				(pin passive line
					(at 0 0 0)
					(length 0.635)
					(name "C"
						(effects
							(font
								(size 1.27 1.27)
							)
						)
					)
					(number "1"
						(effects
							(font
								(size 1.27 1.27)
							)
						)
					)
				)
				(pin passive line
					(at 5.08 0 180)
					(length 0.635)
					(name "A"
						(effects
							(font
								(size 1.27 1.27)
							)
						)
					)
					(number "2"
						(effects
							(font
								(size 1.27 1.27)
							)
						)
					)
				)
			)
		)
	(symbol "antmicroLEDIndicationDiscrete:LED_Y_0603_LTST-C191KSKT"
			(pin_numbers
				(hide yes)
			)
			(pin_names
				(hide yes)
			)
			(exclude_from_sim no)
			(in_bom yes)
			(on_board yes)
			(property "Reference" "D"
				(at 22.86 -2.54 0)
				(effects
					(font
						(size 1.27 1.27)
						(thickness 0.15)
					)
					(justify left bottom)
				)
			)
			(property "Value" "LED_Y_0603_LTST-C191KSKT"
				(at 22.86 -7.62 0)
				(effects
					(font
						(size 1.27 1.27)
						(thickness 0.15)
					)
					(justify left bottom)
					(hide yes)
				)
			)
			(property "Footprint" "antmicro-footprints:LED_0603_1608Metric_Y"
				(at 22.86 -10.16 0)
				(effects
					(font
						(size 1.27 1.27)
						(thickness 0.15)
					)
					(justify left bottom)
					(hide yes)
				)
			)
			(property "Datasheet" "https://optoelectronics.liteon.com/upload/download/DS22-2000-224/LTST-C191KSKT.PDF"
				(at 22.86 -12.7 0)
				(effects
					(font
						(size 1.27 1.27)
						(thickness 0.15)
					)
					(justify left bottom)
					(hide yes)
				)
			)
			(property "Description" "LED, Yellow, SMD, 0603, 30 mA, 2.1 V, 588 nm"
				(at 22.86 -25.4 0)
				(effects
					(font
						(size 1.27 1.27)
					)
					(justify left bottom)
					(hide yes)
				)
			)
			(property "MPN" "LTST-C191KSKT"
				(at 22.86 -15.24 0)
				(effects
					(font
						(size 1.27 1.27)
						(thickness 0.15)
					)
					(justify left bottom)
					(hide yes)
				)
			)
			(property "Manufacturer" "Lite-On"
				(at 22.86 -17.78 0)
				(effects
					(font
						(size 1.27 1.27)
						(thickness 0.15)
					)
					(justify left bottom)
					(hide yes)
				)
			)
			(property "Color" "Yellow"
				(at 22.86 -5.08 0)
				(effects
					(font
						(size 1.27 1.27)
					)
					(justify left bottom)
				)
			)
			(property "Author" "Antmicro"
				(at 22.86 -20.32 0)
				(effects
					(font
						(size 1.27 1.27)
						(thickness 0.15)
					)
					(justify left bottom)
					(hide yes)
				)
			)
			(property "License" "Apache-2.0"
				(at 22.86 -22.86 0)
				(effects
					(font
						(size 1.27 1.27)
						(thickness 0.15)
					)
					(justify left bottom)
					(hide yes)
				)
			)
			(property "ki_keywords" "SMT, DIODE, SEMICONDUCTOR, LED"
				(at 0 0 0)
				(effects
					(font
						(size 1.27 1.27)
					)
					(hide yes)
				)
			)
			(symbol "LED_Y_0603_LTST-C191KSKT_0_1"
				(polyline
					(pts
						(xy 1.905 0) (xy 0.635 0)
					)
					(stroke
						(width 0)
						(type default)
					)
					(fill
						(type none)
					)
				)
				(polyline
					(pts
						(xy 4.445 0) (xy 3.175 0)
					)
					(stroke
						(width 0)
						(type default)
					)
					(fill
						(type none)
					)
				)
			)
			(symbol "LED_Y_0603_LTST-C191KSKT_1_1"
				(polyline
					(pts
						(xy 1.143 2.286) (xy 1.143 1.778) (xy 1.143 2.286) (xy 1.651 2.286) (xy 1.143 2.286) (xy 2.159 1.27)
					)
					(stroke
						(width 0.254)
						(type default)
					)
					(fill
						(type none)
					)
				)
				(polyline
					(pts
						(xy 1.778 1.016) (xy 1.778 -1.016)
					)
					(stroke
						(width 0.254)
						(type default)
					)
					(fill
						(type none)
					)
				)
				(polyline
					(pts
						(xy 2.159 2.54) (xy 2.159 2.032) (xy 2.159 2.54) (xy 2.667 2.54) (xy 2.159 2.54) (xy 3.048 1.651)
					)
					(stroke
						(width 0.254)
						(type default)
					)
					(fill
						(type none)
					)
				)
				(polyline
					(pts
						(xy 3.302 1.016) (xy 3.302 -1.016) (xy 1.778 0) (xy 3.302 1.016)
					)
					(stroke
						(width 0.254)
						(type default)
					)
					(fill
						(type outline)
					)
				)
				(pin passive line
					(at 0 0 0)
					(length 0.635)
					(name "C"
						(effects
							(font
								(size 1.27 1.27)
							)
						)
					)
					(number "1"
						(effects
							(font
								(size 1.27 1.27)
							)
						)
					)
				)
				(pin passive line
					(at 5.08 0 180)
					(length 0.635)
					(name "A"
						(effects
							(font
								(size 1.27 1.27)
							)
						)
					)
					(number "2"
						(effects
							(font
								(size 1.27 1.27)
							)
						)
					)
				)
			)
		)
	(symbol "antmicroLogicBuffersDriversReceiversTransceivers:SN74LVC2G07DCKR"
			(exclude_from_sim no)
			(in_bom yes)
			(on_board yes)
			(property "Reference" "U"
				(at 33.02 -2.54 0)
				(effects
					(font
						(size 1.27 1.27)
						(thickness 0.15)
					)
					(justify left bottom)
				)
			)
			(property "Value" "SN74LVC2G07DCKR"
				(at 33.02 -7.62 0)
				(effects
					(font
						(size 1.27 1.27)
						(thickness 0.15)
					)
					(justify left bottom)
					(hide yes)
				)
			)
			(property "Footprint" "antmicro-footprints:SC-70-6"
				(at 33.02 -10.16 0)
				(effects
					(font
						(size 1.27 1.27)
						(thickness 0.15)
					)
					(justify left bottom)
					(hide yes)
				)
			)
			(property "Datasheet" "https://www.ti.com/lit/gpn/sn74lvc2g07"
				(at 33.02 -12.7 0)
				(effects
					(font
						(size 1.27 1.27)
						(thickness 0.15)
					)
					(justify left bottom)
					(hide yes)
				)
			)
			(property "Description" "Buffer / Line Driver, SN74LVC2G07DCKR, 1.65 V to 5.5 V, SC-70-5"
				(at 33.02 -22.86 0)
				(effects
					(font
						(size 1.27 1.27)
					)
					(justify left bottom)
					(hide yes)
				)
			)
			(property "MPN" "SN74LVC2G07DCKR"
				(at 33.02 -5.08 0)
				(effects
					(font
						(size 1.27 1.27)
						(thickness 0.15)
					)
					(justify left bottom)
				)
			)
			(property "Manufacturer" "Texas Instruments"
				(at 33.02 -15.24 0)
				(effects
					(font
						(size 1.27 1.27)
						(thickness 0.15)
					)
					(justify left bottom)
					(hide yes)
				)
			)
			(property "Author" "Antmicro"
				(at 33.02 -17.78 0)
				(effects
					(font
						(size 1.27 1.27)
						(thickness 0.15)
					)
					(justify left bottom)
					(hide yes)
				)
			)
			(property "License" "Apache-2.0"
				(at 33.02 -20.32 0)
				(effects
					(font
						(size 1.27 1.27)
						(thickness 0.15)
					)
					(justify left bottom)
					(hide yes)
				)
			)
			(property "ki_keywords" "SMT, LOGIC, IC, BUFFER, TRANSCEIVER, DRIVER"
				(at 0 0 0)
				(effects
					(font
						(size 1.27 1.27)
					)
					(hide yes)
				)
			)
			(symbol "SN74LVC2G07DCKR_1_1"
				(rectangle
					(start 2.54 2.54)
					(end 16.51 -11.43)
					(stroke
						(width 0.254)
						(type default)
					)
					(fill
						(type background)
					)
				)
				(polyline
					(pts
						(xy 6.985 -2.667) (xy 7.747 -2.667)
					)
					(stroke
						(width 0.254)
						(type default)
					)
					(fill
						(type background)
					)
				)
				(polyline
					(pts
						(xy 6.985 -6.477) (xy 7.747 -6.477)
					)
					(stroke
						(width 0.254)
						(type default)
					)
					(fill
						(type background)
					)
				)
				(polyline
					(pts
						(xy 7.874 -1.143) (xy 7.874 -4.318) (xy 11.176 -2.667) (xy 7.874 -1.143)
					)
					(stroke
						(width 0.254)
						(type default)
					)
					(fill
						(type background)
					)
				)
				(polyline
					(pts
						(xy 7.874 -4.826) (xy 7.874 -8.001) (xy 11.176 -6.35) (xy 7.874 -4.826)
					)
					(stroke
						(width 0.254)
						(type default)
					)
					(fill
						(type background)
					)
				)
				(polyline
					(pts
						(xy 8.509 -3.175) (xy 9.271 -3.175)
					)
					(stroke
						(width 0.254)
						(type default)
					)
					(fill
						(type background)
					)
				)
				(polyline
					(pts
						(xy 8.509 -6.858) (xy 9.271 -6.858)
					)
					(stroke
						(width 0.254)
						(type default)
					)
					(fill
						(type background)
					)
				)
				(polyline
					(pts
						(xy 8.89 -2.286) (xy 8.509 -2.667) (xy 8.89 -3.048) (xy 9.271 -2.667) (xy 8.89 -2.286)
					)
					(stroke
						(width 0.254)
						(type default)
					)
					(fill
						(type background)
					)
				)
				(polyline
					(pts
						(xy 8.89 -5.969) (xy 8.509 -6.35) (xy 8.89 -6.731) (xy 9.271 -6.35) (xy 8.89 -5.969)
					)
					(stroke
						(width 0.254)
						(type default)
					)
					(fill
						(type background)
					)
				)
				(polyline
					(pts
						(xy 11.176 -2.667) (xy 11.938 -2.667)
					)
					(stroke
						(width 0.254)
						(type default)
					)
					(fill
						(type background)
					)
				)
				(polyline
					(pts
						(xy 11.176 -6.35) (xy 11.938 -6.35)
					)
					(stroke
						(width 0.254)
						(type default)
					)
					(fill
						(type background)
					)
				)
				(pin power_in line
					(at 0 0 0)
					(length 2.54)
					(name "V_{CC}"
						(effects
							(font
								(size 1.27 1.27)
							)
						)
					)
					(number "5"
						(effects
							(font
								(size 1.27 1.27)
							)
						)
					)
				)
				(pin input line
					(at 0 -2.54 0)
					(length 2.54)
					(name "1A"
						(effects
							(font
								(size 1.27 1.27)
							)
						)
					)
					(number "1"
						(effects
							(font
								(size 1.27 1.27)
							)
						)
					)
				)
				(pin input line
					(at 0 -6.35 0)
					(length 2.54)
					(name "2A"
						(effects
							(font
								(size 1.27 1.27)
							)
						)
					)
					(number "3"
						(effects
							(font
								(size 1.27 1.27)
							)
						)
					)
				)
				(pin open_collector line
					(at 19.05 -2.54 180)
					(length 2.54)
					(name "1Y"
						(effects
							(font
								(size 1.27 1.27)
							)
						)
					)
					(number "6"
						(effects
							(font
								(size 1.27 1.27)
							)
						)
					)
				)
				(pin open_collector line
					(at 19.05 -6.35 180)
					(length 2.54)
					(name "2Y"
						(effects
							(font
								(size 1.27 1.27)
							)
						)
					)
					(number "4"
						(effects
							(font
								(size 1.27 1.27)
							)
						)
					)
				)
				(pin power_in line
					(at 19.05 -8.89 180)
					(length 2.54)
					(name "GND"
						(effects
							(font
								(size 1.27 1.27)
							)
						)
					)
					(number "2"
						(effects
							(font
								(size 1.27 1.27)
							)
						)
					)
				)
			)
		)
	(symbol "antmicroLogicSignalSwitchesMultiplexersDecoders:PI4MSD5V9548AZDEX"
			(exclude_from_sim no)
			(in_bom yes)
			(on_board yes)
			(property "Reference" "U"
				(at 35.56 -2.54 0)
				(effects
					(font
						(size 1.27 1.27)
						(thickness 0.15)
					)
					(justify left bottom)
				)
			)
			(property "Value" "PI4MSD5V9548AZDEX"
				(at 35.56 -5.08 0)
				(effects
					(font
						(size 1.27 1.27)
						(thickness 0.15)
					)
					(justify left bottom)
					(hide yes)
				)
			)
			(property "Footprint" "antmicro-footprints:VQFN-24-1EP_3.8x3.8x1.0mm_P0.5mm"
				(at 35.56 -7.62 0)
				(effects
					(font
						(size 1.27 1.27)
						(thickness 0.15)
					)
					(justify left bottom)
					(hide yes)
				)
			)
			(property "Datasheet" "https://www.mouser.com/datasheet/2/115/DIOD_S_A0003139195_1-2542233.pdf"
				(at 35.56 -10.16 0)
				(effects
					(font
						(size 1.27 1.27)
						(thickness 0.15)
					)
					(justify left bottom)
					(hide yes)
				)
			)
			(property "Description" "Logic signal switch/multiplexer/decoder"
				(at 35.56 -22.86 0)
				(effects
					(font
						(size 1.27 1.27)
					)
					(justify left bottom)
					(hide yes)
				)
			)
			(property "Manufacturer" "Diodes Incorporated"
				(at 35.56 -12.7 0)
				(effects
					(font
						(size 1.27 1.27)
						(thickness 0.15)
					)
					(justify left bottom)
					(hide yes)
				)
			)
			(property "MPN" "PI4MSD5V9548AZDEX"
				(at 35.56 -15.24 0)
				(effects
					(font
						(size 1.27 1.27)
						(thickness 0.15)
					)
					(justify left bottom)
				)
			)
			(property "Author" "Antmicro"
				(at 35.56 -17.78 0)
				(effects
					(font
						(size 1.27 1.27)
						(thickness 0.15)
					)
					(justify left bottom)
					(hide yes)
				)
			)
			(property "License" "Apache-2.0"
				(at 35.56 -20.32 0)
				(effects
					(font
						(size 1.27 1.27)
						(thickness 0.15)
					)
					(justify left bottom)
					(hide yes)
				)
			)
			(property "ki_keywords" "SMT, MUX, IC, I2C"
				(at 0 0 0)
				(effects
					(font
						(size 1.27 1.27)
					)
					(hide yes)
				)
			)
			(symbol "PI4MSD5V9548AZDEX_1_1"
				(rectangle
					(start 17.78 -58.42)
					(end 2.54 2.54)
					(stroke
						(width 0.254)
						(type default)
					)
					(fill
						(type background)
					)
				)
				(pin power_in line
					(at 0 0 0)
					(length 2.54)
					(name "VCC"
						(effects
							(font
								(size 1.27 1.27)
							)
						)
					)
					(number "21"
						(effects
							(font
								(size 1.27 1.27)
							)
						)
					)
				)
				(pin bidirectional line
					(at 0 -12.7 0)
					(length 2.54)
					(name "SDA"
						(effects
							(font
								(size 1.27 1.27)
							)
						)
					)
					(number "20"
						(effects
							(font
								(size 1.27 1.27)
							)
						)
					)
				)
				(pin bidirectional line
					(at 0 -15.24 0)
					(length 2.54)
					(name "SCL"
						(effects
							(font
								(size 1.27 1.27)
							)
						)
					)
					(number "19"
						(effects
							(font
								(size 1.27 1.27)
							)
						)
					)
				)
				(pin input line
					(at 0 -38.1 0)
					(length 2.54)
					(name "~{RESET}"
						(effects
							(font
								(size 1.27 1.27)
							)
						)
					)
					(number "24"
						(effects
							(font
								(size 1.27 1.27)
							)
						)
					)
				)
				(pin input line
					(at 0 -43.18 0)
					(length 2.54)
					(name "A0"
						(effects
							(font
								(size 1.27 1.27)
							)
						)
					)
					(number "22"
						(effects
							(font
								(size 1.27 1.27)
							)
						)
					)
				)
				(pin input line
					(at 0 -45.72 0)
					(length 2.54)
					(name "A1"
						(effects
							(font
								(size 1.27 1.27)
							)
						)
					)
					(number "23"
						(effects
							(font
								(size 1.27 1.27)
							)
						)
					)
				)
				(pin input line
					(at 0 -48.26 0)
					(length 2.54)
					(name "A2"
						(effects
							(font
								(size 1.27 1.27)
							)
						)
					)
					(number "18"
						(effects
							(font
								(size 1.27 1.27)
							)
						)
					)
				)
				(pin power_in line
					(at 0 -53.34 0)
					(length 2.54)
					(name "EP"
						(effects
							(font
								(size 1.27 1.27)
							)
						)
					)
					(number "25"
						(effects
							(font
								(size 1.27 1.27)
							)
						)
					)
				)
				(pin power_in line
					(at 0 -55.88 0)
					(length 2.54)
					(name "GND"
						(effects
							(font
								(size 1.27 1.27)
							)
						)
					)
					(number "9"
						(effects
							(font
								(size 1.27 1.27)
							)
						)
					)
				)
				(pin bidirectional line
					(at 20.32 0 180)
					(length 2.54)
					(name "SD0"
						(effects
							(font
								(size 1.27 1.27)
							)
						)
					)
					(number "1"
						(effects
							(font
								(size 1.27 1.27)
							)
						)
					)
				)
				(pin bidirectional line
					(at 20.32 -2.54 180)
					(length 2.54)
					(name "SC0"
						(effects
							(font
								(size 1.27 1.27)
							)
						)
					)
					(number "2"
						(effects
							(font
								(size 1.27 1.27)
							)
						)
					)
				)
				(pin bidirectional line
					(at 20.32 -7.62 180)
					(length 2.54)
					(name "SD1"
						(effects
							(font
								(size 1.27 1.27)
							)
						)
					)
					(number "3"
						(effects
							(font
								(size 1.27 1.27)
							)
						)
					)
				)
				(pin bidirectional line
					(at 20.32 -10.16 180)
					(length 2.54)
					(name "SC1"
						(effects
							(font
								(size 1.27 1.27)
							)
						)
					)
					(number "4"
						(effects
							(font
								(size 1.27 1.27)
							)
						)
					)
				)
				(pin bidirectional line
					(at 20.32 -15.24 180)
					(length 2.54)
					(name "SD2"
						(effects
							(font
								(size 1.27 1.27)
							)
						)
					)
					(number "5"
						(effects
							(font
								(size 1.27 1.27)
							)
						)
					)
				)
				(pin bidirectional line
					(at 20.32 -17.78 180)
					(length 2.54)
					(name "SC2"
						(effects
							(font
								(size 1.27 1.27)
							)
						)
					)
					(number "6"
						(effects
							(font
								(size 1.27 1.27)
							)
						)
					)
				)
				(pin bidirectional line
					(at 20.32 -22.86 180)
					(length 2.54)
					(name "SD3"
						(effects
							(font
								(size 1.27 1.27)
							)
						)
					)
					(number "7"
						(effects
							(font
								(size 1.27 1.27)
							)
						)
					)
				)
				(pin bidirectional line
					(at 20.32 -25.4 180)
					(length 2.54)
					(name "SC3"
						(effects
							(font
								(size 1.27 1.27)
							)
						)
					)
					(number "8"
						(effects
							(font
								(size 1.27 1.27)
							)
						)
					)
				)
				(pin bidirectional line
					(at 20.32 -30.48 180)
					(length 2.54)
					(name "SD4"
						(effects
							(font
								(size 1.27 1.27)
							)
						)
					)
					(number "10"
						(effects
							(font
								(size 1.27 1.27)
							)
						)
					)
				)
				(pin bidirectional line
					(at 20.32 -33.02 180)
					(length 2.54)
					(name "SC4"
						(effects
							(font
								(size 1.27 1.27)
							)
						)
					)
					(number "11"
						(effects
							(font
								(size 1.27 1.27)
							)
						)
					)
				)
				(pin bidirectional line
					(at 20.32 -38.1 180)
					(length 2.54)
					(name "SD5"
						(effects
							(font
								(size 1.27 1.27)
							)
						)
					)
					(number "12"
						(effects
							(font
								(size 1.27 1.27)
							)
						)
					)
				)
				(pin bidirectional line
					(at 20.32 -40.64 180)
					(length 2.54)
					(name "SC5"
						(effects
							(font
								(size 1.27 1.27)
							)
						)
					)
					(number "13"
						(effects
							(font
								(size 1.27 1.27)
							)
						)
					)
				)
				(pin bidirectional line
					(at 20.32 -45.72 180)
					(length 2.54)
					(name "SD6"
						(effects
							(font
								(size 1.27 1.27)
							)
						)
					)
					(number "14"
						(effects
							(font
								(size 1.27 1.27)
							)
						)
					)
				)
				(pin bidirectional line
					(at 20.32 -48.26 180)
					(length 2.54)
					(name "SC6"
						(effects
							(font
								(size 1.27 1.27)
							)
						)
					)
					(number "15"
						(effects
							(font
								(size 1.27 1.27)
							)
						)
					)
				)
				(pin bidirectional line
					(at 20.32 -53.34 180)
					(length 2.54)
					(name "SD7"
						(effects
							(font
								(size 1.27 1.27)
							)
						)
					)
					(number "16"
						(effects
							(font
								(size 1.27 1.27)
							)
						)
					)
				)
				(pin bidirectional line
					(at 20.32 -55.88 180)
					(length 2.54)
					(name "SC7"
						(effects
							(font
								(size 1.27 1.27)
							)
						)
					)
					(number "17"
						(effects
							(font
								(size 1.27 1.27)
							)
						)
					)
				)
			)
		)
	(symbol "antmicroLogicTranslatorsLevelShifters:NTS0102_XSON"
			(exclude_from_sim no)
			(in_bom yes)
			(on_board yes)
			(property "Reference" "U"
				(at 35.56 -2.54 0)
				(effects
					(font
						(size 1.27 1.27)
						(thickness 0.15)
					)
					(justify left bottom)
				)
			)
			(property "Value" "NTS0102_XSON"
				(at 35.56 -7.62 0)
				(effects
					(font
						(size 1.27 1.27)
						(thickness 0.15)
					)
					(justify left bottom)
					(hide yes)
				)
			)
			(property "Footprint" "antmicro-footprints:XSON-8_1x1.95mm_P0.5mm"
				(at 35.56 -10.16 0)
				(effects
					(font
						(size 1.27 1.27)
						(thickness 0.15)
					)
					(justify left bottom)
					(hide yes)
				)
			)
			(property "Datasheet" "http://www.farnell.com/datasheets/1760723.pdf"
				(at 35.56 -12.7 0)
				(effects
					(font
						(size 1.27 1.27)
						(thickness 0.15)
					)
					(justify left bottom)
					(hide yes)
				)
			)
			(property "Description" "Transceiver, 1.65 V to 3.6 V, XSON-8"
				(at 35.56 -22.86 0)
				(effects
					(font
						(size 1.27 1.27)
					)
					(justify left bottom)
					(hide yes)
				)
			)
			(property "MPN" "NTS0102GT"
				(at 35.56 -5.08 0)
				(effects
					(font
						(size 1.27 1.27)
						(thickness 0.15)
					)
					(justify left bottom)
				)
			)
			(property "Manufacturer" "NXP"
				(at 35.56 -15.24 0)
				(effects
					(font
						(size 1.27 1.27)
						(thickness 0.15)
					)
					(justify left bottom)
					(hide yes)
				)
			)
			(property "Author" "Antmicro"
				(at 35.56 -17.78 0)
				(effects
					(font
						(size 1.27 1.27)
						(thickness 0.15)
					)
					(justify left bottom)
					(hide yes)
				)
			)
			(property "License" "Apache-2.0"
				(at 35.56 -20.32 0)
				(effects
					(font
						(size 1.27 1.27)
						(thickness 0.15)
					)
					(justify left bottom)
					(hide yes)
				)
			)
			(property "ki_keywords" "SMT, LEVEL-SHIFTER, IC, LOGIC"
				(at 0 0 0)
				(effects
					(font
						(size 1.27 1.27)
					)
					(hide yes)
				)
			)
			(symbol "NTS0102_XSON_1_1"
				(rectangle
					(start 2.54 2.54)
					(end 17.78 -10.16)
					(stroke
						(width 0.254)
						(type default)
					)
					(fill
						(type background)
					)
				)
				(pin power_in line
					(at 0 0 0)
					(length 2.54)
					(name "VCC_{A}"
						(effects
							(font
								(size 1.27 1.27)
							)
						)
					)
					(number "3"
						(effects
							(font
								(size 1.27 1.27)
							)
						)
					)
				)
				(pin bidirectional line
					(at 0 -2.54 0)
					(length 2.54)
					(name "A_{1}"
						(effects
							(font
								(size 1.27 1.27)
							)
						)
					)
					(number "5"
						(effects
							(font
								(size 1.27 1.27)
							)
						)
					)
				)
				(pin bidirectional line
					(at 0 -5.08 0)
					(length 2.54)
					(name "A_{2}"
						(effects
							(font
								(size 1.27 1.27)
							)
						)
					)
					(number "4"
						(effects
							(font
								(size 1.27 1.27)
							)
						)
					)
				)
				(pin input line
					(at 0 -7.62 0)
					(length 2.54)
					(name "OE"
						(effects
							(font
								(size 1.27 1.27)
							)
						)
					)
					(number "6"
						(effects
							(font
								(size 1.27 1.27)
							)
						)
					)
				)
				(pin power_in line
					(at 20.32 0 180)
					(length 2.54)
					(name "VCC_{B}"
						(effects
							(font
								(size 1.27 1.27)
							)
						)
					)
					(number "7"
						(effects
							(font
								(size 1.27 1.27)
							)
						)
					)
				)
				(pin bidirectional line
					(at 20.32 -2.54 180)
					(length 2.54)
					(name "B_{1}"
						(effects
							(font
								(size 1.27 1.27)
							)
						)
					)
					(number "8"
						(effects
							(font
								(size 1.27 1.27)
							)
						)
					)
				)
				(pin bidirectional line
					(at 20.32 -5.08 180)
					(length 2.54)
					(name "B_{2}"
						(effects
							(font
								(size 1.27 1.27)
							)
						)
					)
					(number "1"
						(effects
							(font
								(size 1.27 1.27)
							)
						)
					)
				)
				(pin power_in line
					(at 20.32 -7.62 180)
					(length 2.54)
					(name "GND"
						(effects
							(font
								(size 1.27 1.27)
							)
						)
					)
					(number "2"
						(effects
							(font
								(size 1.27 1.27)
							)
						)
					)
				)
			)
		)
	(symbol "antmicroLogicTranslatorsLevelShifters:NTS0104_DHVQFN"
			(exclude_from_sim no)
			(in_bom yes)
			(on_board yes)
			(property "Reference" "U"
				(at 35.56 -2.54 0)
				(effects
					(font
						(size 1.27 1.27)
						(thickness 0.15)
					)
					(justify left bottom)
				)
			)
			(property "Value" "NTS0104_DHVQFN"
				(at 35.56 -7.62 0)
				(effects
					(font
						(size 1.27 1.27)
						(thickness 0.15)
					)
					(justify left bottom)
					(hide yes)
				)
			)
			(property "Footprint" "antmicro-footprints:DHVQFN-14-1EP_2.5x3mm"
				(at 35.56 -10.16 0)
				(effects
					(font
						(size 1.27 1.27)
						(thickness 0.15)
					)
					(justify left bottom)
					(hide yes)
				)
			)
			(property "Datasheet" "https://www.nxp.com/docs/en/data-sheet/NTS0104.pdf"
				(at 35.56 -12.7 0)
				(effects
					(font
						(size 1.27 1.27)
						(thickness 0.15)
					)
					(justify left bottom)
					(hide yes)
				)
			)
			(property "Description" "Voltage Level Translator Bidirectional 1 Circuit 4 Channel 50Mbps 14-DHVQFN (2.5x3)"
				(at 35.56 -22.86 0)
				(effects
					(font
						(size 1.27 1.27)
					)
					(justify left bottom)
					(hide yes)
				)
			)
			(property "MPN" "NTS0104BQ"
				(at 35.56 -5.08 0)
				(effects
					(font
						(size 1.27 1.27)
						(thickness 0.15)
					)
					(justify left bottom)
				)
			)
			(property "Manufacturer" "NXP"
				(at 35.56 -15.24 0)
				(effects
					(font
						(size 1.27 1.27)
						(thickness 0.15)
					)
					(justify left bottom)
					(hide yes)
				)
			)
			(property "Author" "Antmicro"
				(at 35.56 -17.78 0)
				(effects
					(font
						(size 1.27 1.27)
						(thickness 0.15)
					)
					(justify left bottom)
					(hide yes)
				)
			)
			(property "License" "Apache-2.0"
				(at 35.56 -20.32 0)
				(effects
					(font
						(size 1.27 1.27)
						(thickness 0.15)
					)
					(justify left bottom)
					(hide yes)
				)
			)
			(property "ki_keywords" "IC, LEVEL-SHIFTER"
				(at 0 0 0)
				(effects
					(font
						(size 1.27 1.27)
					)
					(hide yes)
				)
			)
			(symbol "NTS0104_DHVQFN_1_1"
				(rectangle
					(start 2.54 2.54)
					(end 17.78 -17.78)
					(stroke
						(width 0.254)
						(type default)
					)
					(fill
						(type background)
					)
				)
				(pin power_in line
					(at 0 0 0)
					(length 2.54)
					(name "VCC_A"
						(effects
							(font
								(size 1.27 1.27)
							)
						)
					)
					(number "1"
						(effects
							(font
								(size 1.27 1.27)
							)
						)
					)
				)
				(pin passive line
					(at 0 -2.54 0)
					(length 2.54)
					(name "OE"
						(effects
							(font
								(size 1.27 1.27)
							)
						)
					)
					(number "8"
						(effects
							(font
								(size 1.27 1.27)
							)
						)
					)
				)
				(pin passive line
					(at 0 -5.08 0)
					(length 2.54)
					(name "A1"
						(effects
							(font
								(size 1.27 1.27)
							)
						)
					)
					(number "2"
						(effects
							(font
								(size 1.27 1.27)
							)
						)
					)
				)
				(pin passive line
					(at 0 -7.62 0)
					(length 2.54)
					(name "A2"
						(effects
							(font
								(size 1.27 1.27)
							)
						)
					)
					(number "3"
						(effects
							(font
								(size 1.27 1.27)
							)
						)
					)
				)
				(pin passive line
					(at 0 -10.16 0)
					(length 2.54)
					(name "A3"
						(effects
							(font
								(size 1.27 1.27)
							)
						)
					)
					(number "4"
						(effects
							(font
								(size 1.27 1.27)
							)
						)
					)
				)
				(pin passive line
					(at 0 -12.7 0)
					(length 2.54)
					(name "A4"
						(effects
							(font
								(size 1.27 1.27)
							)
						)
					)
					(number "5"
						(effects
							(font
								(size 1.27 1.27)
							)
						)
					)
				)
				(pin power_in line
					(at 0 -15.24 0)
					(length 2.54)
					(name "GNDPAD"
						(effects
							(font
								(size 1.27 1.27)
							)
						)
					)
					(number "15"
						(effects
							(font
								(size 1.27 1.27)
							)
						)
					)
				)
				(pin no_connect line
					(at 17.78 -2.54 180)
					(length 2.54)
					(hide yes)
					(name "NC"
						(effects
							(font
								(size 1.27 1.27)
							)
						)
					)
					(number "6"
						(effects
							(font
								(size 1.27 1.27)
							)
						)
					)
				)
				(pin no_connect line
					(at 17.78 -3.81 180)
					(length 2.54)
					(hide yes)
					(name "NC"
						(effects
							(font
								(size 1.27 1.27)
							)
						)
					)
					(number "9"
						(effects
							(font
								(size 1.27 1.27)
							)
						)
					)
				)
				(pin power_in line
					(at 20.32 0 180)
					(length 2.54)
					(name "VCC_B"
						(effects
							(font
								(size 1.27 1.27)
							)
						)
					)
					(number "14"
						(effects
							(font
								(size 1.27 1.27)
							)
						)
					)
				)
				(pin passive line
					(at 20.32 -5.08 180)
					(length 2.54)
					(name "B1"
						(effects
							(font
								(size 1.27 1.27)
							)
						)
					)
					(number "13"
						(effects
							(font
								(size 1.27 1.27)
							)
						)
					)
				)
				(pin passive line
					(at 20.32 -7.62 180)
					(length 2.54)
					(name "B2"
						(effects
							(font
								(size 1.27 1.27)
							)
						)
					)
					(number "12"
						(effects
							(font
								(size 1.27 1.27)
							)
						)
					)
				)
				(pin passive line
					(at 20.32 -10.16 180)
					(length 2.54)
					(name "B3"
						(effects
							(font
								(size 1.27 1.27)
							)
						)
					)
					(number "11"
						(effects
							(font
								(size 1.27 1.27)
							)
						)
					)
				)
				(pin passive line
					(at 20.32 -12.7 180)
					(length 2.54)
					(name "B4"
						(effects
							(font
								(size 1.27 1.27)
							)
						)
					)
					(number "10"
						(effects
							(font
								(size 1.27 1.27)
							)
						)
					)
				)
				(pin power_in line
					(at 20.32 -15.24 180)
					(length 2.54)
					(name "GND"
						(effects
							(font
								(size 1.27 1.27)
							)
						)
					)
					(number "7"
						(effects
							(font
								(size 1.27 1.27)
							)
						)
					)
				)
			)
		)
	(symbol "antmicroLogicTranslatorsLevelShifters:SN74AXC8T245_UQFN"
			(exclude_from_sim no)
			(in_bom yes)
			(on_board yes)
			(property "Reference" "U"
				(at 50.8 0 0)
				(effects
					(font
						(size 1.27 1.27)
						(thickness 0.15)
					)
					(justify left bottom)
				)
			)
			(property "Value" "SN74AXC8T245_UQFN"
				(at 50.8 -5.08 0)
				(effects
					(font
						(size 1.27 1.27)
						(thickness 0.15)
					)
					(justify left bottom)
					(hide yes)
				)
			)
			(property "Footprint" "antmicro-footprints:UQFN-24_2x4mm_P0.4mm_Texas_RJW0024A"
				(at 50.8 -10.16 0)
				(effects
					(font
						(size 1.27 1.27)
						(thickness 0.15)
					)
					(justify left bottom)
					(hide yes)
				)
			)
			(property "Datasheet" "https://www.ti.com/lit/ds/symlink/sn74axc8t245.pdf?ts=1702327536011"
				(at 50.8 -12.7 0)
				(effects
					(font
						(size 1.27 1.27)
						(thickness 0.15)
					)
					(justify left bottom)
					(hide yes)
				)
			)
			(property "Description" "8-bit dual-supply bus transceiver"
				(at 50.8 -20.32 0)
				(effects
					(font
						(size 1.27 1.27)
					)
					(justify left bottom)
					(hide yes)
				)
			)
			(property "MPN" "SN74AXC8T245RJWR"
				(at 50.8 -2.54 0)
				(effects
					(font
						(size 1.27 1.27)
					)
					(justify left bottom)
				)
			)
			(property "Manufacturer" "Texas Instruments"
				(at 50.8 -7.62 0)
				(effects
					(font
						(size 1.27 1.27)
					)
					(justify left bottom)
					(hide yes)
				)
			)
			(property "Author" "Antmicro"
				(at 50.8 -15.24 0)
				(effects
					(font
						(size 1.27 1.27)
						(thickness 0.15)
					)
					(justify left bottom)
					(hide yes)
				)
			)
			(property "License" "Apache-2.0"
				(at 50.8 -17.78 0)
				(effects
					(font
						(size 1.27 1.27)
						(thickness 0.15)
					)
					(justify left bottom)
					(hide yes)
				)
			)
			(property "ki_keywords" "LEVEL-SHIFTER , DIGITAL"
				(at 0 0 0)
				(effects
					(font
						(size 1.27 1.27)
					)
					(hide yes)
				)
			)
			(symbol "SN74AXC8T245_UQFN_0_1"
				(rectangle
					(start 2.54 2.54)
					(end 17.78 -38.1)
					(stroke
						(width 0)
						(type default)
					)
					(fill
						(type background)
					)
				)
			)
			(symbol "SN74AXC8T245_UQFN_1_1"
				(pin power_in line
					(at 0 0 0)
					(length 2.54)
					(name "VCCA"
						(effects
							(font
								(size 1.27 1.27)
							)
						)
					)
					(number "24"
						(effects
							(font
								(size 1.27 1.27)
							)
						)
					)
				)
				(pin bidirectional line
					(at 0 -5.08 0)
					(length 2.54)
					(name "A1"
						(effects
							(font
								(size 1.27 1.27)
							)
						)
					)
					(number "2"
						(effects
							(font
								(size 1.27 1.27)
							)
						)
					)
				)
				(pin bidirectional line
					(at 0 -7.62 0)
					(length 2.54)
					(name "A2"
						(effects
							(font
								(size 1.27 1.27)
							)
						)
					)
					(number "3"
						(effects
							(font
								(size 1.27 1.27)
							)
						)
					)
				)
				(pin bidirectional line
					(at 0 -10.16 0)
					(length 2.54)
					(name "A3"
						(effects
							(font
								(size 1.27 1.27)
							)
						)
					)
					(number "4"
						(effects
							(font
								(size 1.27 1.27)
							)
						)
					)
				)
				(pin bidirectional line
					(at 0 -12.7 0)
					(length 2.54)
					(name "A4"
						(effects
							(font
								(size 1.27 1.27)
							)
						)
					)
					(number "5"
						(effects
							(font
								(size 1.27 1.27)
							)
						)
					)
				)
				(pin bidirectional line
					(at 0 -15.24 0)
					(length 2.54)
					(name "A5"
						(effects
							(font
								(size 1.27 1.27)
							)
						)
					)
					(number "6"
						(effects
							(font
								(size 1.27 1.27)
							)
						)
					)
				)
				(pin bidirectional line
					(at 0 -17.78 0)
					(length 2.54)
					(name "A6"
						(effects
							(font
								(size 1.27 1.27)
							)
						)
					)
					(number "7"
						(effects
							(font
								(size 1.27 1.27)
							)
						)
					)
				)
				(pin bidirectional line
					(at 0 -20.32 0)
					(length 2.54)
					(name "A7"
						(effects
							(font
								(size 1.27 1.27)
							)
						)
					)
					(number "8"
						(effects
							(font
								(size 1.27 1.27)
							)
						)
					)
				)
				(pin bidirectional line
					(at 0 -22.86 0)
					(length 2.54)
					(name "A8"
						(effects
							(font
								(size 1.27 1.27)
							)
						)
					)
					(number "9"
						(effects
							(font
								(size 1.27 1.27)
							)
						)
					)
				)
				(pin input line
					(at 0 -27.94 0)
					(length 2.54)
					(name "OE_N"
						(effects
							(font
								(size 1.27 1.27)
							)
						)
					)
					(number "21"
						(effects
							(font
								(size 1.27 1.27)
							)
						)
					)
				)
				(pin input line
					(at 0 -33.02 0)
					(length 2.54)
					(name "DIR1"
						(effects
							(font
								(size 1.27 1.27)
							)
						)
					)
					(number "1"
						(effects
							(font
								(size 1.27 1.27)
							)
						)
					)
				)
				(pin input line
					(at 0 -35.56 0)
					(length 2.54)
					(name "DIR2"
						(effects
							(font
								(size 1.27 1.27)
							)
						)
					)
					(number "10"
						(effects
							(font
								(size 1.27 1.27)
							)
						)
					)
				)
				(pin power_in line
					(at 20.32 0 180)
					(length 2.54)
					(name "VCCB"
						(effects
							(font
								(size 1.27 1.27)
							)
						)
					)
					(number "22"
						(effects
							(font
								(size 1.27 1.27)
							)
						)
					)
				)
				(pin passive line
					(at 20.32 0 180)
					(length 2.54)
					(hide yes)
					(name "VCCB"
						(effects
							(font
								(size 1.27 1.27)
							)
						)
					)
					(number "23"
						(effects
							(font
								(size 1.27 1.27)
							)
						)
					)
				)
				(pin bidirectional line
					(at 20.32 -5.08 180)
					(length 2.54)
					(name "B1"
						(effects
							(font
								(size 1.27 1.27)
							)
						)
					)
					(number "20"
						(effects
							(font
								(size 1.27 1.27)
							)
						)
					)
				)
				(pin bidirectional line
					(at 20.32 -7.62 180)
					(length 2.54)
					(name "B2"
						(effects
							(font
								(size 1.27 1.27)
							)
						)
					)
					(number "19"
						(effects
							(font
								(size 1.27 1.27)
							)
						)
					)
				)
				(pin bidirectional line
					(at 20.32 -10.16 180)
					(length 2.54)
					(name "B3"
						(effects
							(font
								(size 1.27 1.27)
							)
						)
					)
					(number "18"
						(effects
							(font
								(size 1.27 1.27)
							)
						)
					)
				)
				(pin bidirectional line
					(at 20.32 -12.7 180)
					(length 2.54)
					(name "B4"
						(effects
							(font
								(size 1.27 1.27)
							)
						)
					)
					(number "17"
						(effects
							(font
								(size 1.27 1.27)
							)
						)
					)
				)
				(pin bidirectional line
					(at 20.32 -15.24 180)
					(length 2.54)
					(name "B5"
						(effects
							(font
								(size 1.27 1.27)
							)
						)
					)
					(number "16"
						(effects
							(font
								(size 1.27 1.27)
							)
						)
					)
				)
				(pin bidirectional line
					(at 20.32 -17.78 180)
					(length 2.54)
					(name "B6"
						(effects
							(font
								(size 1.27 1.27)
							)
						)
					)
					(number "15"
						(effects
							(font
								(size 1.27 1.27)
							)
						)
					)
				)
				(pin bidirectional line
					(at 20.32 -20.32 180)
					(length 2.54)
					(name "B7"
						(effects
							(font
								(size 1.27 1.27)
							)
						)
					)
					(number "14"
						(effects
							(font
								(size 1.27 1.27)
							)
						)
					)
				)
				(pin bidirectional line
					(at 20.32 -22.86 180)
					(length 2.54)
					(name "B8"
						(effects
							(font
								(size 1.27 1.27)
							)
						)
					)
					(number "13"
						(effects
							(font
								(size 1.27 1.27)
							)
						)
					)
				)
				(pin power_in line
					(at 20.32 -35.56 180)
					(length 2.54)
					(name "GND"
						(effects
							(font
								(size 1.27 1.27)
							)
						)
					)
					(number "11"
						(effects
							(font
								(size 1.27 1.27)
							)
						)
					)
				)
				(pin passive line
					(at 20.32 -35.56 180)
					(length 2.54)
					(hide yes)
					(name "GND"
						(effects
							(font
								(size 1.27 1.27)
							)
						)
					)
					(number "12"
						(effects
							(font
								(size 1.27 1.27)
							)
						)
					)
				)
			)
		)
	(symbol "antmicroLogicTranslatorsLevelShifters:TXU0304BQAR"
			(exclude_from_sim no)
			(in_bom yes)
			(on_board yes)
			(property "Reference" "U"
				(at 31.75 0 0)
				(effects
					(font
						(size 1.27 1.27)
						(thickness 0.15)
					)
					(justify left bottom)
				)
			)
			(property "Value" "TXU0304BQAR"
				(at 31.75 -2.54 0)
				(effects
					(font
						(size 1.27 1.27)
						(thickness 0.15)
					)
					(justify left bottom)
					(hide yes)
				)
			)
			(property "Footprint" "antmicro-footprints:DHVQFN-14-1EP_2.5x3mm"
				(at 31.75 -5.08 0)
				(effects
					(font
						(size 1.27 1.27)
						(thickness 0.15)
					)
					(justify left bottom)
					(hide yes)
				)
			)
			(property "Datasheet" "https://www.ti.com/lit/ds/symlink/txu0304.pdf?ts=1637748643258&ref_url=https%253A%252F%252Fwww.ti.com%252Fproduct%252FTXU0304"
				(at 31.75 -7.62 0)
				(effects
					(font
						(size 1.27 1.27)
						(thickness 0.15)
					)
					(justify left bottom)
					(hide yes)
				)
			)
			(property "Description" "Logic translator/level shifter"
				(at 31.75 -20.32 0)
				(effects
					(font
						(size 1.27 1.27)
					)
					(justify left bottom)
					(hide yes)
				)
			)
			(property "MPN" "TXU0304BQAR"
				(at 31.75 -10.16 0)
				(effects
					(font
						(size 1.27 1.27)
						(thickness 0.15)
					)
					(justify left bottom)
				)
			)
			(property "Manufacturer" "Texas Instruments"
				(at 31.75 -12.7 0)
				(effects
					(font
						(size 1.27 1.27)
						(thickness 0.15)
					)
					(justify left bottom)
					(hide yes)
				)
			)
			(property "Author" "Antmicro"
				(at 31.75 -15.24 0)
				(effects
					(font
						(size 1.27 1.27)
						(thickness 0.15)
					)
					(justify left bottom)
					(hide yes)
				)
			)
			(property "License" "Apache-2.0"
				(at 31.75 -17.78 0)
				(effects
					(font
						(size 1.27 1.27)
						(thickness 0.15)
					)
					(justify left bottom)
					(hide yes)
				)
			)
			(property "ki_keywords" "SMT, LOGIC, IC, LEVEL-SHIFTER"
				(at 0 0 0)
				(effects
					(font
						(size 1.27 1.27)
					)
					(hide yes)
				)
			)
			(symbol "TXU0304BQAR_1_1"
				(rectangle
					(start 2.54 2.54)
					(end 15.24 -17.78)
					(stroke
						(width 0.254)
						(type default)
					)
					(fill
						(type background)
					)
				)
				(polyline
					(pts
						(xy 6.35 -7.62) (xy 10.16 -7.62)
					)
					(stroke
						(width 0.254)
						(type default)
					)
					(fill
						(type background)
					)
				)
				(polyline
					(pts
						(xy 6.35 -12.7) (xy 10.16 -12.7)
					)
					(stroke
						(width 0.254)
						(type default)
					)
					(fill
						(type background)
					)
				)
				(polyline
					(pts
						(xy 7.62 -4.445) (xy 7.62 -5.715) (xy 8.89 -5.08) (xy 7.62 -4.445)
					)
					(stroke
						(width 0.254)
						(type default)
					)
					(fill
						(type outline)
					)
				)
				(polyline
					(pts
						(xy 7.62 -6.985) (xy 7.62 -8.255) (xy 8.89 -7.62) (xy 7.62 -6.985)
					)
					(stroke
						(width 0.254)
						(type default)
					)
					(fill
						(type outline)
					)
				)
				(polyline
					(pts
						(xy 7.62 -12.7) (xy 8.89 -12.065) (xy 8.89 -13.335) (xy 7.62 -12.7)
					)
					(stroke
						(width 0.254)
						(type default)
					)
					(fill
						(type outline)
					)
				)
				(polyline
					(pts
						(xy 8.89 -10.16) (xy 7.62 -10.795) (xy 7.62 -9.525) (xy 8.89 -10.16)
					)
					(stroke
						(width 0.254)
						(type default)
					)
					(fill
						(type outline)
					)
				)
				(polyline
					(pts
						(xy 10.16 -5.08) (xy 6.35 -5.08)
					)
					(stroke
						(width 0.254)
						(type default)
					)
					(fill
						(type background)
					)
				)
				(polyline
					(pts
						(xy 10.16 -10.16) (xy 6.35 -10.16)
					)
					(stroke
						(width 0.254)
						(type default)
					)
					(fill
						(type background)
					)
				)
				(pin power_in line
					(at 0 0 0)
					(length 2.54)
					(name "VCCA"
						(effects
							(font
								(size 1.27 1.27)
							)
						)
					)
					(number "1"
						(effects
							(font
								(size 1.27 1.27)
							)
						)
					)
				)
				(pin input line
					(at 0 -5.08 0)
					(length 2.54)
					(name "A1"
						(effects
							(font
								(size 1.27 1.27)
							)
						)
					)
					(number "2"
						(effects
							(font
								(size 1.27 1.27)
							)
						)
					)
				)
				(pin input line
					(at 0 -7.62 0)
					(length 2.54)
					(name "A2"
						(effects
							(font
								(size 1.27 1.27)
							)
						)
					)
					(number "3"
						(effects
							(font
								(size 1.27 1.27)
							)
						)
					)
				)
				(pin input line
					(at 0 -10.16 0)
					(length 2.54)
					(name "A3"
						(effects
							(font
								(size 1.27 1.27)
							)
						)
					)
					(number "4"
						(effects
							(font
								(size 1.27 1.27)
							)
						)
					)
				)
				(pin output line
					(at 0 -12.7 0)
					(length 2.54)
					(name "A4Y"
						(effects
							(font
								(size 1.27 1.27)
							)
						)
					)
					(number "5"
						(effects
							(font
								(size 1.27 1.27)
							)
						)
					)
				)
				(pin power_in line
					(at 0 -15.24 0)
					(length 2.54)
					(name "GND"
						(effects
							(font
								(size 1.27 1.27)
							)
						)
					)
					(number "15"
						(effects
							(font
								(size 1.27 1.27)
							)
						)
					)
				)
				(pin passive line
					(at 0 -15.24 0)
					(length 2.54)
					(hide yes)
					(name "GND"
						(effects
							(font
								(size 1.27 1.27)
							)
						)
					)
					(number "7"
						(effects
							(font
								(size 1.27 1.27)
							)
						)
					)
				)
				(pin no_connect line
					(at 2.54 -2.54 0)
					(length 2.54)
					(hide yes)
					(name "NC"
						(effects
							(font
								(size 1.27 1.27)
							)
						)
					)
					(number "6"
						(effects
							(font
								(size 1.27 1.27)
							)
						)
					)
				)
				(pin no_connect line
					(at 15.24 -15.24 180)
					(length 2.54)
					(hide yes)
					(name "NC"
						(effects
							(font
								(size 1.27 1.27)
							)
						)
					)
					(number "9"
						(effects
							(font
								(size 1.27 1.27)
							)
						)
					)
				)
				(pin power_in line
					(at 17.78 0 180)
					(length 2.54)
					(name "VCCB"
						(effects
							(font
								(size 1.27 1.27)
							)
						)
					)
					(number "14"
						(effects
							(font
								(size 1.27 1.27)
							)
						)
					)
				)
				(pin tri_state line
					(at 17.78 -2.54 180)
					(length 2.54)
					(name "OE"
						(effects
							(font
								(size 1.27 1.27)
							)
						)
					)
					(number "8"
						(effects
							(font
								(size 1.27 1.27)
							)
						)
					)
				)
				(pin output line
					(at 17.78 -5.08 180)
					(length 2.54)
					(name "B1Y"
						(effects
							(font
								(size 1.27 1.27)
							)
						)
					)
					(number "13"
						(effects
							(font
								(size 1.27 1.27)
							)
						)
					)
				)
				(pin output line
					(at 17.78 -7.62 180)
					(length 2.54)
					(name "B2Y"
						(effects
							(font
								(size 1.27 1.27)
							)
						)
					)
					(number "12"
						(effects
							(font
								(size 1.27 1.27)
							)
						)
					)
				)
				(pin output line
					(at 17.78 -10.16 180)
					(length 2.54)
					(name "B3Y"
						(effects
							(font
								(size 1.27 1.27)
							)
						)
					)
					(number "11"
						(effects
							(font
								(size 1.27 1.27)
							)
						)
					)
				)
				(pin input line
					(at 17.78 -12.7 180)
					(length 2.54)
					(name "B4"
						(effects
							(font
								(size 1.27 1.27)
							)
						)
					)
					(number "10"
						(effects
							(font
								(size 1.27 1.27)
							)
						)
					)
				)
			)
		)
	(symbol "antmicroMechanicalParts:Lightpipe_Bivar_SLP3-150-150-F"
			(pin_names
				(hide yes)
			)
			(exclude_from_sim no)
			(in_bom yes)
			(on_board yes)
			(property "Reference" "H"
				(at 11.76 -2.235 0)
				(effects
					(font
						(size 1.27 1.27)
						(thickness 0.15)
					)
					(justify left bottom)
				)
			)
			(property "Value" "Lightpipe_Bivar_SLP3-150-150-F"
				(at 11.76 -7.315 0)
				(effects
					(font
						(size 1.27 1.27)
						(thickness 0.15)
					)
					(justify left bottom)
					(hide yes)
				)
			)
			(property "Footprint" "antmicro-footprints:Mech_Lightpipe_Bivar_SLP3-150-150-F"
				(at 11.76 -9.855 0)
				(effects
					(font
						(size 1.27 1.27)
						(thickness 0.15)
					)
					(justify left bottom)
					(hide yes)
				)
			)
			(property "Datasheet" "https://eu.mouser.com/datasheet/2/50/Bivar_SLP3_150_XXX_X_N-3318840.pdf"
				(at 11.76 -12.395 0)
				(effects
					(font
						(size 1.27 1.27)
						(thickness 0.15)
					)
					(justify left bottom)
					(hide yes)
				)
			)
			(property "Description" "LED Light Pipe, Rigid Board, Horizontal"
				(at 11.76 -22.555 0)
				(effects
					(font
						(size 1.27 1.27)
					)
					(justify left bottom)
					(hide yes)
				)
			)
			(property "Manufacturer" "BIVAR"
				(at 11.76 -14.935 0)
				(effects
					(font
						(size 1.27 1.27)
						(thickness 0.15)
					)
					(justify left bottom)
					(hide yes)
				)
			)
			(property "MPN" "SLP3-150-150-F"
				(at 11.76 -4.775 0)
				(effects
					(font
						(size 1.27 1.27)
						(thickness 0.15)
					)
					(justify left bottom)
				)
			)
			(property "Author" "Antmicro"
				(at 11.76 -17.475 0)
				(effects
					(font
						(size 1.27 1.27)
						(thickness 0.15)
					)
					(justify left bottom)
					(hide yes)
				)
			)
			(property "License" "Apache-2.0"
				(at 11.76 -20.015 0)
				(effects
					(font
						(size 1.27 1.27)
						(thickness 0.15)
					)
					(justify left bottom)
					(hide yes)
				)
			)
			(property "ki_keywords" "HORIZONTAL, THT, MECHANICAL"
				(at 0 0 0)
				(effects
					(font
						(size 1.27 1.27)
					)
					(hide yes)
				)
			)
			(symbol "Lightpipe_Bivar_SLP3-150-150-F_1_1"
				(rectangle
					(start 5.08 -2.794)
					(end -5.08 3.556)
					(stroke
						(width 0.254)
						(type default)
					)
					(fill
						(type background)
					)
				)
				(text "Horizontal"
					(at -5.08 1.27 0)
					(effects
						(font
							(size 1.27 1.27)
							(thickness 0.15)
						)
						(justify left bottom)
					)
				)
				(text "lightguide"
					(at -4.826 -0.762 0)
					(effects
						(font
							(size 1.27 1.27)
							(thickness 0.15)
						)
						(justify left bottom)
					)
				)
				(text "1x1"
					(at -1.905 -2.794 0)
					(effects
						(font
							(size 1.27 1.27)
							(thickness 0.15)
						)
						(justify left bottom)
					)
				)
			)
		)
	(symbol "antmicroMechanicalParts:Spacer_Drill3.7mm_H2.5mm_9774025151R"
			(exclude_from_sim no)
			(in_bom yes)
			(on_board yes)
			(property "Reference" "H"
				(at 22.86 -2.54 0)
				(effects
					(font
						(size 1.27 1.27)
						(thickness 0.15)
					)
					(justify left bottom)
				)
			)
			(property "Value" "Spacer_Drill3.7mm_H2.5mm_9774025151R"
				(at 22.86 -5.08 0)
				(effects
					(font
						(size 1.27 1.27)
						(thickness 0.15)
					)
					(justify left bottom)
				)
			)
			(property "Footprint" "antmicro-footprints:Spacer_Drill3.7mm_H2.5mm_9774025151R"
				(at 22.86 -7.62 0)
				(effects
					(font
						(size 1.27 1.27)
						(thickness 0.15)
					)
					(justify left bottom)
					(hide yes)
				)
			)
			(property "Datasheet" "https://www.we-online.com/components/products/datasheet/9774025151R.pdf"
				(at 22.86 -10.16 0)
				(effects
					(font
						(size 1.27 1.27)
						(thickness 0.15)
					)
					(justify left bottom)
					(hide yes)
				)
			)
			(property "Description" "Spacer, SMT, Non Stop, Steel, Swage Round, 5.1 mm x 2.5 mm, M2.5 Thread, WA-SMSI Series"
				(at 22.86 -22.86 0)
				(effects
					(font
						(size 1.27 1.27)
					)
					(justify left bottom)
					(hide yes)
				)
			)
			(property "Manufacturer" "Würth Elektronik"
				(at 22.86 -12.7 0)
				(effects
					(font
						(size 1.27 1.27)
						(thickness 0.15)
					)
					(justify left bottom)
					(hide yes)
				)
			)
			(property "MPN" "9774025151R"
				(at 22.86 -15.24 0)
				(effects
					(font
						(size 1.27 1.27)
						(thickness 0.15)
					)
					(justify left bottom)
					(hide yes)
				)
			)
			(property "Author" "Antmicro"
				(at 22.86 -17.78 0)
				(effects
					(font
						(size 1.27 1.27)
						(thickness 0.15)
					)
					(justify left bottom)
					(hide yes)
				)
			)
			(property "License" "Apache-2.0"
				(at 22.86 -20.32 0)
				(effects
					(font
						(size 1.27 1.27)
						(thickness 0.15)
					)
					(justify left bottom)
					(hide yes)
				)
			)
			(property "ki_keywords" "MECHANICAL, SPACER"
				(at 0 0 0)
				(effects
					(font
						(size 1.27 1.27)
					)
					(hide yes)
				)
			)
			(symbol "Spacer_Drill3.7mm_H2.5mm_9774025151R_1_1"
				(rectangle
					(start 2.54 -2.54)
					(end 7.62 2.54)
					(stroke
						(width 0.254)
						(type default)
					)
					(fill
						(type background)
					)
				)
				(rectangle
					(start 3.81 -1.27)
					(end 6.35 1.27)
					(stroke
						(width 0.254)
						(type default)
					)
					(fill
						(type background)
					)
				)
				(pin passive line
					(at 0 0 0)
					(length 2.54)
					(name "~"
						(effects
							(font
								(size 1.27 1.27)
							)
						)
					)
					(number "1"
						(effects
							(font
								(size 1.27 1.27)
							)
						)
					)
				)
			)
		)
	(symbol "antmicroMechanicalParts:Spacer_Drill3.7mm_H8mm_9774080151R"
			(exclude_from_sim no)
			(in_bom yes)
			(on_board yes)
			(property "Reference" "H"
				(at 22.86 -2.54 0)
				(effects
					(font
						(size 1.27 1.27)
						(thickness 0.15)
					)
					(justify left bottom)
				)
			)
			(property "Value" "Spacer_Drill3.7mm_H8mm_9774080151R"
				(at 22.86 -5.08 0)
				(effects
					(font
						(size 1.27 1.27)
						(thickness 0.15)
					)
					(justify left bottom)
				)
			)
			(property "Footprint" "antmicro-footprints:Spacer_Drill3.7mm_H8mm_9774080151R"
				(at 22.86 -7.62 0)
				(effects
					(font
						(size 1.27 1.27)
						(thickness 0.15)
					)
					(justify left bottom)
					(hide yes)
				)
			)
			(property "Datasheet" "https://www.we-online.com/components/products/datasheet/9774080151R.pdf"
				(at 22.86 -10.16 0)
				(effects
					(font
						(size 1.27 1.27)
						(thickness 0.15)
					)
					(justify left bottom)
					(hide yes)
				)
			)
			(property "Description" "Spacer, SMT, Non Stop, Steel, Swage Round, 5.1 mm x 8 mm, M2.5 Thread, WA-SMSI Series"
				(at 22.86 -22.86 0)
				(effects
					(font
						(size 1.27 1.27)
					)
					(justify left bottom)
					(hide yes)
				)
			)
			(property "Manufacturer" "Würth Elektronik"
				(at 22.86 -12.7 0)
				(effects
					(font
						(size 1.27 1.27)
						(thickness 0.15)
					)
					(justify left bottom)
					(hide yes)
				)
			)
			(property "MPN" "9774080151R"
				(at 22.86 -15.24 0)
				(effects
					(font
						(size 1.27 1.27)
						(thickness 0.15)
					)
					(justify left bottom)
					(hide yes)
				)
			)
			(property "Author" "Antmicro"
				(at 22.86 -17.78 0)
				(effects
					(font
						(size 1.27 1.27)
						(thickness 0.15)
					)
					(justify left bottom)
					(hide yes)
				)
			)
			(property "License" "Apache-2.0"
				(at 22.86 -20.32 0)
				(effects
					(font
						(size 1.27 1.27)
						(thickness 0.15)
					)
					(justify left bottom)
					(hide yes)
				)
			)
			(property "ki_keywords" "MECHANICAL, SPACER"
				(at 0 0 0)
				(effects
					(font
						(size 1.27 1.27)
					)
					(hide yes)
				)
			)
			(symbol "Spacer_Drill3.7mm_H8mm_9774080151R_1_1"
				(rectangle
					(start 2.54 -2.54)
					(end 7.62 2.54)
					(stroke
						(width 0.254)
						(type default)
					)
					(fill
						(type background)
					)
				)
				(rectangle
					(start 3.81 -1.27)
					(end 6.35 1.27)
					(stroke
						(width 0.254)
						(type default)
					)
					(fill
						(type background)
					)
				)
				(pin passive line
					(at 0 0 0)
					(length 2.54)
					(name "~"
						(effects
							(font
								(size 1.27 1.27)
							)
						)
					)
					(number "1"
						(effects
							(font
								(size 1.27 1.27)
							)
						)
					)
				)
			)
		)
	(symbol "antmicroMechanicalParts:Spacer_Drill4.45mm_H4mm_9774040960R"
			(exclude_from_sim no)
			(in_bom yes)
			(on_board yes)
			(property "Reference" "H"
				(at 22.86 -2.54 0)
				(effects
					(font
						(size 1.27 1.27)
						(thickness 0.15)
					)
					(justify left bottom)
				)
			)
			(property "Value" "Spacer_Drill4.45mm_H4mm_9774040960R"
				(at 22.86 -5.08 0)
				(effects
					(font
						(size 1.27 1.27)
						(thickness 0.15)
					)
					(justify left bottom)
				)
			)
			(property "Footprint" "antmicro-footprints:Spacer_Drill4.45mm_H4mm_9774040960R"
				(at 22.86 -7.62 0)
				(effects
					(font
						(size 1.27 1.27)
						(thickness 0.15)
					)
					(justify left bottom)
					(hide yes)
				)
			)
			(property "Datasheet" "https://www.we-online.com/components/products/datasheet/9774040960R.pdf"
				(at 22.86 -10.16 0)
				(effects
					(font
						(size 1.27 1.27)
						(thickness 0.15)
					)
					(justify left bottom)
					(hide yes)
				)
			)
			(property "Description" "Spacer, SMT, Non Stop, Steel, Swage Round, 6 mm x 4 mm, 3.3 mm Internal, WA-SMST Series"
				(at 22.86 -22.86 0)
				(effects
					(font
						(size 1.27 1.27)
					)
					(justify left bottom)
					(hide yes)
				)
			)
			(property "Manufacturer" "Würth Elektronik"
				(at 22.86 -12.7 0)
				(effects
					(font
						(size 1.27 1.27)
						(thickness 0.15)
					)
					(justify left bottom)
					(hide yes)
				)
			)
			(property "MPN" "9774040960R"
				(at 22.86 -15.24 0)
				(effects
					(font
						(size 1.27 1.27)
						(thickness 0.15)
					)
					(justify left bottom)
					(hide yes)
				)
			)
			(property "Author" "Antmicro"
				(at 22.86 -17.78 0)
				(effects
					(font
						(size 1.27 1.27)
						(thickness 0.15)
					)
					(justify left bottom)
					(hide yes)
				)
			)
			(property "License" "Apache-2.0"
				(at 22.86 -20.32 0)
				(effects
					(font
						(size 1.27 1.27)
						(thickness 0.15)
					)
					(justify left bottom)
					(hide yes)
				)
			)
			(property "ki_keywords" "SPACER"
				(at 0 0 0)
				(effects
					(font
						(size 1.27 1.27)
					)
					(hide yes)
				)
			)
			(symbol "Spacer_Drill4.45mm_H4mm_9774040960R_1_1"
				(rectangle
					(start 2.54 -2.54)
					(end 7.62 2.54)
					(stroke
						(width 0.254)
						(type default)
					)
					(fill
						(type background)
					)
				)
				(rectangle
					(start 3.81 -1.27)
					(end 6.35 1.27)
					(stroke
						(width 0.254)
						(type default)
					)
					(fill
						(type background)
					)
				)
				(pin passive line
					(at 0 0 0)
					(length 2.54)
					(name "~"
						(effects
							(font
								(size 1.27 1.27)
							)
						)
					)
					(number "1"
						(effects
							(font
								(size 1.27 1.27)
							)
						)
					)
				)
			)
		)
	(symbol "antmicroMemory:AT24CS01_SOIC8"
			(exclude_from_sim no)
			(in_bom yes)
			(on_board yes)
			(property "Reference" "U"
				(at 35.56 -2.54 0)
				(effects
					(font
						(size 1.27 1.27)
						(thickness 0.15)
					)
					(justify left bottom)
				)
			)
			(property "Value" "AT24CS01_SOIC8"
				(at 35.56 -5.08 0)
				(effects
					(font
						(size 1.27 1.27)
						(thickness 0.15)
					)
					(justify left bottom)
					(hide yes)
				)
			)
			(property "Footprint" "antmicro-footprints:SOIC-8_3.9x4.9x1.75mm_P1.27mm"
				(at 35.56 -7.62 0)
				(effects
					(font
						(size 1.27 1.27)
						(thickness 0.15)
					)
					(justify left bottom)
					(hide yes)
				)
			)
			(property "Datasheet" "https://ww1.microchip.com/downloads/aemDocuments/documents/MPD/ProductDocuments/DataSheets/20006330A.pdf"
				(at 35.56 -10.16 0)
				(effects
					(font
						(size 1.27 1.27)
						(thickness 0.15)
					)
					(justify left bottom)
					(hide yes)
				)
			)
			(property "Description" "EEPROM, 1 Kbit, 128 x 8bit, Serial I2C (2-Wire), 1 MHz, SOIC-8"
				(at 35.56 -22.86 0)
				(effects
					(font
						(size 1.27 1.27)
					)
					(justify left bottom)
					(hide yes)
				)
			)
			(property "Manufacturer" "Microchip Technology"
				(at 35.56 -12.7 0)
				(effects
					(font
						(size 1.27 1.27)
						(thickness 0.15)
					)
					(justify left bottom)
					(hide yes)
				)
			)
			(property "MPN" "AT24CS01-SSHM-B"
				(at 35.56 -15.24 0)
				(effects
					(font
						(size 1.27 1.27)
						(thickness 0.15)
					)
					(justify left bottom)
				)
			)
			(property "Author" "Antmicro"
				(at 35.56 -17.78 0)
				(effects
					(font
						(size 1.27 1.27)
						(thickness 0.15)
					)
					(justify left bottom)
					(hide yes)
				)
			)
			(property "License" "Apache-2.0"
				(at 35.56 -20.32 0)
				(effects
					(font
						(size 1.27 1.27)
						(thickness 0.15)
					)
					(justify left bottom)
					(hide yes)
				)
			)
			(property "ki_keywords" "IC"
				(at 0 0 0)
				(effects
					(font
						(size 1.27 1.27)
					)
					(hide yes)
				)
			)
			(symbol "AT24CS01_SOIC8_1_1"
				(rectangle
					(start 2.54 2.54)
					(end 12.7 -13.97)
					(stroke
						(width 0.254)
						(type default)
					)
					(fill
						(type background)
					)
				)
				(pin input line
					(at 0 0 0)
					(length 2.54)
					(name "SCL"
						(effects
							(font
								(size 1.27 1.27)
							)
						)
					)
					(number "6"
						(effects
							(font
								(size 1.27 1.27)
							)
						)
					)
				)
				(pin bidirectional line
					(at 0 -2.54 0)
					(length 2.54)
					(name "SDA"
						(effects
							(font
								(size 1.27 1.27)
							)
						)
					)
					(number "5"
						(effects
							(font
								(size 1.27 1.27)
							)
						)
					)
				)
				(pin input line
					(at 0 -6.35 0)
					(length 2.54)
					(name "A0"
						(effects
							(font
								(size 1.27 1.27)
							)
						)
					)
					(number "1"
						(effects
							(font
								(size 1.27 1.27)
							)
						)
					)
				)
				(pin input line
					(at 0 -8.89 0)
					(length 2.54)
					(name "A1"
						(effects
							(font
								(size 1.27 1.27)
							)
						)
					)
					(number "2"
						(effects
							(font
								(size 1.27 1.27)
							)
						)
					)
				)
				(pin input line
					(at 0 -11.43 0)
					(length 2.54)
					(name "A2"
						(effects
							(font
								(size 1.27 1.27)
							)
						)
					)
					(number "3"
						(effects
							(font
								(size 1.27 1.27)
							)
						)
					)
				)
				(pin power_in line
					(at 15.24 0 180)
					(length 2.54)
					(name "VCC"
						(effects
							(font
								(size 1.27 1.27)
							)
						)
					)
					(number "8"
						(effects
							(font
								(size 1.27 1.27)
							)
						)
					)
				)
				(pin input line
					(at 15.24 -5.08 180)
					(length 2.54)
					(name "WP"
						(effects
							(font
								(size 1.27 1.27)
							)
						)
					)
					(number "7"
						(effects
							(font
								(size 1.27 1.27)
							)
						)
					)
				)
				(pin power_in line
					(at 15.24 -11.43 180)
					(length 2.54)
					(name "GND"
						(effects
							(font
								(size 1.27 1.27)
							)
						)
					)
					(number "4"
						(effects
							(font
								(size 1.27 1.27)
							)
						)
					)
				)
			)
		)
	(symbol "antmicroMemory:SST26VF064B"
			(exclude_from_sim no)
			(in_bom yes)
			(on_board yes)
			(property "Reference" "U"
				(at 35.56 -2.54 0)
				(effects
					(font
						(size 1.27 1.27)
						(thickness 0.15)
					)
					(justify left bottom)
				)
			)
			(property "Value" "SST26VF064B"
				(at 35.56 -7.62 0)
				(effects
					(font
						(size 1.27 1.27)
						(thickness 0.15)
					)
					(justify left bottom)
					(hide yes)
				)
			)
			(property "Footprint" "antmicro-footprints:SOIJ-8_5.28x5.28x2.0mm_P1.27mm"
				(at 35.56 -10.16 0)
				(effects
					(font
						(size 1.27 1.27)
						(thickness 0.15)
					)
					(justify left bottom)
					(hide yes)
				)
			)
			(property "Datasheet" "https://www.mouser.com/datasheet/3/282/1/SST26VF064B-SST26VF064BA-2-5V-3-0V-64-Mbit-Serial-Quad-IO--SQI--Flash-Memory-20005119K.pdf"
				(at 35.56 -12.7 0)
				(effects
					(font
						(size 1.27 1.27)
						(thickness 0.15)
					)
					(justify left bottom)
					(hide yes)
				)
			)
			(property "Description" "64-Mbit 2.3V-3.6V, SQI Flash Memory, -40°C to +85°C"
				(at 35.56 -22.86 0)
				(effects
					(font
						(size 1.27 1.27)
					)
					(justify left bottom)
					(hide yes)
				)
			)
			(property "MPN" "SST26VF064B-104I/SM"
				(at 35.56 -5.08 0)
				(effects
					(font
						(size 1.27 1.27)
						(thickness 0.15)
					)
					(justify left bottom)
				)
			)
			(property "Manufacturer" "Microchip Technology"
				(at 35.56 -15.24 0)
				(effects
					(font
						(size 1.27 1.27)
						(thickness 0.15)
					)
					(justify left bottom)
					(hide yes)
				)
			)
			(property "Author" "Antmicro"
				(at 35.56 -17.78 0)
				(effects
					(font
						(size 1.27 1.27)
						(thickness 0.15)
					)
					(justify left bottom)
					(hide yes)
				)
			)
			(property "License" "Apache-2.0"
				(at 35.56 -20.32 0)
				(effects
					(font
						(size 1.27 1.27)
						(thickness 0.15)
					)
					(justify left bottom)
					(hide yes)
				)
			)
			(property "ki_keywords" "IC, SMT, FLASH"
				(at 0 0 0)
				(effects
					(font
						(size 1.27 1.27)
					)
					(hide yes)
				)
			)
			(symbol "SST26VF064B_0_0"
				(pin input line
					(at 0 -12.7 0)
					(length 2.54)
					(name "SCK"
						(effects
							(font
								(size 1.27 1.27)
							)
						)
					)
					(number "6"
						(effects
							(font
								(size 1.27 1.27)
							)
						)
					)
				)
			)
			(symbol "SST26VF064B_1_0"
				(pin power_in line
					(at 0 0 0)
					(length 2.54)
					(name "V_{DD}"
						(effects
							(font
								(size 1.27 1.27)
							)
						)
					)
					(number "8"
						(effects
							(font
								(size 1.27 1.27)
							)
						)
					)
				)
				(pin input line
					(at 0 -5.08 0)
					(length 2.54)
					(name "WP#"
						(effects
							(font
								(size 1.27 1.27)
							)
						)
					)
					(number "3"
						(effects
							(font
								(size 1.27 1.27)
							)
						)
					)
					(alternate "SIO2" bidirectional line)
				)
				(pin input line
					(at 0 -7.62 0)
					(length 2.54)
					(name "HOLD#"
						(effects
							(font
								(size 1.27 1.27)
							)
						)
					)
					(number "7"
						(effects
							(font
								(size 1.27 1.27)
							)
						)
					)
					(alternate "SIO3" bidirectional line)
				)
				(pin input line
					(at 0 -10.16 0)
					(length 2.54)
					(name "CE#"
						(effects
							(font
								(size 1.27 1.27)
							)
						)
					)
					(number "1"
						(effects
							(font
								(size 1.27 1.27)
							)
						)
					)
				)
				(pin input line
					(at 0 -15.24 0)
					(length 2.54)
					(name "SI"
						(effects
							(font
								(size 1.27 1.27)
							)
						)
					)
					(number "5"
						(effects
							(font
								(size 1.27 1.27)
							)
						)
					)
					(alternate "SIO0" bidirectional line)
				)
				(pin output line
					(at 0 -17.78 0)
					(length 2.54)
					(name "SO"
						(effects
							(font
								(size 1.27 1.27)
							)
						)
					)
					(number "2"
						(effects
							(font
								(size 1.27 1.27)
							)
						)
					)
					(alternate "SIO1" bidirectional line)
				)
				(pin power_in line
					(at 0 -22.86 0)
					(length 2.54)
					(name "V_{SS}"
						(effects
							(font
								(size 1.27 1.27)
							)
						)
					)
					(number "4"
						(effects
							(font
								(size 1.27 1.27)
							)
						)
					)
				)
			)
			(symbol "SST26VF064B_1_1"
				(rectangle
					(start 2.54 2.54)
					(end 21.59 -25.4)
					(stroke
						(width 0.254)
						(type default)
					)
					(fill
						(type background)
					)
				)
			)
		)
	(symbol "antmicroMemory:W25Q80DV_USON"
			(exclude_from_sim no)
			(in_bom yes)
			(on_board yes)
			(property "Reference" "U"
				(at 38.1 -6.35 0)
				(effects
					(font
						(size 1.27 1.27)
						(thickness 0.15)
					)
					(justify left bottom)
				)
			)
			(property "Value" "W25Q80DV_USON"
				(at 38.1 -8.89 0)
				(effects
					(font
						(size 1.27 1.27)
						(thickness 0.15)
					)
					(justify left bottom)
					(hide yes)
				)
			)
			(property "Footprint" "antmicro-footprints:USON-8_2x3mm_P0.5mm"
				(at 38.1 -11.43 0)
				(effects
					(font
						(size 1.27 1.27)
						(thickness 0.15)
					)
					(justify left bottom)
					(hide yes)
				)
			)
			(property "Datasheet" "https://www.mouser.com/datasheet/2/949/w25q80dv_dl_revh_10022015-1489677.pdf"
				(at 38.1 -13.97 0)
				(effects
					(font
						(size 1.27 1.27)
						(thickness 0.15)
					)
					(justify left bottom)
					(hide yes)
				)
			)
			(property "Description" "FLASH - NOR Memory IC 8Mbit SPI - Quad I/O 104 MHz 8-USON (2x3)"
				(at 38.1 -26.67 0)
				(effects
					(font
						(size 1.27 1.27)
					)
					(justify left bottom)
					(hide yes)
				)
			)
			(property "MPN" "W25Q80DVUXIE TR"
				(at 38.1 -16.51 0)
				(effects
					(font
						(size 1.27 1.27)
						(thickness 0.15)
					)
					(justify left bottom)
				)
			)
			(property "Manufacturer" "Winbond"
				(at 38.1 -19.05 0)
				(effects
					(font
						(size 1.27 1.27)
						(thickness 0.15)
					)
					(justify left bottom)
					(hide yes)
				)
			)
			(property "Author" "Antmicro"
				(at 38.1 -21.59 0)
				(effects
					(font
						(size 1.27 1.27)
						(thickness 0.15)
					)
					(justify left bottom)
					(hide yes)
				)
			)
			(property "License" "Apache-2.0"
				(at 38.1 -24.13 0)
				(effects
					(font
						(size 1.27 1.27)
						(thickness 0.15)
					)
					(justify left bottom)
					(hide yes)
				)
			)
			(property "ki_keywords" "SMT, MEMORY, IC, FLASH"
				(at 0 0 0)
				(effects
					(font
						(size 1.27 1.27)
					)
					(hide yes)
				)
			)
			(symbol "W25Q80DV_USON_1_1"
				(rectangle
					(start 2.54 2.54)
					(end 16.51 -15.24)
					(stroke
						(width 0.254)
						(type default)
					)
					(fill
						(type background)
					)
				)
				(pin input line
					(at 0 0 0)
					(length 2.54)
					(name "SI/IO0"
						(effects
							(font
								(size 1.27 1.27)
							)
						)
					)
					(number "5"
						(effects
							(font
								(size 1.27 1.27)
							)
						)
					)
				)
				(pin input line
					(at 0 -2.54 0)
					(length 2.54)
					(name "SO/IO1"
						(effects
							(font
								(size 1.27 1.27)
							)
						)
					)
					(number "2"
						(effects
							(font
								(size 1.27 1.27)
							)
						)
					)
				)
				(pin input line
					(at 0 -5.08 0)
					(length 2.54)
					(name "~{WP}/IO2"
						(effects
							(font
								(size 1.27 1.27)
							)
						)
					)
					(number "3"
						(effects
							(font
								(size 1.27 1.27)
							)
						)
					)
				)
				(pin input line
					(at 0 -7.62 0)
					(length 2.54)
					(name "~{HOLD}/IO3"
						(effects
							(font
								(size 1.27 1.27)
							)
						)
					)
					(number "7"
						(effects
							(font
								(size 1.27 1.27)
							)
						)
					)
				)
				(pin input line
					(at 0 -10.16 0)
					(length 2.54)
					(name "SCLK"
						(effects
							(font
								(size 1.27 1.27)
							)
						)
					)
					(number "6"
						(effects
							(font
								(size 1.27 1.27)
							)
						)
					)
				)
				(pin input line
					(at 0 -12.7 0)
					(length 2.54)
					(name "~{CS}"
						(effects
							(font
								(size 1.27 1.27)
							)
						)
					)
					(number "1"
						(effects
							(font
								(size 1.27 1.27)
							)
						)
					)
				)
				(pin power_in line
					(at 19.05 0 180)
					(length 2.54)
					(name "VCC"
						(effects
							(font
								(size 1.27 1.27)
							)
						)
					)
					(number "8"
						(effects
							(font
								(size 1.27 1.27)
							)
						)
					)
				)
				(pin power_in line
					(at 19.05 -10.16 180)
					(length 2.54)
					(name "EP"
						(effects
							(font
								(size 1.27 1.27)
							)
						)
					)
					(number "EP"
						(effects
							(font
								(size 1.27 1.27)
							)
						)
					)
				)
				(pin power_in line
					(at 19.05 -12.7 180)
					(length 2.54)
					(name "VSS"
						(effects
							(font
								(size 1.27 1.27)
							)
						)
					)
					(number "4"
						(effects
							(font
								(size 1.27 1.27)
							)
						)
					)
				)
			)
		)
	(symbol "antmicroModules:Jetson-Thor-AGX-T5000"
			(pin_names
				(offset 1.016)
			)
			(exclude_from_sim no)
			(in_bom no)
			(on_board yes)
			(property "Reference" "A"
				(at 25.4 -5.08 0)
				(effects
					(font
						(size 1.27 1.27)
						(thickness 0.15)
					)
					(justify left bottom)
				)
			)
			(property "Value" "Jetson-Thor-AGX-T5000"
				(at 25.4 -7.62 0)
				(effects
					(font
						(size 1.27 1.27)
						(thickness 0.15)
					)
					(justify left bottom)
					(hide yes)
				)
			)
			(property "Footprint" "antmicro-footprints:Module_Jetson-Thor-AGX-T5000"
				(at 25.4 -10.16 0)
				(effects
					(font
						(size 1.27 1.27)
						(thickness 0.15)
					)
					(justify left bottom)
					(hide yes)
				)
			)
			(property "Datasheet" "https://developer.nvidia.com/embedded/downloads#?tx=$product,jetson_thor"
				(at 25.4 -12.7 0)
				(effects
					(font
						(size 1.27 1.27)
						(thickness 0.15)
					)
					(justify left bottom)
					(hide yes)
				)
			)
			(property "Description" "Jetson Thor, System-on-Module, 2560-core NVIDIA Blackwell GPU with 96 fifth-gen Tensor Cores, Multi-Instance GPU with 10TPCs, 14-core Arm Neoverse-V3AE 64-bit CPU, 128 GB LPDDR5X"
				(at 25.4 -27.94 0)
				(effects
					(font
						(size 1.27 1.27)
					)
					(justify left bottom)
					(hide yes)
				)
			)
			(property "Manufacturer" "Nvidia"
				(at 25.4 -15.24 0)
				(effects
					(font
						(size 1.27 1.27)
						(thickness 0.15)
					)
					(justify left bottom)
					(hide yes)
				)
			)
			(property "MPN" "900-13834-0080-000"
				(at 25.4 -17.78 0)
				(effects
					(font
						(size 1.27 1.27)
						(thickness 0.15)
					)
					(justify left bottom)
				)
			)
			(property "Author" "Antmicro"
				(at 25.4 -20.32 0)
				(effects
					(font
						(size 1.27 1.27)
						(thickness 0.15)
					)
					(justify left bottom)
					(hide yes)
				)
			)
			(property "License" "Apache-2.0"
				(at 25.4 -22.86 0)
				(effects
					(font
						(size 1.27 1.27)
						(thickness 0.15)
					)
					(justify left bottom)
					(hide yes)
				)
			)
			(property "Displayed name" "Jetson Thor AGX T5000"
				(at 25.4 -25.4 0)
				(effects
					(font
						(size 1.27 1.27)
					)
					(justify left bottom)
				)
			)
			(property "ki_keywords" "MODULE, SOM"
				(at 0 0 0)
				(effects
					(font
						(size 1.27 1.27)
					)
					(hide yes)
				)
			)
			(symbol "Jetson-Thor-AGX-T5000_0_1"
				(rectangle
					(start 10.16 -6.35)
					(end 0 0)
					(stroke
						(width 0)
						(type default)
					)
					(fill
						(type background)
					)
				)
			)
		)
	(symbol "antmicroModules:Mech_M2_2242_H2.5mm"
			(exclude_from_sim no)
			(in_bom no)
			(on_board yes)
			(property "Reference" "A"
				(at 25.4 0 0)
				(effects
					(font
						(size 1.27 1.27)
						(thickness 0.15)
					)
					(justify left bottom)
				)
			)
			(property "Value" "Mech_M2_2242_H2.5mm"
				(at 25.4 -2.54 0)
				(effects
					(font
						(size 1.27 1.27)
						(thickness 0.15)
					)
					(justify left bottom)
				)
			)
			(property "Footprint" "antmicro-footprints:Mech_M2_2242_H2.5mm"
				(at 25.4 -5.08 0)
				(effects
					(font
						(size 1.27 1.27)
						(thickness 0.15)
					)
					(justify left bottom)
					(hide yes)
				)
			)
			(property "Datasheet" ""
				(at 25.4 -7.62 0)
				(effects
					(font
						(size 1.27 1.27)
						(thickness 0.15)
					)
					(justify left bottom)
					(hide yes)
				)
			)
			(property "Description" "Mechanical model for M2 2242 2.5mm module"
				(at 25.4 -15.24 0)
				(effects
					(font
						(size 1.27 1.27)
					)
					(justify left bottom)
					(hide yes)
				)
			)
			(property "MPN" ""
				(at 0 0 0)
				(effects
					(font
						(size 1.27 1.27)
					)
				)
			)
			(property "Manufacturer" ""
				(at 0 0 0)
				(effects
					(font
						(size 1.27 1.27)
					)
					(hide yes)
				)
			)
			(property "Author" "Antmicro"
				(at 25.4 -10.16 0)
				(effects
					(font
						(size 1.27 1.27)
						(thickness 0.15)
					)
					(justify left bottom)
					(hide yes)
				)
			)
			(property "License" "Apache-2.0"
				(at 25.4 -12.7 0)
				(effects
					(font
						(size 1.27 1.27)
						(thickness 0.15)
					)
					(justify left bottom)
					(hide yes)
				)
			)
			(property "ki_keywords" "MODULE"
				(at 0 0 0)
				(effects
					(font
						(size 1.27 1.27)
					)
					(hide yes)
				)
			)
			(symbol "Mech_M2_2242_H2.5mm_1_1"
				(rectangle
					(start 10.16 -6.35)
					(end 0 0)
					(stroke
						(width 0.254)
						(type default)
					)
					(fill
						(type background)
					)
				)
			)
		)
	(symbol "antmicroModules:Mech_M2_2280_H2.5mm"
			(exclude_from_sim no)
			(in_bom no)
			(on_board yes)
			(property "Reference" "A"
				(at 25.4 0 0)
				(effects
					(font
						(size 1.27 1.27)
						(thickness 0.15)
					)
					(justify left bottom)
				)
			)
			(property "Value" "Mech_M2_2280_H2.5mm"
				(at 25.4 -2.54 0)
				(effects
					(font
						(size 1.27 1.27)
						(thickness 0.15)
					)
					(justify left bottom)
				)
			)
			(property "Footprint" "antmicro-footprints:Mech_M2_2280_H2.5mm"
				(at 25.4 -5.08 0)
				(effects
					(font
						(size 1.27 1.27)
						(thickness 0.15)
					)
					(justify left bottom)
					(hide yes)
				)
			)
			(property "Datasheet" ""
				(at 25.4 -7.62 0)
				(effects
					(font
						(size 1.27 1.27)
						(thickness 0.15)
					)
					(justify left bottom)
					(hide yes)
				)
			)
			(property "Description" "Mechanical model for M2 2280 2.5mm module"
				(at 25.4 -15.24 0)
				(effects
					(font
						(size 1.27 1.27)
					)
					(justify left bottom)
					(hide yes)
				)
			)
			(property "Manufacturer" ""
				(at 0 0 0)
				(effects
					(font
						(size 1.27 1.27)
					)
					(hide yes)
				)
			)
			(property "MPN" ""
				(at 0 0 0)
				(effects
					(font
						(size 1.27 1.27)
					)
				)
			)
			(property "Author" "Antmicro"
				(at 25.4 -10.16 0)
				(effects
					(font
						(size 1.27 1.27)
						(thickness 0.15)
					)
					(justify left bottom)
					(hide yes)
				)
			)
			(property "License" "Apache-2.0"
				(at 25.4 -12.7 0)
				(effects
					(font
						(size 1.27 1.27)
						(thickness 0.15)
					)
					(justify left bottom)
					(hide yes)
				)
			)
			(property "ki_keywords" "MODULE"
				(at 0 0 0)
				(effects
					(font
						(size 1.27 1.27)
					)
					(hide yes)
				)
			)
			(symbol "Mech_M2_2280_H2.5mm_1_1"
				(rectangle
					(start 10.16 -6.35)
					(end 0 0)
					(stroke
						(width 0.254)
						(type default)
					)
					(fill
						(type background)
					)
				)
			)
		)
	(symbol "antmicroOscillators:Oscillator_100MHz_NX324"
			(exclude_from_sim no)
			(in_bom yes)
			(on_board yes)
			(property "Reference" "Y"
				(at 29.21 -1.905 0)
				(effects
					(font
						(size 1.27 1.27)
						(thickness 0.15)
					)
					(justify left bottom)
				)
			)
			(property "Value" "Oscillator_100MHz_NX324"
				(at 29.21 -12.065 0)
				(effects
					(font
						(size 1.27 1.27)
						(thickness 0.15)
					)
					(justify left bottom)
					(hide yes)
				)
			)
			(property "Footprint" "antmicro-footprints:Oscillator_SMD_Abracon_AX3_3.2x2.5x1mm"
				(at 29.21 -14.605 0)
				(effects
					(font
						(size 1.27 1.27)
						(thickness 0.15)
					)
					(justify left bottom)
					(hide yes)
				)
			)
			(property "Datasheet" "https://www.diodes.com/assets/Datasheets/NX324.pdf"
				(at 29.21 -17.145 0)
				(effects
					(font
						(size 1.27 1.27)
						(thickness 0.15)
					)
					(justify left bottom)
					(hide yes)
				)
			)
			(property "Description" "100 MHz XO (Standard) HCSL Oscillator 3.3V Enable/Disable 6-SMD, No Lead"
				(at 29.21 -24.765 0)
				(effects
					(font
						(size 1.27 1.27)
					)
					(justify left bottom)
					(hide yes)
				)
			)
			(property "Manufacturer" "Diodes Incorporated"
				(at 29.21 -4.445 0)
				(effects
					(font
						(size 1.27 1.27)
						(thickness 0.15)
					)
					(justify left bottom)
					(hide yes)
				)
			)
			(property "MPN" "NX3241E0100.000000"
				(at 29.21 -6.985 0)
				(effects
					(font
						(size 1.27 1.27)
						(thickness 0.15)
					)
					(justify left bottom)
				)
			)
			(property "Val" "100 MHz"
				(at 29.21 -9.525 0)
				(effects
					(font
						(size 1.27 1.27)
						(thickness 0.15)
					)
					(justify left bottom)
				)
			)
			(property "Author" "Antmicro"
				(at 29.21 -19.685 0)
				(effects
					(font
						(size 1.27 1.27)
						(thickness 0.15)
					)
					(justify left bottom)
					(hide yes)
				)
			)
			(property "License" "Apache-2.0"
				(at 29.21 -22.225 0)
				(effects
					(font
						(size 1.27 1.27)
						(thickness 0.15)
					)
					(justify left bottom)
					(hide yes)
				)
			)
			(property "ki_keywords" "OSCILLATOR"
				(at 0 0 0)
				(effects
					(font
						(size 1.27 1.27)
					)
					(hide yes)
				)
			)
			(symbol "Oscillator_100MHz_NX324_1_1"
				(rectangle
					(start 2.54 2.54)
					(end 16.51 -7.62)
					(stroke
						(width 0.254)
						(type default)
					)
					(fill
						(type background)
					)
				)
				(polyline
					(pts
						(xy 7.62 -1.27) (xy 8.255 -1.27) (xy 8.255 0) (xy 8.89 0) (xy 8.89 -1.27) (xy 9.525 -1.27) (xy 9.525 0)
						(xy 10.16 0) (xy 10.16 -1.27)
					)
					(stroke
						(width 0.254)
						(type default)
					)
					(fill
						(type background)
					)
				)
				(pin power_in line
					(at 0 0 0)
					(length 2.54)
					(name "VCC"
						(effects
							(font
								(size 1.27 1.27)
							)
						)
					)
					(number "6"
						(effects
							(font
								(size 1.27 1.27)
							)
						)
					)
				)
				(pin input line
					(at 0 -2.54 0)
					(length 2.54)
					(name "EN"
						(effects
							(font
								(size 1.27 1.27)
							)
						)
					)
					(number "1"
						(effects
							(font
								(size 1.27 1.27)
							)
						)
					)
				)
				(pin power_in line
					(at 0 -5.08 0)
					(length 2.54)
					(name "GND"
						(effects
							(font
								(size 1.27 1.27)
							)
						)
					)
					(number "3"
						(effects
							(font
								(size 1.27 1.27)
							)
						)
					)
				)
				(pin no_connect line
					(at 16.51 -5.08 180)
					(length 2.54)
					(hide yes)
					(name "NC"
						(effects
							(font
								(size 1.27 1.27)
							)
						)
					)
					(number "2"
						(effects
							(font
								(size 1.27 1.27)
							)
						)
					)
				)
				(pin output line
					(at 19.05 0 180)
					(length 2.54)
					(name "OUT+"
						(effects
							(font
								(size 1.27 1.27)
							)
						)
					)
					(number "4"
						(effects
							(font
								(size 1.27 1.27)
							)
						)
					)
				)
				(pin output line
					(at 19.05 -2.54 180)
					(length 2.54)
					(name "OUT-"
						(effects
							(font
								(size 1.27 1.27)
							)
						)
					)
					(number "5"
						(effects
							(font
								(size 1.27 1.27)
							)
						)
					)
				)
			)
		)
	(symbol "antmicroOscillators:Oscillator_156.25MHz_AK3LPHEF1"
			(exclude_from_sim no)
			(in_bom yes)
			(on_board yes)
			(property "Reference" "Y"
				(at 20.32 -10.16 0)
				(effects
					(font
						(size 1.27 1.27)
						(thickness 0.15)
					)
					(justify left bottom)
				)
			)
			(property "Value" "Oscillator_156.25MHz_AK3LPHEF1"
				(at 20.32 -20.32 0)
				(effects
					(font
						(size 1.27 1.27)
						(thickness 0.15)
					)
					(justify left bottom)
					(hide yes)
				)
			)
			(property "Footprint" "antmicro-footprints:Oscillator_SMD_Abracon_AK3LPHEF1_3.2x2.5x1mm"
				(at 20.32 -22.86 0)
				(effects
					(font
						(size 1.27 1.27)
						(thickness 0.15)
					)
					(justify left bottom)
					(hide yes)
				)
			)
			(property "Datasheet" "https://eu.mouser.com/datasheet/2/3/AK3LP-3318362.pdf"
				(at 20.32 -25.4 0)
				(effects
					(font
						(size 1.27 1.27)
						(thickness 0.15)
					)
					(justify left bottom)
					(hide yes)
				)
			)
			(property "Description" "156.25 MHz XO (Standard) HCSL Oscillator 3.3V Enable/Disable 6-SMD, +/-25ppm"
				(at 20.32 -33.02 0)
				(effects
					(font
						(size 1.27 1.27)
					)
					(justify left bottom)
					(hide yes)
				)
			)
			(property "MPN" "AK3LPHEF1-156.2500T"
				(at 20.32 -12.7 0)
				(effects
					(font
						(size 1.27 1.27)
						(thickness 0.15)
					)
					(justify left bottom)
				)
			)
			(property "Manufacturer" "Abracon"
				(at 20.32 -17.78 0)
				(effects
					(font
						(size 1.27 1.27)
						(thickness 0.15)
					)
					(justify left bottom)
					(hide yes)
				)
			)
			(property "Val" "156.25MHz"
				(at 20.32 -15.24 0)
				(effects
					(font
						(size 1.27 1.27)
						(thickness 0.15)
					)
					(justify left bottom)
				)
			)
			(property "Author" "Antmicro"
				(at 20.32 -27.94 0)
				(effects
					(font
						(size 1.27 1.27)
						(thickness 0.15)
					)
					(justify left bottom)
					(hide yes)
				)
			)
			(property "License" "Apache-2.0"
				(at 20.32 -30.48 0)
				(effects
					(font
						(size 1.27 1.27)
						(thickness 0.15)
					)
					(justify left bottom)
					(hide yes)
				)
			)
			(property "ki_keywords" "OSCILLATOR, SMT"
				(at 0 0 0)
				(effects
					(font
						(size 1.27 1.27)
					)
					(hide yes)
				)
			)
			(symbol "Oscillator_156.25MHz_AK3LPHEF1_1_1"
				(rectangle
					(start 2.54 2.54)
					(end 16.51 -7.62)
					(stroke
						(width 0.254)
						(type default)
					)
					(fill
						(type background)
					)
				)
				(polyline
					(pts
						(xy 7.62 -1.27) (xy 8.255 -1.27) (xy 8.255 0) (xy 8.89 0) (xy 8.89 -1.27) (xy 9.525 -1.27) (xy 9.525 0)
						(xy 10.16 0) (xy 10.16 -1.27)
					)
					(stroke
						(width 0.254)
						(type default)
					)
					(fill
						(type background)
					)
				)
				(pin power_in line
					(at 0 0 0)
					(length 2.54)
					(name "VCC"
						(effects
							(font
								(size 1.27 1.27)
							)
						)
					)
					(number "6"
						(effects
							(font
								(size 1.27 1.27)
							)
						)
					)
				)
				(pin input line
					(at 0 -2.54 0)
					(length 2.54)
					(name "EN"
						(effects
							(font
								(size 1.27 1.27)
							)
						)
					)
					(number "1"
						(effects
							(font
								(size 1.27 1.27)
							)
						)
					)
				)
				(pin power_in line
					(at 0 -5.08 0)
					(length 2.54)
					(name "GND"
						(effects
							(font
								(size 1.27 1.27)
							)
						)
					)
					(number "3"
						(effects
							(font
								(size 1.27 1.27)
							)
						)
					)
				)
				(pin no_connect line
					(at 16.51 -5.08 180)
					(length 2.54)
					(hide yes)
					(name "NC"
						(effects
							(font
								(size 1.27 1.27)
							)
						)
					)
					(number "2"
						(effects
							(font
								(size 1.27 1.27)
							)
						)
					)
				)
				(pin output line
					(at 19.05 0 180)
					(length 2.54)
					(name "OUT+"
						(effects
							(font
								(size 1.27 1.27)
							)
						)
					)
					(number "4"
						(effects
							(font
								(size 1.27 1.27)
							)
						)
					)
				)
				(pin output line
					(at 19.05 -2.54 180)
					(length 2.54)
					(name "OUT-"
						(effects
							(font
								(size 1.27 1.27)
							)
						)
					)
					(number "5"
						(effects
							(font
								(size 1.27 1.27)
							)
						)
					)
				)
			)
		)
	(symbol "antmicroOscillators:Oscillator_25MHz_ESC_2016MV"
			(exclude_from_sim no)
			(in_bom yes)
			(on_board yes)
			(property "Reference" "Y"
				(at 25.4 -2.54 0)
				(effects
					(font
						(size 1.27 1.27)
						(thickness 0.15)
					)
					(justify left bottom)
				)
			)
			(property "Value" "Oscillator_25MHz_ESC_2016MV"
				(at 25.4 -12.7 0)
				(effects
					(font
						(size 1.27 1.27)
						(thickness 0.15)
					)
					(justify left bottom)
					(hide yes)
				)
			)
			(property "Footprint" "antmicro-footprints:Oscillator_SMD_ECS_2016MV_2x1.6x0.85mm"
				(at 25.4 -15.24 0)
				(effects
					(font
						(size 1.27 1.27)
						(thickness 0.15)
					)
					(justify left bottom)
					(hide yes)
				)
			)
			(property "Datasheet" "https://ecsxtal.com/store/pdf/ECS-2016MV.pdf"
				(at 25.4 -17.78 0)
				(effects
					(font
						(size 1.27 1.27)
						(thickness 0.15)
					)
					(justify left bottom)
					(hide yes)
				)
			)
			(property "Description" "Oscillator, 25 MHz, HCMOS, SMD, 2mm x 1.6mm, MultiVolt ECS-2016MV Series"
				(at 25.4 -25.4 0)
				(effects
					(font
						(size 1.27 1.27)
					)
					(justify left bottom)
					(hide yes)
				)
			)
			(property "MPN" "ECS-2016MV-250-CN-TR"
				(at 25.4 -5.08 0)
				(effects
					(font
						(size 1.27 1.27)
						(thickness 0.15)
					)
					(justify left bottom)
				)
			)
			(property "Manufacturer" "ECS Inc. International"
				(at 25.4 -7.62 0)
				(effects
					(font
						(size 1.27 1.27)
						(thickness 0.15)
					)
					(justify left bottom)
					(hide yes)
				)
			)
			(property "Val" "25 MHz"
				(at 25.4 -10.16 0)
				(effects
					(font
						(size 1.27 1.27)
						(thickness 0.15)
					)
					(justify left bottom)
				)
			)
			(property "Author" "Antmicro"
				(at 25.4 -20.32 0)
				(effects
					(font
						(size 1.27 1.27)
						(thickness 0.15)
					)
					(justify left bottom)
					(hide yes)
				)
			)
			(property "License" "Apache-2.0"
				(at 25.4 -22.86 0)
				(effects
					(font
						(size 1.27 1.27)
						(thickness 0.15)
					)
					(justify left bottom)
					(hide yes)
				)
			)
			(property "ki_keywords" "OSCILLATOR"
				(at 0 0 0)
				(effects
					(font
						(size 1.27 1.27)
					)
					(hide yes)
				)
			)
			(symbol "Oscillator_25MHz_ESC_2016MV_1_1"
				(rectangle
					(start 2.54 2.54)
					(end 16.51 -7.62)
					(stroke
						(width 0.254)
						(type default)
					)
					(fill
						(type background)
					)
				)
				(polyline
					(pts
						(xy 7.62 -1.27) (xy 8.255 -1.27) (xy 8.255 0) (xy 8.89 0) (xy 8.89 -1.27) (xy 9.525 -1.27) (xy 9.525 0)
						(xy 10.16 0) (xy 10.16 -1.27)
					)
					(stroke
						(width 0.254)
						(type default)
					)
					(fill
						(type background)
					)
				)
				(pin power_in line
					(at 0 0 0)
					(length 2.54)
					(name "VDD"
						(effects
							(font
								(size 1.27 1.27)
							)
						)
					)
					(number "4"
						(effects
							(font
								(size 1.27 1.27)
							)
						)
					)
				)
				(pin input line
					(at 0 -2.54 0)
					(length 2.54)
					(name "EN"
						(effects
							(font
								(size 1.27 1.27)
							)
						)
					)
					(number "1"
						(effects
							(font
								(size 1.27 1.27)
							)
						)
					)
				)
				(pin power_in line
					(at 0 -5.08 0)
					(length 2.54)
					(name "GND"
						(effects
							(font
								(size 1.27 1.27)
							)
						)
					)
					(number "2"
						(effects
							(font
								(size 1.27 1.27)
							)
						)
					)
				)
				(pin output line
					(at 19.05 0 180)
					(length 2.54)
					(name "OUT"
						(effects
							(font
								(size 1.27 1.27)
							)
						)
					)
					(number "3"
						(effects
							(font
								(size 1.27 1.27)
							)
						)
					)
				)
			)
		)
	(symbol "antmicroOscillators:Oscillator_32.768kHz_ECS_2520MV"
			(exclude_from_sim no)
			(in_bom yes)
			(on_board yes)
			(property "Reference" "Y"
				(at 26.035 -2.54 0)
				(effects
					(font
						(size 1.27 1.27)
						(thickness 0.15)
					)
					(justify left bottom)
				)
			)
			(property "Value" "Oscillator_32.768kHz_ECS_2520MV"
				(at 26.035 -12.7 0)
				(effects
					(font
						(size 1.27 1.27)
						(thickness 0.15)
					)
					(justify left bottom)
					(hide yes)
				)
			)
			(property "Footprint" "antmicro-footprints:Oscillator_SMD_ECS_2520MV_2.5x2mm"
				(at 26.035 -15.24 0)
				(effects
					(font
						(size 1.27 1.27)
						(thickness 0.15)
					)
					(justify left bottom)
					(hide yes)
				)
			)
			(property "Datasheet" "https://ecsxtal.com/store/pdf/ECS-327MVATX.pdf"
				(at 26.035 -17.78 0)
				(effects
					(font
						(size 1.27 1.27)
						(thickness 0.15)
					)
					(justify left bottom)
					(hide yes)
				)
			)
			(property "Description" "32.768 kHz XO (Standard) CMOS Oscillator 1.6V ~ 3.6V Enable/Disable 4-SMD, No Lead"
				(at 26.035 -25.4 0)
				(effects
					(font
						(size 1.27 1.27)
					)
					(justify left bottom)
					(hide yes)
				)
			)
			(property "Manufacturer" "ECS Inc. International"
				(at 26.035 -7.62 0)
				(effects
					(font
						(size 1.27 1.27)
						(thickness 0.15)
					)
					(justify left bottom)
					(hide yes)
				)
			)
			(property "MPN" "ECS-327MVATX-2-CN-TR3"
				(at 26.035 -5.08 0)
				(effects
					(font
						(size 1.27 1.27)
						(thickness 0.15)
					)
					(justify left bottom)
				)
			)
			(property "Val" "32.768 kHz"
				(at 26.035 -10.16 0)
				(effects
					(font
						(size 1.27 1.27)
						(thickness 0.15)
					)
					(justify left bottom)
				)
			)
			(property "Author" "Antmicro"
				(at 26.035 -20.32 0)
				(effects
					(font
						(size 1.27 1.27)
						(thickness 0.15)
					)
					(justify left bottom)
					(hide yes)
				)
			)
			(property "License" "Apache-2.0"
				(at 26.035 -22.86 0)
				(effects
					(font
						(size 1.27 1.27)
						(thickness 0.15)
					)
					(justify left bottom)
					(hide yes)
				)
			)
			(property "ki_keywords" "OSCILLATOR"
				(at 0 0 0)
				(effects
					(font
						(size 1.27 1.27)
					)
					(hide yes)
				)
			)
			(symbol "Oscillator_32.768kHz_ECS_2520MV_1_1"
				(rectangle
					(start 2.54 2.54)
					(end 16.51 -7.62)
					(stroke
						(width 0.254)
						(type default)
					)
					(fill
						(type background)
					)
				)
				(polyline
					(pts
						(xy 7.62 -1.27) (xy 8.255 -1.27) (xy 8.255 0) (xy 8.89 0) (xy 8.89 -1.27) (xy 9.525 -1.27) (xy 9.525 0)
						(xy 10.16 0) (xy 10.16 -1.27)
					)
					(stroke
						(width 0.254)
						(type default)
					)
					(fill
						(type background)
					)
				)
				(pin power_in line
					(at 0 0 0)
					(length 2.54)
					(name "VDD"
						(effects
							(font
								(size 1.27 1.27)
							)
						)
					)
					(number "4"
						(effects
							(font
								(size 1.27 1.27)
							)
						)
					)
				)
				(pin input line
					(at 0 -2.54 0)
					(length 2.54)
					(name "EN"
						(effects
							(font
								(size 1.27 1.27)
							)
						)
					)
					(number "1"
						(effects
							(font
								(size 1.27 1.27)
							)
						)
					)
				)
				(pin power_in line
					(at 0 -5.08 0)
					(length 2.54)
					(name "GND"
						(effects
							(font
								(size 1.27 1.27)
							)
						)
					)
					(number "2"
						(effects
							(font
								(size 1.27 1.27)
							)
						)
					)
				)
				(pin output line
					(at 19.05 0 180)
					(length 2.54)
					(name "OUT"
						(effects
							(font
								(size 1.27 1.27)
							)
						)
					)
					(number "3"
						(effects
							(font
								(size 1.27 1.27)
							)
						)
					)
				)
			)
		)
	(symbol "antmicroOverUnderVoltageProtection:MAX16013"
			(exclude_from_sim no)
			(in_bom yes)
			(on_board yes)
			(property "Reference" "U"
				(at 35.56 -2.54 0)
				(effects
					(font
						(size 1.27 1.27)
						(thickness 0.15)
					)
					(justify left bottom)
				)
			)
			(property "Value" "MAX16013"
				(at 35.56 -7.62 0)
				(effects
					(font
						(size 1.27 1.27)
						(thickness 0.15)
					)
					(justify left bottom)
					(hide yes)
				)
			)
			(property "Footprint" "antmicro-footprints:TDFN-6-1EP_3x3mm_P0.95mm"
				(at 35.56 -10.16 0)
				(effects
					(font
						(size 1.27 1.27)
						(thickness 0.15)
					)
					(justify left bottom)
					(hide yes)
				)
			)
			(property "Datasheet" "https://www.analog.com/media/en/technical-documentation/data-sheets/max16010-max16014.pdf"
				(at 35.56 -12.7 0)
				(effects
					(font
						(size 1.27 1.27)
						(thickness 0.15)
					)
					(justify left bottom)
					(hide yes)
				)
			)
			(property "Description" "Over voltage, reverse voltage protection"
				(at 35.56 -15.24 0)
				(effects
					(font
						(size 1.27 1.27)
						(thickness 0.15)
					)
					(justify left bottom)
					(hide yes)
				)
			)
			(property "Manufacturer" "Analog Devices"
				(at 35.56 -17.78 0)
				(effects
					(font
						(size 1.27 1.27)
						(thickness 0.15)
					)
					(justify left bottom)
					(hide yes)
				)
			)
			(property "MPN" "MAX16013TT-T"
				(at 35.56 -5.08 0)
				(effects
					(font
						(size 1.27 1.27)
						(thickness 0.15)
					)
					(justify left bottom)
				)
			)
			(property "Author" "Antmicro"
				(at 35.56 -20.32 0)
				(effects
					(font
						(size 1.27 1.27)
						(thickness 0.15)
					)
					(justify left bottom)
					(hide yes)
				)
			)
			(property "License" "Apache-2.0"
				(at 35.56 -22.86 0)
				(effects
					(font
						(size 1.27 1.27)
						(thickness 0.15)
					)
					(justify left bottom)
					(hide yes)
				)
			)
			(property "ki_keywords" "IC, SMT"
				(at 0 0 0)
				(effects
					(font
						(size 1.27 1.27)
					)
					(hide yes)
				)
			)
			(symbol "MAX16013_1_1"
				(rectangle
					(start 2.54 2.54)
					(end 15.24 -7.62)
					(stroke
						(width 0.254)
						(type solid)
					)
					(fill
						(type background)
					)
				)
				(pin power_in line
					(at 0 0 0)
					(length 2.54)
					(name "VCC"
						(effects
							(font
								(size 1.27 1.27)
							)
						)
					)
					(number "1"
						(effects
							(font
								(size 1.27 1.27)
							)
						)
					)
				)
				(pin output line
					(at 0 -2.54 0)
					(length 2.54)
					(name "GATE1"
						(effects
							(font
								(size 1.27 1.27)
							)
						)
					)
					(number "6"
						(effects
							(font
								(size 1.27 1.27)
							)
						)
					)
				)
				(pin input line
					(at 0 -5.08 0)
					(length 2.54)
					(name "EN"
						(effects
							(font
								(size 1.27 1.27)
							)
						)
					)
					(number "5"
						(effects
							(font
								(size 1.27 1.27)
							)
						)
					)
				)
				(pin output line
					(at 17.78 0 180)
					(length 2.54)
					(name "GATE2"
						(effects
							(font
								(size 1.27 1.27)
							)
						)
					)
					(number "3"
						(effects
							(font
								(size 1.27 1.27)
							)
						)
					)
				)
				(pin input line
					(at 17.78 -2.54 180)
					(length 2.54)
					(name "SET"
						(effects
							(font
								(size 1.27 1.27)
							)
						)
					)
					(number "4"
						(effects
							(font
								(size 1.27 1.27)
							)
						)
					)
				)
				(pin power_in line
					(at 17.78 -5.08 180)
					(length 2.54)
					(name "GND"
						(effects
							(font
								(size 1.27 1.27)
							)
						)
					)
					(number "2"
						(effects
							(font
								(size 1.27 1.27)
							)
						)
					)
				)
				(pin power_in line
					(at 17.78 -5.08 180)
					(length 2.54)
					(hide yes)
					(name "GND"
						(effects
							(font
								(size 1.27 1.27)
							)
						)
					)
					(number "7"
						(effects
							(font
								(size 1.27 1.27)
							)
						)
					)
				)
			)
		)
	(symbol "antmicroPMICORControllersIdealDiodes:LTC4412IS6"
			(exclude_from_sim no)
			(in_bom yes)
			(on_board yes)
			(property "Reference" "U"
				(at 31.75 -2.54 0)
				(effects
					(font
						(size 1.27 1.27)
						(thickness 0.15)
					)
					(justify left bottom)
				)
			)
			(property "Value" "LTC4412IS6"
				(at 31.75 -5.08 0)
				(effects
					(font
						(size 1.27 1.27)
						(thickness 0.15)
					)
					(justify left bottom)
					(hide yes)
				)
			)
			(property "Footprint" "antmicro-footprints:SOT-23-6"
				(at 31.75 -7.62 0)
				(effects
					(font
						(size 1.27 1.27)
						(thickness 0.15)
					)
					(justify left bottom)
					(hide yes)
				)
			)
			(property "Datasheet" "https://www.analog.com/media/en/technical-documentation/data-sheets/4412fb.pdf"
				(at 31.75 -10.16 0)
				(effects
					(font
						(size 1.27 1.27)
						(thickness 0.15)
					)
					(justify left bottom)
					(hide yes)
				)
			)
			(property "Description" "Ideal diode controller"
				(at 31.75 -22.86 0)
				(effects
					(font
						(size 1.27 1.27)
					)
					(justify left bottom)
					(hide yes)
				)
			)
			(property "MPN" "LTC4412IS6#TRMPBF"
				(at 31.75 -12.7 0)
				(effects
					(font
						(size 1.27 1.27)
						(thickness 0.15)
					)
					(justify left bottom)
				)
			)
			(property "Manufacturer" "Analog Devices"
				(at 31.75 -15.24 0)
				(effects
					(font
						(size 1.27 1.27)
						(thickness 0.15)
					)
					(justify left bottom)
					(hide yes)
				)
			)
			(property "Author" "Antmicro"
				(at 31.75 -17.78 0)
				(effects
					(font
						(size 1.27 1.27)
						(thickness 0.15)
					)
					(justify left bottom)
					(hide yes)
				)
			)
			(property "License" "Apache-2.0"
				(at 31.75 -20.32 0)
				(effects
					(font
						(size 1.27 1.27)
						(thickness 0.15)
					)
					(justify left bottom)
					(hide yes)
				)
			)
			(property "ki_keywords" "SMT, CONTROLLER, IC, DIODE"
				(at 0 0 0)
				(effects
					(font
						(size 1.27 1.27)
					)
					(hide yes)
				)
			)
			(symbol "LTC4412IS6_1_1"
				(rectangle
					(start 2.54 2.54)
					(end 15.24 -7.62)
					(stroke
						(width 0.254)
						(type default)
					)
					(fill
						(type background)
					)
				)
				(pin power_in line
					(at 0 0 0)
					(length 2.54)
					(name "IN"
						(effects
							(font
								(size 1.27 1.27)
							)
						)
					)
					(number "1"
						(effects
							(font
								(size 1.27 1.27)
							)
						)
					)
				)
				(pin input line
					(at 0 -2.54 0)
					(length 2.54)
					(name "CTL"
						(effects
							(font
								(size 1.27 1.27)
							)
						)
					)
					(number "3"
						(effects
							(font
								(size 1.27 1.27)
							)
						)
					)
				)
				(pin power_in line
					(at 0 -5.08 0)
					(length 2.54)
					(name "GND"
						(effects
							(font
								(size 1.27 1.27)
							)
						)
					)
					(number "2"
						(effects
							(font
								(size 1.27 1.27)
							)
						)
					)
				)
				(pin input line
					(at 17.78 0 180)
					(length 2.54)
					(name "SENSE"
						(effects
							(font
								(size 1.27 1.27)
							)
						)
					)
					(number "6"
						(effects
							(font
								(size 1.27 1.27)
							)
						)
					)
				)
				(pin output line
					(at 17.78 -2.54 180)
					(length 2.54)
					(name "GATE"
						(effects
							(font
								(size 1.27 1.27)
							)
						)
					)
					(number "5"
						(effects
							(font
								(size 1.27 1.27)
							)
						)
					)
				)
				(pin output line
					(at 17.78 -5.08 180)
					(length 2.54)
					(name "STAT"
						(effects
							(font
								(size 1.27 1.27)
							)
						)
					)
					(number "4"
						(effects
							(font
								(size 1.27 1.27)
							)
						)
					)
				)
			)
		)
	(symbol "antmicroPMICPowerDistributionSwitchesLoadDrivers:AP22615A_TSOT26"
			(exclude_from_sim no)
			(in_bom yes)
			(on_board yes)
			(property "Reference" "U"
				(at 30.48 -2.54 0)
				(effects
					(font
						(size 1.27 1.27)
						(thickness 0.15)
					)
					(justify left bottom)
				)
			)
			(property "Value" "AP22615A_TSOT26"
				(at 30.48 -5.08 0)
				(effects
					(font
						(size 1.27 1.27)
						(thickness 0.15)
					)
					(justify left bottom)
					(hide yes)
				)
			)
			(property "Footprint" "antmicro-footprints:TSOT23-6"
				(at 30.48 -7.62 0)
				(effects
					(font
						(size 1.27 1.27)
						(thickness 0.15)
					)
					(justify left bottom)
					(hide yes)
				)
			)
			(property "Datasheet" "https://www.mouser.com/datasheet/2/115/DIOD_S_A0008958405_1-2543193.pdf"
				(at 30.48 -10.16 0)
				(effects
					(font
						(size 1.27 1.27)
						(thickness 0.15)
					)
					(justify left bottom)
					(hide yes)
				)
			)
			(property "Description" "Power Load Distribution Switch, High Side, Active High, 1 Output, 5.5 V, 3.6 A, 0.04 ohm, TSOT-26-6"
				(at 30.48 -22.86 0)
				(effects
					(font
						(size 1.27 1.27)
					)
					(justify left bottom)
					(hide yes)
				)
			)
			(property "MPN" "AP22615AWU-7"
				(at 30.48 -12.7 0)
				(effects
					(font
						(size 1.27 1.27)
						(thickness 0.15)
					)
					(justify left bottom)
				)
			)
			(property "Manufacturer" "Diodes Incorporated"
				(at 30.48 -15.24 0)
				(effects
					(font
						(size 1.27 1.27)
						(thickness 0.15)
					)
					(justify left bottom)
					(hide yes)
				)
			)
			(property "Author" "Antmicro"
				(at 30.48 -17.78 0)
				(effects
					(font
						(size 1.27 1.27)
						(thickness 0.15)
					)
					(justify left bottom)
					(hide yes)
				)
			)
			(property "License" "Apache-2.0"
				(at 30.48 -20.32 0)
				(effects
					(font
						(size 1.27 1.27)
						(thickness 0.15)
					)
					(justify left bottom)
					(hide yes)
				)
			)
			(property "ki_keywords" "SMT, PMIC, IC, VOLTAGE"
				(at 0 0 0)
				(effects
					(font
						(size 1.27 1.27)
					)
					(hide yes)
				)
			)
			(symbol "AP22615A_TSOT26_1_1"
				(rectangle
					(start 2.54 2.54)
					(end 12.7 -7.62)
					(stroke
						(width 0.254)
						(type default)
					)
					(fill
						(type background)
					)
				)
				(pin power_in line
					(at 0 0 0)
					(length 2.54)
					(name "IN"
						(effects
							(font
								(size 1.27 1.27)
							)
						)
					)
					(number "6"
						(effects
							(font
								(size 1.27 1.27)
							)
						)
					)
				)
				(pin output line
					(at 0 -2.54 0)
					(length 2.54)
					(name "FLG"
						(effects
							(font
								(size 1.27 1.27)
							)
						)
					)
					(number "3"
						(effects
							(font
								(size 1.27 1.27)
							)
						)
					)
				)
				(pin input line
					(at 0 -5.08 0)
					(length 2.54)
					(name "EN"
						(effects
							(font
								(size 1.27 1.27)
							)
						)
					)
					(number "4"
						(effects
							(font
								(size 1.27 1.27)
							)
						)
					)
				)
				(pin power_out line
					(at 15.24 0 180)
					(length 2.54)
					(name "OUT"
						(effects
							(font
								(size 1.27 1.27)
							)
						)
					)
					(number "1"
						(effects
							(font
								(size 1.27 1.27)
							)
						)
					)
				)
				(pin passive line
					(at 15.24 -2.54 180)
					(length 2.54)
					(name "ISET"
						(effects
							(font
								(size 1.27 1.27)
							)
						)
					)
					(number "5"
						(effects
							(font
								(size 1.27 1.27)
							)
						)
					)
				)
				(pin power_in line
					(at 15.24 -5.08 180)
					(length 2.54)
					(name "GND"
						(effects
							(font
								(size 1.27 1.27)
							)
						)
					)
					(number "2"
						(effects
							(font
								(size 1.27 1.27)
							)
						)
					)
				)
			)
		)
	(symbol "antmicroPMICPowerSequencers:MAX16150A_SOT"
			(exclude_from_sim no)
			(in_bom yes)
			(on_board yes)
			(property "Reference" "U"
				(at 31.75 -3.81 0)
				(effects
					(font
						(size 1.27 1.27)
						(thickness 0.15)
					)
					(justify left bottom)
				)
			)
			(property "Value" "MAX16150A_SOT"
				(at 31.75 -6.35 0)
				(effects
					(font
						(size 1.27 1.27)
						(thickness 0.15)
					)
					(justify left bottom)
					(hide yes)
				)
			)
			(property "Footprint" "antmicro-footprints:SOT-23-6"
				(at 31.75 -8.89 0)
				(effects
					(font
						(size 1.27 1.27)
						(thickness 0.15)
					)
					(justify left bottom)
					(hide yes)
				)
			)
			(property "Datasheet" "https://datasheets.maximintegrated.com/en/ds/MAX16150.pdf"
				(at 31.75 -11.43 0)
				(effects
					(font
						(size 1.27 1.27)
						(thickness 0.15)
					)
					(justify left bottom)
					(hide yes)
				)
			)
			(property "Description" "Pushbutton On/Off Controller, Latched Output, 1.3 to 5.5 V Supply, 50 ms Debounce Time, SOT-23-6"
				(at 31.75 -24.13 0)
				(effects
					(font
						(size 1.27 1.27)
					)
					(justify left bottom)
					(hide yes)
				)
			)
			(property "Manufacturer" "Maxim Integrated Products"
				(at 31.75 -13.97 0)
				(effects
					(font
						(size 1.27 1.27)
						(thickness 0.15)
					)
					(justify left bottom)
					(hide yes)
				)
			)
			(property "MPN" "MAX16150AUT+T"
				(at 31.75 -16.51 0)
				(effects
					(font
						(size 1.27 1.27)
						(thickness 0.15)
					)
					(justify left bottom)
				)
			)
			(property "License" "Apache-2.0"
				(at 31.75 -19.05 0)
				(effects
					(font
						(size 1.27 1.27)
						(thickness 0.15)
					)
					(justify left bottom)
					(hide yes)
				)
			)
			(property "Author" "Antmicro"
				(at 31.75 -21.59 0)
				(effects
					(font
						(size 1.27 1.27)
						(thickness 0.15)
					)
					(justify left bottom)
					(hide yes)
				)
			)
			(property "ki_keywords" "SMT, PMIC, IC, CONTROLLER, ESD"
				(at 0 0 0)
				(effects
					(font
						(size 1.27 1.27)
					)
					(hide yes)
				)
			)
			(symbol "MAX16150A_SOT_0_0"
				(text "CTRL"
					(at 8.89 -0.254 0)
					(effects
						(font
							(size 0.635 0.635)
						)
					)
				)
			)
			(symbol "MAX16150A_SOT_1_1"
				(rectangle
					(start 2.54 2.54)
					(end 15.24 -7.62)
					(stroke
						(width 0.254)
						(type default)
					)
					(fill
						(type background)
					)
				)
				(polyline
					(pts
						(xy 6.35 -3.429) (xy 7.112 -3.429)
					)
					(stroke
						(width 0.254)
						(type default)
					)
					(fill
						(type background)
					)
				)
				(polyline
					(pts
						(xy 7.112 -2.54) (xy 10.668 -2.54)
					)
					(stroke
						(width 0.254)
						(type default)
					)
					(fill
						(type background)
					)
				)
				(circle
					(center 7.366 -3.429)
					(radius 0.254)
					(stroke
						(width 0.254)
						(type default)
					)
					(fill
						(type outline)
					)
				)
				(polyline
					(pts
						(xy 7.874 -1.016) (xy 9.906 -1.016)
					)
					(stroke
						(width 0.254)
						(type default)
					)
					(fill
						(type background)
					)
				)
				(polyline
					(pts
						(xy 8.89 -2.54) (xy 8.89 -1.016)
					)
					(stroke
						(width 0.254)
						(type default)
					)
					(fill
						(type background)
					)
				)
				(circle
					(center 10.414 -3.429)
					(radius 0.254)
					(stroke
						(width 0.254)
						(type default)
					)
					(fill
						(type outline)
					)
				)
				(polyline
					(pts
						(xy 11.43 -3.429) (xy 10.668 -3.429)
					)
					(stroke
						(width 0.254)
						(type default)
					)
					(fill
						(type background)
					)
				)
				(pin power_in line
					(at 0 0 0)
					(length 2.54)
					(name "VCC"
						(effects
							(font
								(size 1.27 1.27)
							)
						)
					)
					(number "3"
						(effects
							(font
								(size 1.27 1.27)
							)
						)
					)
				)
				(pin input line
					(at 0 -2.54 0)
					(length 2.54)
					(name "~{CLR}"
						(effects
							(font
								(size 1.27 1.27)
							)
						)
					)
					(number "6"
						(effects
							(font
								(size 1.27 1.27)
							)
						)
					)
				)
				(pin input line
					(at 0 -5.08 0)
					(length 2.54)
					(name "~{PB_IN}"
						(effects
							(font
								(size 1.27 1.27)
							)
						)
					)
					(number "1"
						(effects
							(font
								(size 1.27 1.27)
							)
						)
					)
				)
				(pin output line
					(at 17.78 0 180)
					(length 2.54)
					(name "OUT"
						(effects
							(font
								(size 1.27 1.27)
							)
						)
					)
					(number "4"
						(effects
							(font
								(size 1.27 1.27)
							)
						)
					)
				)
				(pin output line
					(at 17.78 -2.54 180)
					(length 2.54)
					(name "~{INT}"
						(effects
							(font
								(size 1.27 1.27)
							)
						)
					)
					(number "5"
						(effects
							(font
								(size 1.27 1.27)
							)
						)
					)
				)
				(pin power_in line
					(at 17.78 -5.08 180)
					(length 2.54)
					(name "GND"
						(effects
							(font
								(size 1.27 1.27)
							)
						)
					)
					(number "2"
						(effects
							(font
								(size 1.27 1.27)
							)
						)
					)
				)
			)
		)
	(symbol "antmicroPMICPowerSequencers:TPS3840PL30DBVR"
			(exclude_from_sim no)
			(in_bom yes)
			(on_board yes)
			(property "Reference" "U"
				(at 38.1 -1.27 0)
				(effects
					(font
						(size 1.27 1.27)
						(thickness 0.15)
					)
					(justify left bottom)
				)
			)
			(property "Value" "TPS3840PL30DBVR"
				(at 38.1 -13.97 0)
				(effects
					(font
						(size 1.27 1.27)
						(thickness 0.15)
					)
					(justify left bottom)
					(hide yes)
				)
			)
			(property "Footprint" "antmicro-footprints:SOT-23-5"
				(at 38.1 -6.35 0)
				(effects
					(font
						(size 1.27 1.27)
						(thickness 0.15)
					)
					(justify left bottom)
					(hide yes)
				)
			)
			(property "Datasheet" "https://www.ti.com/lit/ds/symlink/tps3840.pdf?HQS=dis-mous-null-mousermode-dsf-pf-null-wwe&DCM=yes&ref_url=https%3A%2F%2Fwww.mouser.com%2F&distId=26"
				(at 38.1 -8.89 0)
				(effects
					(font
						(size 1.27 1.27)
						(thickness 0.15)
					)
					(justify left bottom)
					(hide yes)
				)
			)
			(property "Description" "Voltage supervisor"
				(at 38.1 -21.59 0)
				(effects
					(font
						(size 1.27 1.27)
					)
					(justify left bottom)
					(hide yes)
				)
			)
			(property "Manufacturer" "Texas Instruments"
				(at 38.1 -11.43 0)
				(effects
					(font
						(size 1.27 1.27)
						(thickness 0.15)
					)
					(justify left bottom)
					(hide yes)
				)
			)
			(property "MPN" "TPS3840PL30DBVR"
				(at 38.1 -3.81 0)
				(effects
					(font
						(size 1.27 1.27)
						(thickness 0.15)
					)
					(justify left bottom)
				)
			)
			(property "Author" "Antmicro"
				(at 38.1 -16.51 0)
				(effects
					(font
						(size 1.27 1.27)
						(thickness 0.15)
					)
					(justify left bottom)
					(hide yes)
				)
			)
			(property "License" "Apache-2.0"
				(at 38.1 -19.05 0)
				(effects
					(font
						(size 1.27 1.27)
						(thickness 0.15)
					)
					(justify left bottom)
					(hide yes)
				)
			)
			(property "ki_keywords" "SMT, PMIC, IC, CONTROLLER"
				(at 0 0 0)
				(effects
					(font
						(size 1.27 1.27)
					)
					(hide yes)
				)
			)
			(property "ki_fp_filters" "DBV0005A_N DBV0005A_M DBV0005A_L"
				(at 0 0 0)
				(effects
					(font
						(size 1.27 1.27)
					)
					(hide yes)
				)
			)
			(symbol "TPS3840PL30DBVR_1_1"
				(rectangle
					(start 2.54 2.54)
					(end 15.24 -7.62)
					(stroke
						(width 0.254)
						(type default)
					)
					(fill
						(type background)
					)
				)
				(pin power_in line
					(at 0 0 0)
					(length 2.54)
					(name "VDD"
						(effects
							(font
								(size 1.27 1.27)
							)
						)
					)
					(number "2"
						(effects
							(font
								(size 1.27 1.27)
							)
						)
					)
				)
				(pin input line
					(at 0 -2.54 0)
					(length 2.54)
					(name "~{MR}"
						(effects
							(font
								(size 1.27 1.27)
							)
						)
					)
					(number "4"
						(effects
							(font
								(size 1.27 1.27)
							)
						)
					)
				)
				(pin passive line
					(at 0 -5.08 0)
					(length 2.54)
					(name "CT"
						(effects
							(font
								(size 1.27 1.27)
							)
						)
					)
					(number "5"
						(effects
							(font
								(size 1.27 1.27)
							)
						)
					)
				)
				(pin output line
					(at 17.78 0 180)
					(length 2.54)
					(name "~{RESET}"
						(effects
							(font
								(size 1.27 1.27)
							)
						)
					)
					(number "1"
						(effects
							(font
								(size 1.27 1.27)
							)
						)
					)
				)
				(pin power_in line
					(at 17.78 -5.08 180)
					(length 2.54)
					(name "GND"
						(effects
							(font
								(size 1.27 1.27)
							)
						)
					)
					(number "3"
						(effects
							(font
								(size 1.27 1.27)
							)
						)
					)
				)
			)
		)
	(symbol "antmicroPMICVoltageRegulatorsLinear:LD39100PUR"
			(exclude_from_sim no)
			(in_bom yes)
			(on_board yes)
			(property "Reference" "U"
				(at 30.48 -2.54 0)
				(effects
					(font
						(size 1.27 1.27)
						(thickness 0.15)
					)
					(justify left bottom)
				)
			)
			(property "Value" "LD39100PUR"
				(at 30.48 -7.62 0)
				(effects
					(font
						(size 1.27 1.27)
						(thickness 0.15)
					)
					(justify left bottom)
					(hide yes)
				)
			)
			(property "Footprint" "antmicro-footprints:DFN-6-1EP_3x3mm_P1mm_EP1.5x2.4mm"
				(at 30.48 -10.16 0)
				(effects
					(font
						(size 1.27 1.27)
						(thickness 0.15)
					)
					(justify left bottom)
					(hide yes)
				)
			)
			(property "Datasheet" "https://eu.mouser.com/datasheet/2/389/ld39100-1849679.pdf"
				(at 30.48 -12.7 0)
				(effects
					(font
						(size 1.27 1.27)
						(thickness 0.15)
					)
					(justify left bottom)
					(hide yes)
				)
			)
			(property "Description" "LDO Voltage Regulator 1A Low Quiescent Reg 1.5 to 5.5 V 200mV"
				(at 30.48 -22.86 0)
				(effects
					(font
						(size 1.27 1.27)
					)
					(justify left bottom)
					(hide yes)
				)
			)
			(property "MPN" "LD39100PUR"
				(at 30.48 -5.08 0)
				(effects
					(font
						(size 1.27 1.27)
						(thickness 0.15)
					)
					(justify left bottom)
				)
			)
			(property "Manufacturer" "STMicroelectronics"
				(at 30.48 -15.24 0)
				(effects
					(font
						(size 1.27 1.27)
						(thickness 0.15)
					)
					(justify left bottom)
					(hide yes)
				)
			)
			(property "Author" "Antmicro"
				(at 30.48 -17.78 0)
				(effects
					(font
						(size 1.27 1.27)
						(thickness 0.15)
					)
					(justify left bottom)
					(hide yes)
				)
			)
			(property "License" "Apache-2.0"
				(at 30.48 -20.32 0)
				(effects
					(font
						(size 1.27 1.27)
						(thickness 0.15)
					)
					(justify left bottom)
					(hide yes)
				)
			)
			(property "ki_keywords" "SMT, PMIC, IC, LDO, VOLTAGE, REGULATOR"
				(at 0 0 0)
				(effects
					(font
						(size 1.27 1.27)
					)
					(hide yes)
				)
			)
			(symbol "LD39100PUR_1_1"
				(rectangle
					(start 2.54 2.54)
					(end 12.7 -7.62)
					(stroke
						(width 0.254)
						(type default)
					)
					(fill
						(type background)
					)
				)
				(pin power_in line
					(at 0 0 0)
					(length 2.54)
					(name "V_{IN}"
						(effects
							(font
								(size 1.27 1.27)
							)
						)
					)
					(number "6"
						(effects
							(font
								(size 1.27 1.27)
							)
						)
					)
				)
				(pin input line
					(at 0 -2.54 0)
					(length 2.54)
					(name "EN"
						(effects
							(font
								(size 1.27 1.27)
							)
						)
					)
					(number "1"
						(effects
							(font
								(size 1.27 1.27)
							)
						)
					)
				)
				(pin power_in line
					(at 0 -5.08 0)
					(length 2.54)
					(name "GND"
						(effects
							(font
								(size 1.27 1.27)
							)
						)
					)
					(number "2"
						(effects
							(font
								(size 1.27 1.27)
							)
						)
					)
				)
				(pin passive line
					(at 0 -5.08 0)
					(length 2.54)
					(hide yes)
					(name "GND"
						(effects
							(font
								(size 1.27 1.27)
							)
						)
					)
					(number "7"
						(effects
							(font
								(size 1.27 1.27)
							)
						)
					)
				)
				(pin power_out line
					(at 15.24 0 180)
					(length 2.54)
					(name "V_{OUT}"
						(effects
							(font
								(size 1.27 1.27)
							)
						)
					)
					(number "4"
						(effects
							(font
								(size 1.27 1.27)
							)
						)
					)
				)
				(pin open_collector line
					(at 15.24 -2.54 180)
					(length 2.54)
					(name "PG"
						(effects
							(font
								(size 1.27 1.27)
							)
						)
					)
					(number "3"
						(effects
							(font
								(size 1.27 1.27)
							)
						)
					)
				)
				(pin input line
					(at 15.24 -5.08 180)
					(length 2.54)
					(name "ADJ"
						(effects
							(font
								(size 1.27 1.27)
							)
						)
					)
					(number "5"
						(effects
							(font
								(size 1.27 1.27)
							)
						)
					)
				)
			)
		)
	(symbol "antmicroPMICVoltageRegulatorsLinear:NCP718BSN330T1G"
			(exclude_from_sim no)
			(in_bom yes)
			(on_board yes)
			(property "Reference" "U"
				(at 35.56 -3.81 0)
				(effects
					(font
						(size 1.27 1.27)
						(thickness 0.15)
					)
					(justify left bottom)
				)
			)
			(property "Value" "NCP718BSN330T1G"
				(at 35.56 -6.35 0)
				(effects
					(font
						(size 1.27 1.27)
						(thickness 0.15)
					)
					(justify left bottom)
					(hide yes)
				)
			)
			(property "Footprint" "antmicro-footprints:SOT-23-5"
				(at 35.56 -8.89 0)
				(effects
					(font
						(size 1.27 1.27)
						(thickness 0.15)
					)
					(justify left bottom)
					(hide yes)
				)
			)
			(property "Datasheet" "https://www.mouser.com/datasheet/2/308/NCP718_D-1224359.pdf"
				(at 35.56 -11.43 0)
				(effects
					(font
						(size 1.27 1.27)
						(thickness 0.15)
					)
					(justify left bottom)
					(hide yes)
				)
			)
			(property "Description" "Linear Voltage Regulator IC Positive Fixed 1 Output 300mA TSOT-23-5"
				(at 35.56 -24.13 0)
				(effects
					(font
						(size 1.27 1.27)
					)
					(justify left bottom)
					(hide yes)
				)
			)
			(property "MPN" "NCP718BSN330T1G"
				(at 35.56 -13.97 0)
				(effects
					(font
						(size 1.27 1.27)
						(thickness 0.15)
					)
					(justify left bottom)
				)
			)
			(property "Manufacturer" "ON Semiconductor"
				(at 35.56 -16.51 0)
				(effects
					(font
						(size 1.27 1.27)
						(thickness 0.15)
					)
					(justify left bottom)
					(hide yes)
				)
			)
			(property "Author" "Antmicro"
				(at 35.56 -19.05 0)
				(effects
					(font
						(size 1.27 1.27)
						(thickness 0.15)
					)
					(justify left bottom)
					(hide yes)
				)
			)
			(property "License" "Apache-2.0"
				(at 35.56 -21.59 0)
				(effects
					(font
						(size 1.27 1.27)
						(thickness 0.15)
					)
					(justify left bottom)
					(hide yes)
				)
			)
			(property "ki_keywords" "SMT, PMIC, IC, LDO, VOLTAGE, REGULATOR"
				(at 0 0 0)
				(effects
					(font
						(size 1.27 1.27)
					)
					(hide yes)
				)
			)
			(symbol "NCP718BSN330T1G_1_1"
				(rectangle
					(start 2.54 2.54)
					(end 17.78 -5.08)
					(stroke
						(width 0.254)
						(type default)
					)
					(fill
						(type background)
					)
				)
				(pin passive line
					(at 0 0 0)
					(length 2.54)
					(name "VIN"
						(effects
							(font
								(size 1.27 1.27)
							)
						)
					)
					(number "1"
						(effects
							(font
								(size 1.27 1.27)
							)
						)
					)
				)
				(pin passive line
					(at 0 -2.54 0)
					(length 2.54)
					(name "EN"
						(effects
							(font
								(size 1.27 1.27)
							)
						)
					)
					(number "3"
						(effects
							(font
								(size 1.27 1.27)
							)
						)
					)
				)
				(pin no_connect line
					(at 10.16 -5.08 90)
					(length 2.54)
					(hide yes)
					(name "NC"
						(effects
							(font
								(size 1.27 1.27)
							)
						)
					)
					(number "4"
						(effects
							(font
								(size 1.27 1.27)
							)
						)
					)
				)
				(pin passive line
					(at 20.32 0 180)
					(length 2.54)
					(name "VOUT"
						(effects
							(font
								(size 1.27 1.27)
							)
						)
					)
					(number "5"
						(effects
							(font
								(size 1.27 1.27)
							)
						)
					)
				)
				(pin passive line
					(at 20.32 -2.54 180)
					(length 2.54)
					(name "GND"
						(effects
							(font
								(size 1.27 1.27)
							)
						)
					)
					(number "2"
						(effects
							(font
								(size 1.27 1.27)
							)
						)
					)
				)
			)
		)
	(symbol "antmicroPciConnectors:Bus_M.2_1-2199230-6"
			(exclude_from_sim no)
			(in_bom yes)
			(on_board yes)
			(property "Reference" "J"
				(at 45.72 -2.54 0)
				(effects
					(font
						(size 1.27 1.27)
						(thickness 0.15)
					)
					(justify left bottom)
				)
			)
			(property "Value" "Bus_M.2_1-2199230-6"
				(at 45.72 -7.62 0)
				(effects
					(font
						(size 1.27 1.27)
						(thickness 0.15)
					)
					(justify left bottom)
					(hide yes)
				)
			)
			(property "Footprint" "antmicro-footprints:Bus_M.2_Socket_Key_M_TE_1-2199230-6"
				(at 45.72 -10.16 0)
				(effects
					(font
						(size 1.27 1.27)
						(thickness 0.15)
					)
					(justify left bottom)
					(hide yes)
				)
			)
			(property "Datasheet" "https://www.te.com/commerce/DocumentDelivery/DDEController?Action=srchrtrv&DocNm=2199230&DocType=Customer+Drawing&DocLang=English"
				(at 45.72 -12.7 0)
				(effects
					(font
						(size 1.27 1.27)
						(thickness 0.15)
					)
					(justify left bottom)
					(hide yes)
				)
			)
			(property "Description" "Key M Card Edge Connector, 0, Dual Side, 67 Contacts, Surface Mount, Right Angle, Solder"
				(at 45.72 -22.86 0)
				(effects
					(font
						(size 1.27 1.27)
					)
					(justify left bottom)
					(hide yes)
				)
			)
			(property "Manufacturer" "TE Connectivity"
				(at 45.72 -15.24 0)
				(effects
					(font
						(size 1.27 1.27)
						(thickness 0.15)
					)
					(justify left bottom)
					(hide yes)
				)
			)
			(property "MPN" "1-2199230-6"
				(at 45.72 -5.08 0)
				(effects
					(font
						(size 1.27 1.27)
						(thickness 0.15)
					)
					(justify left bottom)
				)
			)
			(property "Author" "Antmicro"
				(at 45.72 -17.78 0)
				(effects
					(font
						(size 1.27 1.27)
						(thickness 0.15)
					)
					(justify left bottom)
					(hide yes)
				)
			)
			(property "License" "Apache-2.0"
				(at 45.72 -20.32 0)
				(effects
					(font
						(size 1.27 1.27)
						(thickness 0.15)
					)
					(justify left bottom)
					(hide yes)
				)
			)
			(property "ki_keywords" "HORIZONTAL, SMT, PCIE, CONNECTOR"
				(at 0 0 0)
				(effects
					(font
						(size 1.27 1.27)
					)
					(hide yes)
				)
			)
			(symbol "Bus_M.2_1-2199230-6_0_0"
				(text "KEY M"
					(at 15.24 0 0)
					(effects
						(font
							(size 1.27 1.27)
							(bold yes)
						)
					)
				)
			)
			(symbol "Bus_M.2_1-2199230-6_1_1"
				(rectangle
					(start 3.81 2.54)
					(end 26.67 -80.01)
					(stroke
						(width 0.254)
						(type default)
					)
					(fill
						(type background)
					)
				)
				(pin input line
					(at 0 0 0)
					(length 3.81)
					(name "~{PERST}"
						(effects
							(font
								(size 1.27 1.27)
							)
						)
					)
					(number "50"
						(effects
							(font
								(size 1.27 1.27)
							)
						)
					)
				)
				(pin output line
					(at 0 -2.54 0)
					(length 3.81)
					(name "~{CLKREQ}"
						(effects
							(font
								(size 1.27 1.27)
							)
						)
					)
					(number "52"
						(effects
							(font
								(size 1.27 1.27)
							)
						)
					)
				)
				(pin input line
					(at 0 -5.08 0)
					(length 3.81)
					(name "~{PEWAKE}"
						(effects
							(font
								(size 1.27 1.27)
							)
						)
					)
					(number "54"
						(effects
							(font
								(size 1.27 1.27)
							)
						)
					)
				)
				(pin input line
					(at 0 -12.7 0)
					(length 3.81)
					(name "REFCLK_P"
						(effects
							(font
								(size 1.27 1.27)
							)
						)
					)
					(number "55"
						(effects
							(font
								(size 1.27 1.27)
							)
						)
					)
				)
				(pin input line
					(at 0 -15.24 0)
					(length 3.81)
					(name "REFCLK_N"
						(effects
							(font
								(size 1.27 1.27)
							)
						)
					)
					(number "53"
						(effects
							(font
								(size 1.27 1.27)
							)
						)
					)
				)
				(pin input line
					(at 0 -21.59 0)
					(length 3.81)
					(name "PET0_P"
						(effects
							(font
								(size 1.27 1.27)
							)
						)
					)
					(number "49"
						(effects
							(font
								(size 1.27 1.27)
							)
						)
					)
				)
				(pin input line
					(at 0 -24.13 0)
					(length 3.81)
					(name "PET0_N"
						(effects
							(font
								(size 1.27 1.27)
							)
						)
					)
					(number "47"
						(effects
							(font
								(size 1.27 1.27)
							)
						)
					)
				)
				(pin output line
					(at 0 -29.21 0)
					(length 3.81)
					(name "PER0_P"
						(effects
							(font
								(size 1.27 1.27)
							)
						)
					)
					(number "43"
						(effects
							(font
								(size 1.27 1.27)
							)
						)
					)
				)
				(pin output line
					(at 0 -31.75 0)
					(length 3.81)
					(name "PER0_N"
						(effects
							(font
								(size 1.27 1.27)
							)
						)
					)
					(number "41"
						(effects
							(font
								(size 1.27 1.27)
							)
						)
					)
				)
				(pin input line
					(at 0 -36.83 0)
					(length 3.81)
					(name "PET1_P"
						(effects
							(font
								(size 1.27 1.27)
							)
						)
					)
					(number "37"
						(effects
							(font
								(size 1.27 1.27)
							)
						)
					)
				)
				(pin input line
					(at 0 -39.37 0)
					(length 3.81)
					(name "PET1_N"
						(effects
							(font
								(size 1.27 1.27)
							)
						)
					)
					(number "35"
						(effects
							(font
								(size 1.27 1.27)
							)
						)
					)
				)
				(pin output line
					(at 0 -44.45 0)
					(length 3.81)
					(name "PER1_P"
						(effects
							(font
								(size 1.27 1.27)
							)
						)
					)
					(number "31"
						(effects
							(font
								(size 1.27 1.27)
							)
						)
					)
				)
				(pin output line
					(at 0 -46.99 0)
					(length 3.81)
					(name "PER1_N"
						(effects
							(font
								(size 1.27 1.27)
							)
						)
					)
					(number "29"
						(effects
							(font
								(size 1.27 1.27)
							)
						)
					)
				)
				(pin input line
					(at 0 -52.07 0)
					(length 3.81)
					(name "PET2_P"
						(effects
							(font
								(size 1.27 1.27)
							)
						)
					)
					(number "25"
						(effects
							(font
								(size 1.27 1.27)
							)
						)
					)
				)
				(pin input line
					(at 0 -54.61 0)
					(length 3.81)
					(name "PET2_N"
						(effects
							(font
								(size 1.27 1.27)
							)
						)
					)
					(number "23"
						(effects
							(font
								(size 1.27 1.27)
							)
						)
					)
				)
				(pin output line
					(at 0 -59.69 0)
					(length 3.81)
					(name "PER2_P"
						(effects
							(font
								(size 1.27 1.27)
							)
						)
					)
					(number "19"
						(effects
							(font
								(size 1.27 1.27)
							)
						)
					)
				)
				(pin output line
					(at 0 -62.23 0)
					(length 3.81)
					(name "PER2_N"
						(effects
							(font
								(size 1.27 1.27)
							)
						)
					)
					(number "17"
						(effects
							(font
								(size 1.27 1.27)
							)
						)
					)
				)
				(pin input line
					(at 0 -67.31 0)
					(length 3.81)
					(name "PET3_P"
						(effects
							(font
								(size 1.27 1.27)
							)
						)
					)
					(number "13"
						(effects
							(font
								(size 1.27 1.27)
							)
						)
					)
				)
				(pin input line
					(at 0 -69.85 0)
					(length 3.81)
					(name "PET3_N"
						(effects
							(font
								(size 1.27 1.27)
							)
						)
					)
					(number "11"
						(effects
							(font
								(size 1.27 1.27)
							)
						)
					)
				)
				(pin output line
					(at 0 -74.93 0)
					(length 3.81)
					(name "PER3_P"
						(effects
							(font
								(size 1.27 1.27)
							)
						)
					)
					(number "7"
						(effects
							(font
								(size 1.27 1.27)
							)
						)
					)
				)
				(pin output line
					(at 0 -77.47 0)
					(length 3.81)
					(name "PER3_N"
						(effects
							(font
								(size 1.27 1.27)
							)
						)
					)
					(number "5"
						(effects
							(font
								(size 1.27 1.27)
							)
						)
					)
				)
				(pin no_connect line
					(at 26.67 -38.1 180)
					(length 3.81)
					(hide yes)
					(name "NC"
						(effects
							(font
								(size 1.27 1.27)
							)
						)
					)
					(number "69"
						(effects
							(font
								(size 1.27 1.27)
							)
						)
					)
				)
				(pin no_connect line
					(at 26.67 -39.37 180)
					(length 3.81)
					(hide yes)
					(name "NC"
						(effects
							(font
								(size 1.27 1.27)
							)
						)
					)
					(number "6"
						(effects
							(font
								(size 1.27 1.27)
							)
						)
					)
				)
				(pin no_connect line
					(at 26.67 -40.64 180)
					(length 3.81)
					(hide yes)
					(name "NC"
						(effects
							(font
								(size 1.27 1.27)
							)
						)
					)
					(number "67"
						(effects
							(font
								(size 1.27 1.27)
							)
						)
					)
				)
				(pin no_connect line
					(at 26.67 -41.91 180)
					(length 3.81)
					(hide yes)
					(name "NC"
						(effects
							(font
								(size 1.27 1.27)
							)
						)
					)
					(number "48"
						(effects
							(font
								(size 1.27 1.27)
							)
						)
					)
				)
				(pin no_connect line
					(at 26.67 -43.18 180)
					(length 3.81)
					(hide yes)
					(name "NC"
						(effects
							(font
								(size 1.27 1.27)
							)
						)
					)
					(number "56"
						(effects
							(font
								(size 1.27 1.27)
							)
						)
					)
				)
				(pin no_connect line
					(at 26.67 -44.45 180)
					(length 3.81)
					(hide yes)
					(name "NC"
						(effects
							(font
								(size 1.27 1.27)
							)
						)
					)
					(number "20"
						(effects
							(font
								(size 1.27 1.27)
							)
						)
					)
				)
				(pin no_connect line
					(at 26.67 -45.72 180)
					(length 3.81)
					(hide yes)
					(name "NC"
						(effects
							(font
								(size 1.27 1.27)
							)
						)
					)
					(number "22"
						(effects
							(font
								(size 1.27 1.27)
							)
						)
					)
				)
				(pin no_connect line
					(at 26.67 -46.99 180)
					(length 3.81)
					(hide yes)
					(name "NC"
						(effects
							(font
								(size 1.27 1.27)
							)
						)
					)
					(number "24"
						(effects
							(font
								(size 1.27 1.27)
							)
						)
					)
				)
				(pin no_connect line
					(at 26.67 -59.69 180)
					(length 3.81)
					(hide yes)
					(name "NC"
						(effects
							(font
								(size 1.27 1.27)
							)
						)
					)
					(number "26"
						(effects
							(font
								(size 1.27 1.27)
							)
						)
					)
				)
				(pin no_connect line
					(at 26.67 -60.96 180)
					(length 3.81)
					(hide yes)
					(name "NC"
						(effects
							(font
								(size 1.27 1.27)
							)
						)
					)
					(number "28"
						(effects
							(font
								(size 1.27 1.27)
							)
						)
					)
				)
				(pin no_connect line
					(at 26.67 -62.23 180)
					(length 3.81)
					(hide yes)
					(name "NC"
						(effects
							(font
								(size 1.27 1.27)
							)
						)
					)
					(number "30"
						(effects
							(font
								(size 1.27 1.27)
							)
						)
					)
				)
				(pin no_connect line
					(at 26.67 -63.5 180)
					(length 3.81)
					(hide yes)
					(name "NC"
						(effects
							(font
								(size 1.27 1.27)
							)
						)
					)
					(number "32"
						(effects
							(font
								(size 1.27 1.27)
							)
						)
					)
				)
				(pin no_connect line
					(at 26.67 -64.77 180)
					(length 3.81)
					(hide yes)
					(name "NC"
						(effects
							(font
								(size 1.27 1.27)
							)
						)
					)
					(number "8"
						(effects
							(font
								(size 1.27 1.27)
							)
						)
					)
				)
				(pin no_connect line
					(at 26.67 -66.04 180)
					(length 3.81)
					(hide yes)
					(name "NC"
						(effects
							(font
								(size 1.27 1.27)
							)
						)
					)
					(number "34"
						(effects
							(font
								(size 1.27 1.27)
							)
						)
					)
				)
				(pin no_connect line
					(at 26.67 -67.31 180)
					(length 3.81)
					(hide yes)
					(name "NC"
						(effects
							(font
								(size 1.27 1.27)
							)
						)
					)
					(number "36"
						(effects
							(font
								(size 1.27 1.27)
							)
						)
					)
				)
				(pin no_connect line
					(at 26.67 -68.58 180)
					(length 3.81)
					(hide yes)
					(name "NC"
						(effects
							(font
								(size 1.27 1.27)
							)
						)
					)
					(number "46"
						(effects
							(font
								(size 1.27 1.27)
							)
						)
					)
				)
				(pin no_connect line
					(at 26.67 -69.85 180)
					(length 3.81)
					(hide yes)
					(name "NC"
						(effects
							(font
								(size 1.27 1.27)
							)
						)
					)
					(number "38"
						(effects
							(font
								(size 1.27 1.27)
							)
						)
					)
				)
				(pin no_connect line
					(at 26.67 -71.12 180)
					(length 3.81)
					(hide yes)
					(name "NC"
						(effects
							(font
								(size 1.27 1.27)
							)
						)
					)
					(number "58"
						(effects
							(font
								(size 1.27 1.27)
							)
						)
					)
				)
				(pin passive line
					(at 30.48 0 180)
					(length 3.81)
					(name "3V3"
						(effects
							(font
								(size 1.27 1.27)
							)
						)
					)
					(number "12"
						(effects
							(font
								(size 1.27 1.27)
							)
						)
					)
				)
				(pin passive line
					(at 30.48 0 180)
					(length 3.81)
					(hide yes)
					(name "3V3"
						(effects
							(font
								(size 1.27 1.27)
							)
						)
					)
					(number "14"
						(effects
							(font
								(size 1.27 1.27)
							)
						)
					)
				)
				(pin passive line
					(at 30.48 0 180)
					(length 3.81)
					(hide yes)
					(name "3V3"
						(effects
							(font
								(size 1.27 1.27)
							)
						)
					)
					(number "16"
						(effects
							(font
								(size 1.27 1.27)
							)
						)
					)
				)
				(pin passive line
					(at 30.48 0 180)
					(length 3.81)
					(hide yes)
					(name "3V3"
						(effects
							(font
								(size 1.27 1.27)
							)
						)
					)
					(number "18"
						(effects
							(font
								(size 1.27 1.27)
							)
						)
					)
				)
				(pin passive line
					(at 30.48 0 180)
					(length 3.81)
					(hide yes)
					(name "3V3"
						(effects
							(font
								(size 1.27 1.27)
							)
						)
					)
					(number "2"
						(effects
							(font
								(size 1.27 1.27)
							)
						)
					)
				)
				(pin passive line
					(at 30.48 0 180)
					(length 3.81)
					(hide yes)
					(name "3V3"
						(effects
							(font
								(size 1.27 1.27)
							)
						)
					)
					(number "4"
						(effects
							(font
								(size 1.27 1.27)
							)
						)
					)
				)
				(pin passive line
					(at 30.48 0 180)
					(length 3.81)
					(hide yes)
					(name "3V3"
						(effects
							(font
								(size 1.27 1.27)
							)
						)
					)
					(number "70"
						(effects
							(font
								(size 1.27 1.27)
							)
						)
					)
				)
				(pin passive line
					(at 30.48 0 180)
					(length 3.81)
					(hide yes)
					(name "3V3"
						(effects
							(font
								(size 1.27 1.27)
							)
						)
					)
					(number "72"
						(effects
							(font
								(size 1.27 1.27)
							)
						)
					)
				)
				(pin passive line
					(at 30.48 0 180)
					(length 3.81)
					(hide yes)
					(name "3V3"
						(effects
							(font
								(size 1.27 1.27)
							)
						)
					)
					(number "74"
						(effects
							(font
								(size 1.27 1.27)
							)
						)
					)
				)
				(pin input line
					(at 30.48 -12.7 180)
					(length 3.81)
					(name "SUSCLK"
						(effects
							(font
								(size 1.27 1.27)
							)
						)
					)
					(number "68"
						(effects
							(font
								(size 1.27 1.27)
							)
						)
					)
				)
				(pin output line
					(at 30.48 -26.67 180)
					(length 3.81)
					(name "ALERT"
						(effects
							(font
								(size 1.27 1.27)
							)
						)
					)
					(number "44"
						(effects
							(font
								(size 1.27 1.27)
							)
						)
					)
				)
				(pin bidirectional line
					(at 30.48 -29.21 180)
					(length 3.81)
					(name "SMB_DATA"
						(effects
							(font
								(size 1.27 1.27)
							)
						)
					)
					(number "42"
						(effects
							(font
								(size 1.27 1.27)
							)
						)
					)
				)
				(pin input line
					(at 30.48 -31.75 180)
					(length 3.81)
					(name "SMB_CLK"
						(effects
							(font
								(size 1.27 1.27)
							)
						)
					)
					(number "40"
						(effects
							(font
								(size 1.27 1.27)
							)
						)
					)
				)
				(pin passive line
					(at 30.48 -54.61 180)
					(length 3.81)
					(name "LED"
						(effects
							(font
								(size 1.27 1.27)
							)
						)
					)
					(number "10"
						(effects
							(font
								(size 1.27 1.27)
							)
						)
					)
				)
				(pin passive line
					(at 30.48 -74.93 180)
					(length 3.81)
					(name "MP"
						(effects
							(font
								(size 1.27 1.27)
							)
						)
					)
					(number "MP1"
						(effects
							(font
								(size 1.27 1.27)
							)
						)
					)
				)
				(pin passive line
					(at 30.48 -74.93 180)
					(length 3.81)
					(hide yes)
					(name "MP"
						(effects
							(font
								(size 1.27 1.27)
							)
						)
					)
					(number "MP2"
						(effects
							(font
								(size 1.27 1.27)
							)
						)
					)
				)
				(pin power_in line
					(at 30.48 -77.47 180)
					(length 3.81)
					(name "GND"
						(effects
							(font
								(size 1.27 1.27)
							)
						)
					)
					(number "1"
						(effects
							(font
								(size 1.27 1.27)
							)
						)
					)
				)
				(pin passive line
					(at 30.48 -77.47 180)
					(length 3.81)
					(hide yes)
					(name "GND"
						(effects
							(font
								(size 1.27 1.27)
							)
						)
					)
					(number "15"
						(effects
							(font
								(size 1.27 1.27)
							)
						)
					)
				)
				(pin passive line
					(at 30.48 -77.47 180)
					(length 3.81)
					(hide yes)
					(name "GND"
						(effects
							(font
								(size 1.27 1.27)
							)
						)
					)
					(number "21"
						(effects
							(font
								(size 1.27 1.27)
							)
						)
					)
				)
				(pin passive line
					(at 30.48 -77.47 180)
					(length 3.81)
					(hide yes)
					(name "GND"
						(effects
							(font
								(size 1.27 1.27)
							)
						)
					)
					(number "27"
						(effects
							(font
								(size 1.27 1.27)
							)
						)
					)
				)
				(pin passive line
					(at 30.48 -77.47 180)
					(length 3.81)
					(hide yes)
					(name "GND"
						(effects
							(font
								(size 1.27 1.27)
							)
						)
					)
					(number "3"
						(effects
							(font
								(size 1.27 1.27)
							)
						)
					)
				)
				(pin passive line
					(at 30.48 -77.47 180)
					(length 3.81)
					(hide yes)
					(name "GND"
						(effects
							(font
								(size 1.27 1.27)
							)
						)
					)
					(number "33"
						(effects
							(font
								(size 1.27 1.27)
							)
						)
					)
				)
				(pin passive line
					(at 30.48 -77.47 180)
					(length 3.81)
					(hide yes)
					(name "GND"
						(effects
							(font
								(size 1.27 1.27)
							)
						)
					)
					(number "39"
						(effects
							(font
								(size 1.27 1.27)
							)
						)
					)
				)
				(pin passive line
					(at 30.48 -77.47 180)
					(length 3.81)
					(hide yes)
					(name "GND"
						(effects
							(font
								(size 1.27 1.27)
							)
						)
					)
					(number "45"
						(effects
							(font
								(size 1.27 1.27)
							)
						)
					)
				)
				(pin passive line
					(at 30.48 -77.47 180)
					(length 3.81)
					(hide yes)
					(name "GND"
						(effects
							(font
								(size 1.27 1.27)
							)
						)
					)
					(number "51"
						(effects
							(font
								(size 1.27 1.27)
							)
						)
					)
				)
				(pin passive line
					(at 30.48 -77.47 180)
					(length 3.81)
					(hide yes)
					(name "GND"
						(effects
							(font
								(size 1.27 1.27)
							)
						)
					)
					(number "57"
						(effects
							(font
								(size 1.27 1.27)
							)
						)
					)
				)
				(pin passive line
					(at 30.48 -77.47 180)
					(length 3.81)
					(hide yes)
					(name "GND"
						(effects
							(font
								(size 1.27 1.27)
							)
						)
					)
					(number "71"
						(effects
							(font
								(size 1.27 1.27)
							)
						)
					)
				)
				(pin passive line
					(at 30.48 -77.47 180)
					(length 3.81)
					(hide yes)
					(name "GND"
						(effects
							(font
								(size 1.27 1.27)
							)
						)
					)
					(number "73"
						(effects
							(font
								(size 1.27 1.27)
							)
						)
					)
				)
				(pin passive line
					(at 30.48 -77.47 180)
					(length 3.81)
					(hide yes)
					(name "GND"
						(effects
							(font
								(size 1.27 1.27)
							)
						)
					)
					(number "75"
						(effects
							(font
								(size 1.27 1.27)
							)
						)
					)
				)
				(pin passive line
					(at 30.48 -77.47 180)
					(length 3.81)
					(hide yes)
					(name "GND"
						(effects
							(font
								(size 1.27 1.27)
							)
						)
					)
					(number "9"
						(effects
							(font
								(size 1.27 1.27)
							)
						)
					)
				)
			)
		)
	(symbol "antmicroPciConnectors:Bus_M.2_2199230-2"
			(exclude_from_sim no)
			(in_bom yes)
			(on_board yes)
			(property "Reference" "J"
				(at 45.72 -1.27 0)
				(effects
					(font
						(size 1.27 1.27)
						(thickness 0.15)
					)
					(justify left bottom)
				)
			)
			(property "Value" "Bus_M.2_2199230-2"
				(at 45.72 -6.35 0)
				(effects
					(font
						(size 1.27 1.27)
						(thickness 0.15)
					)
					(justify left bottom)
					(hide yes)
				)
			)
			(property "Footprint" "antmicro-footprints:Bus_M.2_Socket_Key_E_TE_2199230-6"
				(at 45.72 -8.89 0)
				(effects
					(font
						(size 1.27 1.27)
						(thickness 0.15)
					)
					(justify left bottom)
					(hide yes)
				)
			)
			(property "Datasheet" "https://eu.mouser.com/datasheet/2/418/9/ENG_DS_1_1773702_1NGFFQRG_EN_0214_1_1773702_1NGFF_-3328593.pdf"
				(at 45.72 -11.43 0)
				(effects
					(font
						(size 1.27 1.27)
						(thickness 0.15)
					)
					(justify left bottom)
					(hide yes)
				)
			)
			(property "Description" "Key E, PCI connector"
				(at 45.72 -21.59 0)
				(effects
					(font
						(size 1.27 1.27)
					)
					(justify left bottom)
					(hide yes)
				)
			)
			(property "MPN" "2199230-2"
				(at 45.72 -3.81 0)
				(effects
					(font
						(size 1.27 1.27)
						(thickness 0.15)
					)
					(justify left bottom)
				)
			)
			(property "Manufacturer" "TE Connectivity"
				(at 45.72 -13.97 0)
				(effects
					(font
						(size 1.27 1.27)
						(thickness 0.15)
					)
					(justify left bottom)
					(hide yes)
				)
			)
			(property "Author" "Antmicro"
				(at 45.72 -16.51 0)
				(effects
					(font
						(size 1.27 1.27)
						(thickness 0.15)
					)
					(justify left bottom)
					(hide yes)
				)
			)
			(property "License" "Apache-2.0"
				(at 45.72 -19.05 0)
				(effects
					(font
						(size 1.27 1.27)
						(thickness 0.15)
					)
					(justify left bottom)
					(hide yes)
				)
			)
			(property "ki_keywords" "HORIZONTAL, SMT, PCIE, CONNECTOR"
				(at 0 0 0)
				(effects
					(font
						(size 1.27 1.27)
					)
					(hide yes)
				)
			)
			(symbol "Bus_M.2_2199230-2_0_0"
				(text "KEY E"
					(at 15.24 0 0)
					(effects
						(font
							(size 1.27 1.27)
							(bold yes)
						)
					)
				)
			)
			(symbol "Bus_M.2_2199230-2_1_1"
				(rectangle
					(start 2.54 2.54)
					(end 27.94 -106.68)
					(stroke
						(width 0.254)
						(type default)
					)
					(fill
						(type background)
					)
				)
				(pin input line
					(at 0 0 0)
					(length 2.54)
					(name "~{PERST0}"
						(effects
							(font
								(size 1.27 1.27)
							)
						)
					)
					(number "52"
						(effects
							(font
								(size 1.27 1.27)
							)
						)
					)
				)
				(pin output line
					(at 0 -2.54 0)
					(length 2.54)
					(name "~{CLKREQ0}"
						(effects
							(font
								(size 1.27 1.27)
							)
						)
					)
					(number "53"
						(effects
							(font
								(size 1.27 1.27)
							)
						)
					)
				)
				(pin output line
					(at 0 -5.08 0)
					(length 2.54)
					(name "~{PEWAKE0}"
						(effects
							(font
								(size 1.27 1.27)
							)
						)
					)
					(number "55"
						(effects
							(font
								(size 1.27 1.27)
							)
						)
					)
				)
				(pin input line
					(at 0 -10.16 0)
					(length 2.54)
					(name "REFCLK0_P"
						(effects
							(font
								(size 1.27 1.27)
							)
						)
					)
					(number "47"
						(effects
							(font
								(size 1.27 1.27)
							)
						)
					)
				)
				(pin input line
					(at 0 -12.7 0)
					(length 2.54)
					(name "REFCLK0_N"
						(effects
							(font
								(size 1.27 1.27)
							)
						)
					)
					(number "49"
						(effects
							(font
								(size 1.27 1.27)
							)
						)
					)
				)
				(pin input line
					(at 0 -17.78 0)
					(length 2.54)
					(name "PET0_P"
						(effects
							(font
								(size 1.27 1.27)
							)
						)
					)
					(number "35"
						(effects
							(font
								(size 1.27 1.27)
							)
						)
					)
				)
				(pin input line
					(at 0 -20.32 0)
					(length 2.54)
					(name "PET0_N"
						(effects
							(font
								(size 1.27 1.27)
							)
						)
					)
					(number "37"
						(effects
							(font
								(size 1.27 1.27)
							)
						)
					)
				)
				(pin output line
					(at 0 -25.4 0)
					(length 2.54)
					(name "PER0_P"
						(effects
							(font
								(size 1.27 1.27)
							)
						)
					)
					(number "41"
						(effects
							(font
								(size 1.27 1.27)
							)
						)
					)
				)
				(pin output line
					(at 0 -27.94 0)
					(length 2.54)
					(name "PER0_N"
						(effects
							(font
								(size 1.27 1.27)
							)
						)
					)
					(number "43"
						(effects
							(font
								(size 1.27 1.27)
							)
						)
					)
				)
				(pin input line
					(at 0 -33.02 0)
					(length 2.54)
					(name "REFCLK1_P"
						(effects
							(font
								(size 1.27 1.27)
							)
						)
					)
					(number "71"
						(effects
							(font
								(size 1.27 1.27)
							)
						)
					)
				)
				(pin input line
					(at 0 -35.56 0)
					(length 2.54)
					(name "REFCLK1_N"
						(effects
							(font
								(size 1.27 1.27)
							)
						)
					)
					(number "73"
						(effects
							(font
								(size 1.27 1.27)
							)
						)
					)
				)
				(pin input line
					(at 0 -40.64 0)
					(length 2.54)
					(name "PET1_P"
						(effects
							(font
								(size 1.27 1.27)
							)
						)
					)
					(number "59"
						(effects
							(font
								(size 1.27 1.27)
							)
						)
					)
				)
				(pin input line
					(at 0 -43.18 0)
					(length 2.54)
					(name "PET1_N"
						(effects
							(font
								(size 1.27 1.27)
							)
						)
					)
					(number "61"
						(effects
							(font
								(size 1.27 1.27)
							)
						)
					)
				)
				(pin output line
					(at 0 -48.26 0)
					(length 2.54)
					(name "PER1_P"
						(effects
							(font
								(size 1.27 1.27)
							)
						)
					)
					(number "65"
						(effects
							(font
								(size 1.27 1.27)
							)
						)
					)
				)
				(pin output line
					(at 0 -50.8 0)
					(length 2.54)
					(name "PER1_N"
						(effects
							(font
								(size 1.27 1.27)
							)
						)
					)
					(number "67"
						(effects
							(font
								(size 1.27 1.27)
							)
						)
					)
				)
				(pin bidirectional line
					(at 0 -55.88 0)
					(length 2.54)
					(name "UIM_SWP"
						(effects
							(font
								(size 1.27 1.27)
							)
						)
					)
					(number "66"
						(effects
							(font
								(size 1.27 1.27)
							)
						)
					)
				)
				(pin bidirectional line
					(at 0 -58.42 0)
					(length 2.54)
					(name "UIM_POWER_SNK"
						(effects
							(font
								(size 1.27 1.27)
							)
						)
					)
					(number "68"
						(effects
							(font
								(size 1.27 1.27)
							)
						)
					)
				)
				(pin bidirectional line
					(at 0 -60.96 0)
					(length 2.54)
					(name "UIM_POWER_SRC"
						(effects
							(font
								(size 1.27 1.27)
							)
						)
					)
					(number "70"
						(effects
							(font
								(size 1.27 1.27)
							)
						)
					)
				)
				(pin bidirectional line
					(at 0 -66.04 0)
					(length 2.54)
					(name "PCM_CLK"
						(effects
							(font
								(size 1.27 1.27)
							)
						)
					)
					(number "8"
						(effects
							(font
								(size 1.27 1.27)
							)
						)
					)
				)
				(pin bidirectional line
					(at 0 -68.58 0)
					(length 2.54)
					(name "PCM_SYNC"
						(effects
							(font
								(size 1.27 1.27)
							)
						)
					)
					(number "10"
						(effects
							(font
								(size 1.27 1.27)
							)
						)
					)
				)
				(pin bidirectional line
					(at 0 -71.12 0)
					(length 2.54)
					(name "PCM_OUT"
						(effects
							(font
								(size 1.27 1.27)
							)
						)
					)
					(number "14"
						(effects
							(font
								(size 1.27 1.27)
							)
						)
					)
				)
				(pin bidirectional line
					(at 0 -73.66 0)
					(length 2.54)
					(name "PCM_IN"
						(effects
							(font
								(size 1.27 1.27)
							)
						)
					)
					(number "12"
						(effects
							(font
								(size 1.27 1.27)
							)
						)
					)
				)
				(pin bidirectional line
					(at 0 -78.74 0)
					(length 2.54)
					(name "USB_D_P"
						(effects
							(font
								(size 1.27 1.27)
							)
						)
					)
					(number "3"
						(effects
							(font
								(size 1.27 1.27)
							)
						)
					)
				)
				(pin bidirectional line
					(at 0 -81.28 0)
					(length 2.54)
					(name "USB_D_N"
						(effects
							(font
								(size 1.27 1.27)
							)
						)
					)
					(number "5"
						(effects
							(font
								(size 1.27 1.27)
							)
						)
					)
				)
				(pin input line
					(at 0 -86.36 0)
					(length 2.54)
					(name "SDIO_CLK"
						(effects
							(font
								(size 1.27 1.27)
							)
						)
					)
					(number "9"
						(effects
							(font
								(size 1.27 1.27)
							)
						)
					)
				)
				(pin bidirectional line
					(at 0 -88.9 0)
					(length 2.54)
					(name "SDIO_CMD"
						(effects
							(font
								(size 1.27 1.27)
							)
						)
					)
					(number "11"
						(effects
							(font
								(size 1.27 1.27)
							)
						)
					)
				)
				(pin bidirectional line
					(at 0 -91.44 0)
					(length 2.54)
					(name "SDIO_D0"
						(effects
							(font
								(size 1.27 1.27)
							)
						)
					)
					(number "13"
						(effects
							(font
								(size 1.27 1.27)
							)
						)
					)
				)
				(pin bidirectional line
					(at 0 -93.98 0)
					(length 2.54)
					(name "SDIO_D1"
						(effects
							(font
								(size 1.27 1.27)
							)
						)
					)
					(number "15"
						(effects
							(font
								(size 1.27 1.27)
							)
						)
					)
				)
				(pin bidirectional line
					(at 0 -96.52 0)
					(length 2.54)
					(name "SDIO_D2"
						(effects
							(font
								(size 1.27 1.27)
							)
						)
					)
					(number "17"
						(effects
							(font
								(size 1.27 1.27)
							)
						)
					)
				)
				(pin bidirectional line
					(at 0 -99.06 0)
					(length 2.54)
					(name "SDIO_D3"
						(effects
							(font
								(size 1.27 1.27)
							)
						)
					)
					(number "19"
						(effects
							(font
								(size 1.27 1.27)
							)
						)
					)
				)
				(pin bidirectional line
					(at 0 -101.6 0)
					(length 2.54)
					(name "SDIO_~{WAKE}"
						(effects
							(font
								(size 1.27 1.27)
							)
						)
					)
					(number "21"
						(effects
							(font
								(size 1.27 1.27)
							)
						)
					)
				)
				(pin input line
					(at 0 -104.14 0)
					(length 2.54)
					(name "SDIO_~{RESET}"
						(effects
							(font
								(size 1.27 1.27)
							)
						)
					)
					(number "23"
						(effects
							(font
								(size 1.27 1.27)
							)
						)
					)
				)
				(pin no_connect line
					(at 27.94 -93.98 180)
					(length 2.54)
					(hide yes)
					(name "RFU"
						(effects
							(font
								(size 1.27 1.27)
							)
						)
					)
					(number "64"
						(effects
							(font
								(size 1.27 1.27)
							)
						)
					)
				)
				(pin power_in line
					(at 30.48 0 180)
					(length 2.54)
					(name "3.3V"
						(effects
							(font
								(size 1.27 1.27)
							)
						)
					)
					(number "2"
						(effects
							(font
								(size 1.27 1.27)
							)
						)
					)
				)
				(pin passive line
					(at 30.48 0 180)
					(length 2.54)
					(hide yes)
					(name "3.3V"
						(effects
							(font
								(size 1.27 1.27)
							)
						)
					)
					(number "4"
						(effects
							(font
								(size 1.27 1.27)
							)
						)
					)
				)
				(pin passive line
					(at 30.48 0 180)
					(length 2.54)
					(hide yes)
					(name "3.3V"
						(effects
							(font
								(size 1.27 1.27)
							)
						)
					)
					(number "72"
						(effects
							(font
								(size 1.27 1.27)
							)
						)
					)
				)
				(pin passive line
					(at 30.48 0 180)
					(length 2.54)
					(hide yes)
					(name "3.3V"
						(effects
							(font
								(size 1.27 1.27)
							)
						)
					)
					(number "74"
						(effects
							(font
								(size 1.27 1.27)
							)
						)
					)
				)
				(pin input line
					(at 30.48 -12.7 180)
					(length 2.54)
					(name "SUSCLK"
						(effects
							(font
								(size 1.27 1.27)
							)
						)
					)
					(number "50"
						(effects
							(font
								(size 1.27 1.27)
							)
						)
					)
				)
				(pin output line
					(at 30.48 -25.4 180)
					(length 2.54)
					(name "~{ALERT}"
						(effects
							(font
								(size 1.27 1.27)
							)
						)
					)
					(number "62"
						(effects
							(font
								(size 1.27 1.27)
							)
						)
					)
				)
				(pin bidirectional line
					(at 30.48 -27.94 180)
					(length 2.54)
					(name "I2C_DATA"
						(effects
							(font
								(size 1.27 1.27)
							)
						)
					)
					(number "58"
						(effects
							(font
								(size 1.27 1.27)
							)
						)
					)
				)
				(pin bidirectional line
					(at 30.48 -30.48 180)
					(length 2.54)
					(name "I2C_CLK"
						(effects
							(font
								(size 1.27 1.27)
							)
						)
					)
					(number "60"
						(effects
							(font
								(size 1.27 1.27)
							)
						)
					)
				)
				(pin input line
					(at 30.48 -35.56 180)
					(length 2.54)
					(name "W_DISABLE1"
						(effects
							(font
								(size 1.27 1.27)
							)
						)
					)
					(number "56"
						(effects
							(font
								(size 1.27 1.27)
							)
						)
					)
				)
				(pin input line
					(at 30.48 -38.1 180)
					(length 2.54)
					(name "W_DISABLE2"
						(effects
							(font
								(size 1.27 1.27)
							)
						)
					)
					(number "54"
						(effects
							(font
								(size 1.27 1.27)
							)
						)
					)
				)
				(pin output line
					(at 30.48 -43.18 180)
					(length 2.54)
					(name "~{UART_WAKE}"
						(effects
							(font
								(size 1.27 1.27)
							)
						)
					)
					(number "20"
						(effects
							(font
								(size 1.27 1.27)
							)
						)
					)
				)
				(pin bidirectional line
					(at 30.48 -45.72 180)
					(length 2.54)
					(name "UART_TXD"
						(effects
							(font
								(size 1.27 1.27)
							)
						)
					)
					(number "32"
						(effects
							(font
								(size 1.27 1.27)
							)
						)
					)
				)
				(pin bidirectional line
					(at 30.48 -48.26 180)
					(length 2.54)
					(name "UART_RXD"
						(effects
							(font
								(size 1.27 1.27)
							)
						)
					)
					(number "22"
						(effects
							(font
								(size 1.27 1.27)
							)
						)
					)
				)
				(pin bidirectional line
					(at 30.48 -50.8 180)
					(length 2.54)
					(name "UART_RTS"
						(effects
							(font
								(size 1.27 1.27)
							)
						)
					)
					(number "36"
						(effects
							(font
								(size 1.27 1.27)
							)
						)
					)
				)
				(pin bidirectional line
					(at 30.48 -53.34 180)
					(length 2.54)
					(name "UART_CTS"
						(effects
							(font
								(size 1.27 1.27)
							)
						)
					)
					(number "34"
						(effects
							(font
								(size 1.27 1.27)
							)
						)
					)
				)
				(pin bidirectional line
					(at 30.48 -63.5 180)
					(length 2.54)
					(name "COEX_RXD"
						(effects
							(font
								(size 1.27 1.27)
							)
						)
					)
					(number "48"
						(effects
							(font
								(size 1.27 1.27)
							)
						)
					)
				)
				(pin bidirectional line
					(at 30.48 -66.04 180)
					(length 2.54)
					(name "COEX_TXD"
						(effects
							(font
								(size 1.27 1.27)
							)
						)
					)
					(number "46"
						(effects
							(font
								(size 1.27 1.27)
							)
						)
					)
				)
				(pin bidirectional line
					(at 30.48 -68.58 180)
					(length 2.54)
					(name "COEX3"
						(effects
							(font
								(size 1.27 1.27)
							)
						)
					)
					(number "44"
						(effects
							(font
								(size 1.27 1.27)
							)
						)
					)
				)
				(pin bidirectional line
					(at 30.48 -74.93 180)
					(length 2.54)
					(name "VENDOR_1"
						(effects
							(font
								(size 1.27 1.27)
							)
						)
					)
					(number "38"
						(effects
							(font
								(size 1.27 1.27)
							)
						)
					)
				)
				(pin bidirectional line
					(at 30.48 -77.47 180)
					(length 2.54)
					(name "VENDOR_2"
						(effects
							(font
								(size 1.27 1.27)
							)
						)
					)
					(number "40"
						(effects
							(font
								(size 1.27 1.27)
							)
						)
					)
				)
				(pin bidirectional line
					(at 30.48 -80.01 180)
					(length 2.54)
					(name "VENDOR_3"
						(effects
							(font
								(size 1.27 1.27)
							)
						)
					)
					(number "42"
						(effects
							(font
								(size 1.27 1.27)
							)
						)
					)
				)
				(pin output line
					(at 30.48 -85.09 180)
					(length 2.54)
					(name "~{LED_1}"
						(effects
							(font
								(size 1.27 1.27)
							)
						)
					)
					(number "6"
						(effects
							(font
								(size 1.27 1.27)
							)
						)
					)
				)
				(pin output line
					(at 30.48 -90.17 180)
					(length 2.54)
					(name "~{LED_2}"
						(effects
							(font
								(size 1.27 1.27)
							)
						)
					)
					(number "16"
						(effects
							(font
								(size 1.27 1.27)
							)
						)
					)
				)
				(pin passive line
					(at 30.48 -101.6 180)
					(length 2.54)
					(name "MP"
						(effects
							(font
								(size 1.27 1.27)
							)
						)
					)
					(number "MP"
						(effects
							(font
								(size 1.27 1.27)
							)
						)
					)
				)
				(pin power_in line
					(at 30.48 -104.14 180)
					(length 2.54)
					(name "GND"
						(effects
							(font
								(size 1.27 1.27)
							)
						)
					)
					(number "1"
						(effects
							(font
								(size 1.27 1.27)
							)
						)
					)
				)
				(pin passive line
					(at 30.48 -104.14 180)
					(length 2.54)
					(hide yes)
					(name "GND"
						(effects
							(font
								(size 1.27 1.27)
							)
						)
					)
					(number "18"
						(effects
							(font
								(size 1.27 1.27)
							)
						)
					)
				)
				(pin passive line
					(at 30.48 -104.14 180)
					(length 2.54)
					(hide yes)
					(name "GND"
						(effects
							(font
								(size 1.27 1.27)
							)
						)
					)
					(number "33"
						(effects
							(font
								(size 1.27 1.27)
							)
						)
					)
				)
				(pin passive line
					(at 30.48 -104.14 180)
					(length 2.54)
					(hide yes)
					(name "GND"
						(effects
							(font
								(size 1.27 1.27)
							)
						)
					)
					(number "39"
						(effects
							(font
								(size 1.27 1.27)
							)
						)
					)
				)
				(pin passive line
					(at 30.48 -104.14 180)
					(length 2.54)
					(hide yes)
					(name "GND"
						(effects
							(font
								(size 1.27 1.27)
							)
						)
					)
					(number "45"
						(effects
							(font
								(size 1.27 1.27)
							)
						)
					)
				)
				(pin passive line
					(at 30.48 -104.14 180)
					(length 2.54)
					(hide yes)
					(name "GND"
						(effects
							(font
								(size 1.27 1.27)
							)
						)
					)
					(number "51"
						(effects
							(font
								(size 1.27 1.27)
							)
						)
					)
				)
				(pin passive line
					(at 30.48 -104.14 180)
					(length 2.54)
					(hide yes)
					(name "GND"
						(effects
							(font
								(size 1.27 1.27)
							)
						)
					)
					(number "57"
						(effects
							(font
								(size 1.27 1.27)
							)
						)
					)
				)
				(pin passive line
					(at 30.48 -104.14 180)
					(length 2.54)
					(hide yes)
					(name "GND"
						(effects
							(font
								(size 1.27 1.27)
							)
						)
					)
					(number "63"
						(effects
							(font
								(size 1.27 1.27)
							)
						)
					)
				)
				(pin passive line
					(at 30.48 -104.14 180)
					(length 2.54)
					(hide yes)
					(name "GND"
						(effects
							(font
								(size 1.27 1.27)
							)
						)
					)
					(number "69"
						(effects
							(font
								(size 1.27 1.27)
							)
						)
					)
				)
				(pin passive line
					(at 30.48 -104.14 180)
					(length 2.54)
					(hide yes)
					(name "GND"
						(effects
							(font
								(size 1.27 1.27)
							)
						)
					)
					(number "7"
						(effects
							(font
								(size 1.27 1.27)
							)
						)
					)
				)
				(pin passive line
					(at 30.48 -104.14 180)
					(length 2.54)
					(hide yes)
					(name "GND"
						(effects
							(font
								(size 1.27 1.27)
							)
						)
					)
					(number "75"
						(effects
							(font
								(size 1.27 1.27)
							)
						)
					)
				)
			)
		)
	(symbol "antmicroPowerMeasurement:INA219AIDCNR"
			(exclude_from_sim no)
			(in_bom yes)
			(on_board yes)
			(property "Reference" "U"
				(at 25.4 -5.08 0)
				(effects
					(font
						(size 1.27 1.27)
						(thickness 0.15)
					)
					(justify left bottom)
				)
			)
			(property "Value" "INA219AIDCNR"
				(at 25.4 -10.16 0)
				(effects
					(font
						(size 1.27 1.27)
						(thickness 0.15)
					)
					(justify left bottom)
					(hide yes)
				)
			)
			(property "Footprint" "antmicro-footprints:SOT-23-8"
				(at 25.4 -12.7 0)
				(effects
					(font
						(size 1.27 1.27)
						(thickness 0.15)
					)
					(justify left bottom)
					(hide yes)
				)
			)
			(property "Datasheet" "https://www.ti.com/lit/ds/symlink/ina219.pdf?ts=1713856455637&ref_url=https%253A%252F%252Fwww.mouser.es%252F"
				(at 25.4 -15.24 0)
				(effects
					(font
						(size 1.27 1.27)
						(thickness 0.15)
					)
					(justify left bottom)
					(hide yes)
				)
			)
			(property "Description" "Zerø-Drift, Bidirectional Current/Power Monitor With I2C Interface"
				(at 25.4 -25.4 0)
				(effects
					(font
						(size 1.27 1.27)
					)
					(justify left bottom)
					(hide yes)
				)
			)
			(property "Manufacturer" "Texas Instruments"
				(at 25.4 -17.78 0)
				(effects
					(font
						(size 1.27 1.27)
						(thickness 0.15)
					)
					(justify left bottom)
					(hide yes)
				)
			)
			(property "MPN" "INA219AIDCNR"
				(at 25.4 -7.62 0)
				(effects
					(font
						(size 1.27 1.27)
						(thickness 0.15)
					)
					(justify left bottom)
				)
			)
			(property "Author" "Antmicro"
				(at 25.4 -20.32 0)
				(effects
					(font
						(size 1.27 1.27)
						(thickness 0.15)
					)
					(justify left bottom)
					(hide yes)
				)
			)
			(property "License" "Apache-2.0"
				(at 25.4 -22.86 0)
				(effects
					(font
						(size 1.27 1.27)
						(thickness 0.15)
					)
					(justify left bottom)
					(hide yes)
				)
			)
			(property "ki_keywords" "IC, PMIC, SMT, MONITOR"
				(at 0 0 0)
				(effects
					(font
						(size 1.27 1.27)
					)
					(hide yes)
				)
			)
			(symbol "INA219AIDCNR_1_1"
				(rectangle
					(start 2.54 1.27)
					(end 12.7 -13.97)
					(stroke
						(width 0.254)
						(type default)
					)
					(fill
						(type background)
					)
				)
				(pin passive line
					(at 0 0 0)
					(length 2.54)
					(name "IN+"
						(effects
							(font
								(size 1.27 1.27)
							)
						)
					)
					(number "1"
						(effects
							(font
								(size 1.27 1.27)
							)
						)
					)
				)
				(pin open_collector line
					(at 0 -5.08 0)
					(length 2.54)
					(name "SDA"
						(effects
							(font
								(size 1.27 1.27)
							)
						)
					)
					(number "6"
						(effects
							(font
								(size 1.27 1.27)
							)
						)
					)
				)
				(pin open_collector line
					(at 0 -7.62 0)
					(length 2.54)
					(name "SCL"
						(effects
							(font
								(size 1.27 1.27)
							)
						)
					)
					(number "5"
						(effects
							(font
								(size 1.27 1.27)
							)
						)
					)
				)
				(pin passive line
					(at 0 -10.16 0)
					(length 2.54)
					(name "A1"
						(effects
							(font
								(size 1.27 1.27)
							)
						)
					)
					(number "8"
						(effects
							(font
								(size 1.27 1.27)
							)
						)
					)
				)
				(pin passive line
					(at 0 -12.7 0)
					(length 2.54)
					(name "A0"
						(effects
							(font
								(size 1.27 1.27)
							)
						)
					)
					(number "7"
						(effects
							(font
								(size 1.27 1.27)
							)
						)
					)
				)
				(pin passive line
					(at 15.24 0 180)
					(length 2.54)
					(name "IN-"
						(effects
							(font
								(size 1.27 1.27)
							)
						)
					)
					(number "2"
						(effects
							(font
								(size 1.27 1.27)
							)
						)
					)
				)
				(pin power_in line
					(at 15.24 -5.08 180)
					(length 2.54)
					(name "V_{S}"
						(effects
							(font
								(size 1.27 1.27)
							)
						)
					)
					(number "4"
						(effects
							(font
								(size 1.27 1.27)
							)
						)
					)
				)
				(pin power_in line
					(at 15.24 -12.7 180)
					(length 2.54)
					(name "GND"
						(effects
							(font
								(size 1.27 1.27)
							)
						)
					)
					(number "3"
						(effects
							(font
								(size 1.27 1.27)
							)
						)
					)
				)
			)
		)
	(symbol "antmicroPushbuttonSwitches:SW_KMR211NGLFS_SMD"
			(pin_names
				(hide yes)
			)
			(exclude_from_sim no)
			(in_bom yes)
			(on_board yes)
			(property "Reference" "SW"
				(at 25.4 -2.54 0)
				(effects
					(font
						(size 1.27 1.27)
						(thickness 0.15)
					)
					(justify left bottom)
				)
			)
			(property "Value" "SW_KMR211NGLFS_SMD"
				(at 25.4 -7.62 0)
				(effects
					(font
						(size 1.27 1.27)
						(thickness 0.15)
					)
					(justify left bottom)
					(hide yes)
				)
			)
			(property "Footprint" "antmicro-footprints:SW_KMR211NGLFS_SMD"
				(at 25.4 -10.16 0)
				(effects
					(font
						(size 1.27 1.27)
						(thickness 0.15)
					)
					(justify left bottom)
					(hide yes)
				)
			)
			(property "Datasheet" "http://www.farnell.com/datasheets/2631211.pdf"
				(at 25.4 -12.7 0)
				(effects
					(font
						(size 1.27 1.27)
						(thickness 0.15)
					)
					(justify left bottom)
					(hide yes)
				)
			)
			(property "Description" "Tactile Switch, KMR 2 Series, Top Actuated, Surface Mount, Oval Button, 120 gf, 50mA at 32VDC"
				(at 25.4 -22.86 0)
				(effects
					(font
						(size 1.27 1.27)
					)
					(justify left bottom)
					(hide yes)
				)
			)
			(property "MPN" "KMR211NGLFS"
				(at 25.4 -5.08 0)
				(effects
					(font
						(size 1.27 1.27)
						(thickness 0.15)
					)
					(justify left bottom)
				)
			)
			(property "Manufacturer" "C&K"
				(at 25.4 -15.24 0)
				(effects
					(font
						(size 1.27 1.27)
						(thickness 0.15)
					)
					(justify left bottom)
					(hide yes)
				)
			)
			(property "Author" "Antmicro"
				(at 25.4 -17.78 0)
				(effects
					(font
						(size 1.27 1.27)
						(thickness 0.15)
					)
					(justify left bottom)
					(hide yes)
				)
			)
			(property "License" "Apache-2.0"
				(at 25.4 -20.32 0)
				(effects
					(font
						(size 1.27 1.27)
						(thickness 0.15)
					)
					(justify left bottom)
					(hide yes)
				)
			)
			(property "ki_keywords" "VERTICAL, SMT, SWITCH, MECHANICAL, TACTILE"
				(at 0 0 0)
				(effects
					(font
						(size 1.27 1.27)
					)
					(hide yes)
				)
			)
			(symbol "SW_KMR211NGLFS_SMD_1_1"
				(polyline
					(pts
						(xy 2.54 0) (xy 3.302 0)
					)
					(stroke
						(width 0.254)
						(type default)
					)
					(fill
						(type none)
					)
				)
				(polyline
					(pts
						(xy 2.54 -2.54) (xy 3.302 -2.54)
					)
					(stroke
						(width 0.254)
						(type default)
					)
					(fill
						(type none)
					)
				)
				(polyline
					(pts
						(xy 3.302 1.27) (xy 6.858 1.27)
					)
					(stroke
						(width 0.254)
						(type default)
					)
					(fill
						(type none)
					)
				)
				(circle
					(center 3.556 0)
					(radius 0.254)
					(stroke
						(width 0.254)
						(type default)
					)
					(fill
						(type none)
					)
				)
				(polyline
					(pts
						(xy 3.556 -0.3048) (xy 3.556 -2.1844)
					)
					(stroke
						(width 0.254)
						(type default)
					)
					(fill
						(type none)
					)
				)
				(circle
					(center 3.556 -2.54)
					(radius 0.254)
					(stroke
						(width 0.254)
						(type default)
					)
					(fill
						(type none)
					)
				)
				(polyline
					(pts
						(xy 4.064 2.794) (xy 6.096 2.794)
					)
					(stroke
						(width 0.254)
						(type default)
					)
					(fill
						(type none)
					)
				)
				(polyline
					(pts
						(xy 5.08 1.27) (xy 5.08 2.794)
					)
					(stroke
						(width 0.254)
						(type default)
					)
					(fill
						(type none)
					)
				)
				(circle
					(center 6.604 0)
					(radius 0.254)
					(stroke
						(width 0.254)
						(type default)
					)
					(fill
						(type none)
					)
				)
				(polyline
					(pts
						(xy 6.604 -0.254) (xy 6.604 -2.1844)
					)
					(stroke
						(width 0.254)
						(type default)
					)
					(fill
						(type none)
					)
				)
				(circle
					(center 6.604 -2.54)
					(radius 0.254)
					(stroke
						(width 0.254)
						(type default)
					)
					(fill
						(type none)
					)
				)
				(polyline
					(pts
						(xy 7.62 0) (xy 6.858 0)
					)
					(stroke
						(width 0.254)
						(type default)
					)
					(fill
						(type none)
					)
				)
				(polyline
					(pts
						(xy 7.62 -2.54) (xy 6.858 -2.54)
					)
					(stroke
						(width 0.254)
						(type default)
					)
					(fill
						(type none)
					)
				)
				(pin passive line
					(at 0 0 0)
					(length 2.54)
					(name "1"
						(effects
							(font
								(size 1.27 1.27)
							)
						)
					)
					(number "1"
						(effects
							(font
								(size 1.27 1.27)
							)
						)
					)
				)
				(pin passive line
					(at 0 -2.54 0)
					(length 2.54)
					(name "2"
						(effects
							(font
								(size 1.27 1.27)
							)
						)
					)
					(number "2"
						(effects
							(font
								(size 1.27 1.27)
							)
						)
					)
				)
				(pin passive line
					(at 10.16 0 180)
					(length 2.54)
					(name "3"
						(effects
							(font
								(size 1.27 1.27)
							)
						)
					)
					(number "3"
						(effects
							(font
								(size 1.27 1.27)
							)
						)
					)
				)
				(pin passive line
					(at 10.16 -2.54 180)
					(length 2.54)
					(name "4"
						(effects
							(font
								(size 1.27 1.27)
							)
						)
					)
					(number "4"
						(effects
							(font
								(size 1.27 1.27)
							)
						)
					)
				)
			)
		)
	(symbol "antmicroResistors0402:R_0R_0402"
			(pin_numbers
				(hide yes)
			)
			(pin_names
				(hide yes)
			)
			(exclude_from_sim no)
			(in_bom yes)
			(on_board yes)
			(property "Reference" "R"
				(at 20.32 -5.08 0)
				(effects
					(font
						(size 1.27 1.27)
						(thickness 0.15)
					)
					(justify left bottom)
				)
			)
			(property "Value" "R_0R_0402"
				(at 20.32 -12.7 0)
				(effects
					(font
						(size 1.27 1.27)
						(thickness 0.15)
					)
					(justify left bottom)
					(hide yes)
				)
			)
			(property "Footprint" "antmicro-footprints:R_0402_1005Metric"
				(at 20.32 -15.24 0)
				(effects
					(font
						(size 1.27 1.27)
						(thickness 0.15)
					)
					(justify left bottom)
					(hide yes)
				)
			)
			(property "Datasheet" "https://industrial.panasonic.com/cdbs/www-data/pdf/RDA0000/AOA0000C301.pdf"
				(at 20.32 -17.78 0)
				(effects
					(font
						(size 1.27 1.27)
						(thickness 0.15)
					)
					(justify left bottom)
					(hide yes)
				)
			)
			(property "Description" "SMD Chip Resistor, Jumper, 0 ohm, 100 mW, 0402 [1005 Metric], Thick Film, General Purpose"
				(at 20.32 -33.02 0)
				(effects
					(font
						(size 1.27 1.27)
					)
					(justify left bottom)
					(hide yes)
				)
			)
			(property "MPN" "ERJ2GE0R00X"
				(at 20.32 -20.32 0)
				(effects
					(font
						(size 1.27 1.27)
						(thickness 0.15)
					)
					(justify left bottom)
					(hide yes)
				)
			)
			(property "Manufacturer" "Panasonic"
				(at 20.32 -22.86 0)
				(effects
					(font
						(size 1.27 1.27)
						(thickness 0.15)
					)
					(justify left bottom)
					(hide yes)
				)
			)
			(property "License" "Apache-2.0"
				(at 20.32 -25.4 0)
				(effects
					(font
						(size 1.27 1.27)
						(thickness 0.15)
					)
					(justify left bottom)
					(hide yes)
				)
			)
			(property "Author" "Antmicro"
				(at 20.32 -27.94 0)
				(effects
					(font
						(size 1.27 1.27)
						(thickness 0.15)
					)
					(justify left bottom)
					(hide yes)
				)
			)
			(property "Val" "0R"
				(at 20.32 -7.62 0)
				(effects
					(font
						(size 1.27 1.27)
						(thickness 0.15)
					)
					(justify left bottom)
				)
			)
			(property "Tolerance" "~"
				(at 20.32 -10.16 0)
				(effects
					(font
						(size 1.27 1.27)
					)
					(justify left bottom)
					(hide yes)
				)
			)
			(property "Current" "1A"
				(at 20.32 -30.48 0)
				(effects
					(font
						(size 1.27 1.27)
						(thickness 0.15)
					)
					(justify left bottom)
					(hide yes)
				)
			)
			(property "ki_keywords" "0402, SMT, RESISTOR, PASSIVE"
				(at 0 0 0)
				(effects
					(font
						(size 1.27 1.27)
					)
					(hide yes)
				)
			)
			(symbol "R_0R_0402_0_1"
				(rectangle
					(start 0.635 0.889)
					(end 4.445 -0.889)
					(stroke
						(width 0.254)
						(type default)
					)
					(fill
						(type none)
					)
				)
			)
			(symbol "R_0R_0402_1_1"
				(pin passive line
					(at 0 0 0)
					(length 0.635)
					(name "~"
						(effects
							(font
								(size 1.27 1.27)
							)
						)
					)
					(number "1"
						(effects
							(font
								(size 1.27 1.27)
							)
						)
					)
				)
				(pin passive line
					(at 5.08 0 180)
					(length 0.635)
					(name "~"
						(effects
							(font
								(size 1.27 1.27)
							)
						)
					)
					(number "2"
						(effects
							(font
								(size 1.27 1.27)
							)
						)
					)
				)
			)
		)
	(symbol "antmicroResistors0402:R_100R_0402"
			(pin_numbers
				(hide yes)
			)
			(pin_names
				(hide yes)
			)
			(exclude_from_sim no)
			(in_bom yes)
			(on_board yes)
			(property "Reference" "R"
				(at 20.32 -5.08 0)
				(effects
					(font
						(size 1.27 1.27)
						(thickness 0.15)
					)
					(justify left bottom)
				)
			)
			(property "Value" "R_100R_0402"
				(at 20.32 -12.7 0)
				(effects
					(font
						(size 1.27 1.27)
						(thickness 0.15)
					)
					(justify left bottom)
					(hide yes)
				)
			)
			(property "Footprint" "antmicro-footprints:R_0402_1005Metric"
				(at 20.32 -15.24 0)
				(effects
					(font
						(size 1.27 1.27)
						(thickness 0.15)
					)
					(justify left bottom)
					(hide yes)
				)
			)
			(property "Datasheet" "https://www.bourns.com/docs/product-datasheets/cr.pdf"
				(at 20.32 -17.78 0)
				(effects
					(font
						(size 1.27 1.27)
						(thickness 0.15)
					)
					(justify left bottom)
					(hide yes)
				)
			)
			(property "Description" "SMD Chip Resistor, 100 ohm, ± 1%, 62.5 mW, 0402 [1005 Metric], Thick Film, General Purpose"
				(at 20.32 -30.48 0)
				(effects
					(font
						(size 1.27 1.27)
					)
					(justify left bottom)
					(hide yes)
				)
			)
			(property "MPN" "CR0402-FX-1000GLF"
				(at 20.32 -20.32 0)
				(effects
					(font
						(size 1.27 1.27)
						(thickness 0.15)
					)
					(justify left bottom)
					(hide yes)
				)
			)
			(property "Manufacturer" "Bourns"
				(at 20.32 -22.86 0)
				(effects
					(font
						(size 1.27 1.27)
						(thickness 0.15)
					)
					(justify left bottom)
					(hide yes)
				)
			)
			(property "License" "Apache-2.0"
				(at 20.32 -25.4 0)
				(effects
					(font
						(size 1.27 1.27)
						(thickness 0.15)
					)
					(justify left bottom)
					(hide yes)
				)
			)
			(property "Author" "Antmicro"
				(at 20.32 -27.94 0)
				(effects
					(font
						(size 1.27 1.27)
						(thickness 0.15)
					)
					(justify left bottom)
					(hide yes)
				)
			)
			(property "Val" "100R"
				(at 20.32 -7.62 0)
				(effects
					(font
						(size 1.27 1.27)
						(thickness 0.15)
					)
					(justify left bottom)
				)
			)
			(property "Tolerance" "1%"
				(at 20.32 -10.16 0)
				(effects
					(font
						(size 1.27 1.27)
					)
					(justify left bottom)
					(hide yes)
				)
			)
			(property "ki_keywords" "0402, SMT, RESISTOR, PASSIVE"
				(at 0 0 0)
				(effects
					(font
						(size 1.27 1.27)
					)
					(hide yes)
				)
			)
			(symbol "R_100R_0402_0_1"
				(rectangle
					(start 0.635 0.889)
					(end 4.445 -0.889)
					(stroke
						(width 0.254)
						(type default)
					)
					(fill
						(type none)
					)
				)
			)
			(symbol "R_100R_0402_1_1"
				(pin passive line
					(at 0 0 0)
					(length 0.635)
					(name "~"
						(effects
							(font
								(size 1.27 1.27)
							)
						)
					)
					(number "1"
						(effects
							(font
								(size 1.27 1.27)
							)
						)
					)
				)
				(pin passive line
					(at 5.08 0 180)
					(length 0.635)
					(name "~"
						(effects
							(font
								(size 1.27 1.27)
							)
						)
					)
					(number "2"
						(effects
							(font
								(size 1.27 1.27)
							)
						)
					)
				)
			)
		)
	(symbol "antmicroResistors0402:R_100k_0402"
			(pin_numbers
				(hide yes)
			)
			(pin_names
				(hide yes)
			)
			(exclude_from_sim no)
			(in_bom yes)
			(on_board yes)
			(property "Reference" "R"
				(at 20.32 -5.08 0)
				(effects
					(font
						(size 1.27 1.27)
						(thickness 0.15)
					)
					(justify left bottom)
				)
			)
			(property "Value" "R_100k_0402"
				(at 20.32 -12.7 0)
				(effects
					(font
						(size 1.27 1.27)
						(thickness 0.15)
					)
					(justify left bottom)
					(hide yes)
				)
			)
			(property "Footprint" "antmicro-footprints:R_0402_1005Metric"
				(at 20.32 -15.24 0)
				(effects
					(font
						(size 1.27 1.27)
						(thickness 0.15)
					)
					(justify left bottom)
					(hide yes)
				)
			)
			(property "Datasheet" "https://www.bourns.com/docs/product-datasheets/cr.pdf"
				(at 20.32 -17.78 0)
				(effects
					(font
						(size 1.27 1.27)
						(thickness 0.15)
					)
					(justify left bottom)
					(hide yes)
				)
			)
			(property "Description" "SMD Chip Resistor, 100 kohm, ± 1%, 62.5 mW, 0402 [1005 Metric], Thick Film, General Purpose"
				(at 20.32 -30.48 0)
				(effects
					(font
						(size 1.27 1.27)
					)
					(justify left bottom)
					(hide yes)
				)
			)
			(property "MPN" "CR0402-FX-1003GLF"
				(at 20.32 -20.32 0)
				(effects
					(font
						(size 1.27 1.27)
						(thickness 0.15)
					)
					(justify left bottom)
					(hide yes)
				)
			)
			(property "Manufacturer" "Bourns"
				(at 20.32 -22.86 0)
				(effects
					(font
						(size 1.27 1.27)
						(thickness 0.15)
					)
					(justify left bottom)
					(hide yes)
				)
			)
			(property "License" "Apache-2.0"
				(at 20.32 -25.4 0)
				(effects
					(font
						(size 1.27 1.27)
						(thickness 0.15)
					)
					(justify left bottom)
					(hide yes)
				)
			)
			(property "Author" "Antmicro"
				(at 20.32 -27.94 0)
				(effects
					(font
						(size 1.27 1.27)
						(thickness 0.15)
					)
					(justify left bottom)
					(hide yes)
				)
			)
			(property "Val" "100k"
				(at 20.32 -7.62 0)
				(effects
					(font
						(size 1.27 1.27)
						(thickness 0.15)
					)
					(justify left bottom)
				)
			)
			(property "Tolerance" "1%"
				(at 20.32 -10.16 0)
				(effects
					(font
						(size 1.27 1.27)
					)
					(justify left bottom)
					(hide yes)
				)
			)
			(property "ki_keywords" "0402, SMT, RESISTOR, PASSIVE"
				(at 0 0 0)
				(effects
					(font
						(size 1.27 1.27)
					)
					(hide yes)
				)
			)
			(symbol "R_100k_0402_0_1"
				(rectangle
					(start 0.635 0.889)
					(end 4.445 -0.889)
					(stroke
						(width 0.254)
						(type default)
					)
					(fill
						(type none)
					)
				)
			)
			(symbol "R_100k_0402_1_1"
				(pin passive line
					(at 0 0 0)
					(length 0.635)
					(name "~"
						(effects
							(font
								(size 1.27 1.27)
							)
						)
					)
					(number "1"
						(effects
							(font
								(size 1.27 1.27)
							)
						)
					)
				)
				(pin passive line
					(at 5.08 0 180)
					(length 0.635)
					(name "~"
						(effects
							(font
								(size 1.27 1.27)
							)
						)
					)
					(number "2"
						(effects
							(font
								(size 1.27 1.27)
							)
						)
					)
				)
			)
		)
	(symbol "antmicroResistors0402:R_10M_0402"
			(pin_numbers
				(hide yes)
			)
			(pin_names
				(hide yes)
			)
			(exclude_from_sim no)
			(in_bom yes)
			(on_board yes)
			(property "Reference" "R"
				(at 20.32 -5.08 0)
				(effects
					(font
						(size 1.27 1.27)
						(thickness 0.15)
					)
					(justify left bottom)
				)
			)
			(property "Value" "R_10M_0402"
				(at 20.32 -12.7 0)
				(effects
					(font
						(size 1.27 1.27)
						(thickness 0.15)
					)
					(justify left bottom)
					(hide yes)
				)
			)
			(property "Footprint" "antmicro-footprints:R_0402_1005Metric"
				(at 20.32 -15.24 0)
				(effects
					(font
						(size 1.27 1.27)
						(thickness 0.15)
					)
					(justify left bottom)
					(hide yes)
				)
			)
			(property "Datasheet" "https://www.bourns.com/docs/product-datasheets/cr.pdf"
				(at 20.32 -17.78 0)
				(effects
					(font
						(size 1.27 1.27)
						(thickness 0.15)
					)
					(justify left bottom)
					(hide yes)
				)
			)
			(property "Description" "SMD Chip Resistor"
				(at 20.32 -30.48 0)
				(effects
					(font
						(size 1.27 1.27)
					)
					(justify left bottom)
					(hide yes)
				)
			)
			(property "MPN" "CR0402-FX-1005GLF"
				(at 20.32 -20.32 0)
				(effects
					(font
						(size 1.27 1.27)
						(thickness 0.15)
					)
					(justify left bottom)
					(hide yes)
				)
			)
			(property "Manufacturer" "Bourns"
				(at 20.32 -22.86 0)
				(effects
					(font
						(size 1.27 1.27)
						(thickness 0.15)
					)
					(justify left bottom)
					(hide yes)
				)
			)
			(property "License" "Apache-2.0"
				(at 20.32 -25.4 0)
				(effects
					(font
						(size 1.27 1.27)
						(thickness 0.15)
					)
					(justify left bottom)
					(hide yes)
				)
			)
			(property "Author" "Antmicro"
				(at 20.32 -27.94 0)
				(effects
					(font
						(size 1.27 1.27)
						(thickness 0.15)
					)
					(justify left bottom)
					(hide yes)
				)
			)
			(property "Val" "10M"
				(at 20.32 -7.62 0)
				(effects
					(font
						(size 1.27 1.27)
						(thickness 0.15)
					)
					(justify left bottom)
				)
			)
			(property "Tolerance" "1%"
				(at 20.32 -10.16 0)
				(effects
					(font
						(size 1.27 1.27)
					)
					(justify left bottom)
					(hide yes)
				)
			)
			(property "ki_keywords" "0402, SMT, RESISTOR, PASSIVE"
				(at 0 0 0)
				(effects
					(font
						(size 1.27 1.27)
					)
					(hide yes)
				)
			)
			(symbol "R_10M_0402_0_1"
				(rectangle
					(start 0.635 0.889)
					(end 4.445 -0.889)
					(stroke
						(width 0.254)
						(type default)
					)
					(fill
						(type none)
					)
				)
			)
			(symbol "R_10M_0402_1_1"
				(pin passive line
					(at 0 0 0)
					(length 0.635)
					(name "~"
						(effects
							(font
								(size 1.27 1.27)
							)
						)
					)
					(number "1"
						(effects
							(font
								(size 1.27 1.27)
							)
						)
					)
				)
				(pin passive line
					(at 5.08 0 180)
					(length 0.635)
					(name "~"
						(effects
							(font
								(size 1.27 1.27)
							)
						)
					)
					(number "2"
						(effects
							(font
								(size 1.27 1.27)
							)
						)
					)
				)
			)
		)
	(symbol "antmicroResistors0402:R_10k_0402"
			(pin_numbers
				(hide yes)
			)
			(pin_names
				(hide yes)
			)
			(exclude_from_sim no)
			(in_bom yes)
			(on_board yes)
			(property "Reference" "R"
				(at 20.32 -5.08 0)
				(effects
					(font
						(size 1.27 1.27)
						(thickness 0.15)
					)
					(justify left bottom)
				)
			)
			(property "Value" "R_10k_0402"
				(at 20.32 -12.7 0)
				(effects
					(font
						(size 1.27 1.27)
						(thickness 0.15)
					)
					(justify left bottom)
					(hide yes)
				)
			)
			(property "Footprint" "antmicro-footprints:R_0402_1005Metric"
				(at 20.32 -15.24 0)
				(effects
					(font
						(size 1.27 1.27)
						(thickness 0.15)
					)
					(justify left bottom)
					(hide yes)
				)
			)
			(property "Datasheet" "https://www.bourns.com/docs/product-datasheets/cr.pdf"
				(at 20.32 -17.78 0)
				(effects
					(font
						(size 1.27 1.27)
						(thickness 0.15)
					)
					(justify left bottom)
					(hide yes)
				)
			)
			(property "Description" "SMD Chip Resistor, 10 kohm, ± 1%, 62.5 mW, 0402 [1005 Metric], Thick Film, General Purpose"
				(at 20.32 -30.48 0)
				(effects
					(font
						(size 1.27 1.27)
					)
					(justify left bottom)
					(hide yes)
				)
			)
			(property "MPN" "CR0402-FX-1002GLF"
				(at 20.32 -20.32 0)
				(effects
					(font
						(size 1.27 1.27)
						(thickness 0.15)
					)
					(justify left bottom)
					(hide yes)
				)
			)
			(property "Manufacturer" "Bourns"
				(at 20.32 -22.86 0)
				(effects
					(font
						(size 1.27 1.27)
						(thickness 0.15)
					)
					(justify left bottom)
					(hide yes)
				)
			)
			(property "License" "Apache-2.0"
				(at 20.32 -25.4 0)
				(effects
					(font
						(size 1.27 1.27)
						(thickness 0.15)
					)
					(justify left bottom)
					(hide yes)
				)
			)
			(property "Author" "Antmicro"
				(at 20.32 -27.94 0)
				(effects
					(font
						(size 1.27 1.27)
						(thickness 0.15)
					)
					(justify left bottom)
					(hide yes)
				)
			)
			(property "Val" "10k"
				(at 20.32 -7.62 0)
				(effects
					(font
						(size 1.27 1.27)
						(thickness 0.15)
					)
					(justify left bottom)
				)
			)
			(property "Tolerance" "1%"
				(at 20.32 -10.16 0)
				(effects
					(font
						(size 1.27 1.27)
					)
					(justify left bottom)
					(hide yes)
				)
			)
			(property "ki_keywords" "0402, SMT, RESISTOR, PASSIVE"
				(at 0 0 0)
				(effects
					(font
						(size 1.27 1.27)
					)
					(hide yes)
				)
			)
			(symbol "R_10k_0402_0_1"
				(rectangle
					(start 0.635 0.889)
					(end 4.445 -0.889)
					(stroke
						(width 0.254)
						(type default)
					)
					(fill
						(type none)
					)
				)
			)
			(symbol "R_10k_0402_1_1"
				(pin passive line
					(at 0 0 0)
					(length 0.635)
					(name "~"
						(effects
							(font
								(size 1.27 1.27)
							)
						)
					)
					(number "1"
						(effects
							(font
								(size 1.27 1.27)
							)
						)
					)
				)
				(pin passive line
					(at 5.08 0 180)
					(length 0.635)
					(name "~"
						(effects
							(font
								(size 1.27 1.27)
							)
						)
					)
					(number "2"
						(effects
							(font
								(size 1.27 1.27)
							)
						)
					)
				)
			)
		)
	(symbol "antmicroResistors0402:R_11k8_0402"
			(pin_numbers
				(hide yes)
			)
			(pin_names
				(hide yes)
			)
			(exclude_from_sim no)
			(in_bom yes)
			(on_board yes)
			(property "Reference" "R"
				(at 20.32 -5.08 0)
				(effects
					(font
						(size 1.27 1.27)
						(thickness 0.15)
					)
					(justify left bottom)
				)
			)
			(property "Value" "R_11k8_0402"
				(at 20.32 -12.7 0)
				(effects
					(font
						(size 1.27 1.27)
						(thickness 0.15)
					)
					(justify left bottom)
					(hide yes)
				)
			)
			(property "Footprint" "antmicro-footprints:R_0402_1005Metric"
				(at 20.32 -15.24 0)
				(effects
					(font
						(size 1.27 1.27)
						(thickness 0.15)
					)
					(justify left bottom)
					(hide yes)
				)
			)
			(property "Datasheet" "https://www.bourns.com/docs/product-datasheets/cr.pdf"
				(at 20.32 -17.78 0)
				(effects
					(font
						(size 1.27 1.27)
						(thickness 0.15)
					)
					(justify left bottom)
					(hide yes)
				)
			)
			(property "Description" "SMD Chip Resistor, 11.8 kohm, ± 1%, 100 mW, 0402 [1005 Metric], Thick Film, Precision"
				(at 20.32 -30.48 0)
				(effects
					(font
						(size 1.27 1.27)
					)
					(justify left bottom)
					(hide yes)
				)
			)
			(property "MPN" "CR0402-FX-1182GLF"
				(at 20.32 -20.32 0)
				(effects
					(font
						(size 1.27 1.27)
						(thickness 0.15)
					)
					(justify left bottom)
					(hide yes)
				)
			)
			(property "Manufacturer" "Bourns"
				(at 20.32 -22.86 0)
				(effects
					(font
						(size 1.27 1.27)
						(thickness 0.15)
					)
					(justify left bottom)
					(hide yes)
				)
			)
			(property "License" "Apache-2.0"
				(at 20.32 -25.4 0)
				(effects
					(font
						(size 1.27 1.27)
						(thickness 0.15)
					)
					(justify left bottom)
					(hide yes)
				)
			)
			(property "Author" "Antmicro"
				(at 20.32 -27.94 0)
				(effects
					(font
						(size 1.27 1.27)
						(thickness 0.15)
					)
					(justify left bottom)
					(hide yes)
				)
			)
			(property "Val" "11k8"
				(at 20.32 -7.62 0)
				(effects
					(font
						(size 1.27 1.27)
						(thickness 0.15)
					)
					(justify left bottom)
				)
			)
			(property "Tolerance" "1%"
				(at 20.32 -10.16 0)
				(effects
					(font
						(size 1.27 1.27)
					)
					(justify left bottom)
					(hide yes)
				)
			)
			(property "ki_keywords" "0402, SMT, RESISTOR, PASSIVE"
				(at 0 0 0)
				(effects
					(font
						(size 1.27 1.27)
					)
					(hide yes)
				)
			)
			(symbol "R_11k8_0402_0_1"
				(rectangle
					(start 0.635 0.889)
					(end 4.445 -0.889)
					(stroke
						(width 0.254)
						(type default)
					)
					(fill
						(type none)
					)
				)
			)
			(symbol "R_11k8_0402_1_1"
				(pin passive line
					(at 0 0 0)
					(length 0.635)
					(name "~"
						(effects
							(font
								(size 1.27 1.27)
							)
						)
					)
					(number "1"
						(effects
							(font
								(size 1.27 1.27)
							)
						)
					)
				)
				(pin passive line
					(at 5.08 0 180)
					(length 0.635)
					(name "~"
						(effects
							(font
								(size 1.27 1.27)
							)
						)
					)
					(number "2"
						(effects
							(font
								(size 1.27 1.27)
							)
						)
					)
				)
			)
		)
	(symbol "antmicroResistors0402:R_11k_0402"
			(pin_numbers
				(hide yes)
			)
			(pin_names
				(hide yes)
			)
			(exclude_from_sim no)
			(in_bom yes)
			(on_board yes)
			(property "Reference" "R"
				(at 20.32 -5.08 0)
				(effects
					(font
						(size 1.27 1.27)
						(thickness 0.15)
					)
					(justify left bottom)
				)
			)
			(property "Value" "R_11k_0402"
				(at 20.32 -12.7 0)
				(effects
					(font
						(size 1.27 1.27)
						(thickness 0.15)
					)
					(justify left bottom)
					(hide yes)
				)
			)
			(property "Footprint" "antmicro-footprints:R_0402_1005Metric"
				(at 20.32 -15.24 0)
				(effects
					(font
						(size 1.27 1.27)
						(thickness 0.15)
					)
					(justify left bottom)
					(hide yes)
				)
			)
			(property "Datasheet" "https://www.bourns.com/docs/product-datasheets/cr.pdf"
				(at 20.32 -17.78 0)
				(effects
					(font
						(size 1.27 1.27)
						(thickness 0.15)
					)
					(justify left bottom)
					(hide yes)
				)
			)
			(property "Description" "SMD Chip Resistor, 11 kohm, ± 1%, 62.5 mW, 0402 [1005 Metric], Thick Film, General Purpose"
				(at 20.32 -30.48 0)
				(effects
					(font
						(size 1.27 1.27)
					)
					(justify left bottom)
					(hide yes)
				)
			)
			(property "MPN" "CR0402-FX-1102GLF"
				(at 20.32 -20.32 0)
				(effects
					(font
						(size 1.27 1.27)
						(thickness 0.15)
					)
					(justify left bottom)
					(hide yes)
				)
			)
			(property "Manufacturer" "Bourns"
				(at 20.32 -22.86 0)
				(effects
					(font
						(size 1.27 1.27)
						(thickness 0.15)
					)
					(justify left bottom)
					(hide yes)
				)
			)
			(property "License" "Apache-2.0"
				(at 20.32 -25.4 0)
				(effects
					(font
						(size 1.27 1.27)
						(thickness 0.15)
					)
					(justify left bottom)
					(hide yes)
				)
			)
			(property "Author" "Antmicro"
				(at 20.32 -27.94 0)
				(effects
					(font
						(size 1.27 1.27)
						(thickness 0.15)
					)
					(justify left bottom)
					(hide yes)
				)
			)
			(property "Val" "11k"
				(at 20.32 -7.62 0)
				(effects
					(font
						(size 1.27 1.27)
						(thickness 0.15)
					)
					(justify left bottom)
				)
			)
			(property "Tolerance" "1%"
				(at 20.32 -10.16 0)
				(effects
					(font
						(size 1.27 1.27)
					)
					(justify left bottom)
					(hide yes)
				)
			)
			(property "ki_keywords" "0402, SMT, RESISTOR, PASSIVE"
				(at 0 0 0)
				(effects
					(font
						(size 1.27 1.27)
					)
					(hide yes)
				)
			)
			(symbol "R_11k_0402_0_1"
				(rectangle
					(start 0.635 0.889)
					(end 4.445 -0.889)
					(stroke
						(width 0.254)
						(type default)
					)
					(fill
						(type none)
					)
				)
			)
			(symbol "R_11k_0402_1_1"
				(pin passive line
					(at 0 0 0)
					(length 0.635)
					(name "~"
						(effects
							(font
								(size 1.27 1.27)
							)
						)
					)
					(number "1"
						(effects
							(font
								(size 1.27 1.27)
							)
						)
					)
				)
				(pin passive line
					(at 5.08 0 180)
					(length 0.635)
					(name "~"
						(effects
							(font
								(size 1.27 1.27)
							)
						)
					)
					(number "2"
						(effects
							(font
								(size 1.27 1.27)
							)
						)
					)
				)
			)
		)
	(symbol "antmicroResistors0402:R_124k_0402"
			(pin_numbers
				(hide yes)
			)
			(pin_names
				(hide yes)
			)
			(exclude_from_sim no)
			(in_bom yes)
			(on_board yes)
			(property "Reference" "R"
				(at 20.32 -5.08 0)
				(effects
					(font
						(size 1.27 1.27)
						(thickness 0.15)
					)
					(justify left bottom)
				)
			)
			(property "Value" "R_124k_0402"
				(at 20.32 -12.7 0)
				(effects
					(font
						(size 1.27 1.27)
						(thickness 0.15)
					)
					(justify left bottom)
					(hide yes)
				)
			)
			(property "Footprint" "antmicro-footprints:R_0402_1005Metric"
				(at 20.32 -15.24 0)
				(effects
					(font
						(size 1.27 1.27)
						(thickness 0.15)
					)
					(justify left bottom)
					(hide yes)
				)
			)
			(property "Datasheet" "https://www.bourns.com/docs/product-datasheets/cr.pdf"
				(at 20.32 -17.78 0)
				(effects
					(font
						(size 1.27 1.27)
						(thickness 0.15)
					)
					(justify left bottom)
					(hide yes)
				)
			)
			(property "Description" "SMD Chip Resistor, 124 kohm, ± 1%, 100 mW, 0402 [1005 Metric], Thick Film, Precision"
				(at 20.32 -30.48 0)
				(effects
					(font
						(size 1.27 1.27)
					)
					(justify left bottom)
					(hide yes)
				)
			)
			(property "MPN" "CR0402-FX-1243GLF"
				(at 20.32 -20.32 0)
				(effects
					(font
						(size 1.27 1.27)
						(thickness 0.15)
					)
					(justify left bottom)
					(hide yes)
				)
			)
			(property "Manufacturer" "Bourns"
				(at 20.32 -22.86 0)
				(effects
					(font
						(size 1.27 1.27)
						(thickness 0.15)
					)
					(justify left bottom)
					(hide yes)
				)
			)
			(property "License" "Apache-2.0"
				(at 20.32 -25.4 0)
				(effects
					(font
						(size 1.27 1.27)
						(thickness 0.15)
					)
					(justify left bottom)
					(hide yes)
				)
			)
			(property "Author" "Antmicro"
				(at 20.32 -27.94 0)
				(effects
					(font
						(size 1.27 1.27)
						(thickness 0.15)
					)
					(justify left bottom)
					(hide yes)
				)
			)
			(property "Val" "124k"
				(at 20.32 -7.62 0)
				(effects
					(font
						(size 1.27 1.27)
						(thickness 0.15)
					)
					(justify left bottom)
				)
			)
			(property "Tolerance" "1%"
				(at 20.32 -10.16 0)
				(effects
					(font
						(size 1.27 1.27)
					)
					(justify left bottom)
					(hide yes)
				)
			)
			(property "ki_keywords" "0402, SMT, RESISTOR, PASSIVE"
				(at 0 0 0)
				(effects
					(font
						(size 1.27 1.27)
					)
					(hide yes)
				)
			)
			(symbol "R_124k_0402_0_1"
				(rectangle
					(start 0.635 0.889)
					(end 4.445 -0.889)
					(stroke
						(width 0.254)
						(type default)
					)
					(fill
						(type none)
					)
				)
			)
			(symbol "R_124k_0402_1_1"
				(pin passive line
					(at 0 0 0)
					(length 0.635)
					(name "~"
						(effects
							(font
								(size 1.27 1.27)
							)
						)
					)
					(number "1"
						(effects
							(font
								(size 1.27 1.27)
							)
						)
					)
				)
				(pin passive line
					(at 5.08 0 180)
					(length 0.635)
					(name "~"
						(effects
							(font
								(size 1.27 1.27)
							)
						)
					)
					(number "2"
						(effects
							(font
								(size 1.27 1.27)
							)
						)
					)
				)
			)
		)
	(symbol "antmicroResistors0402:R_12k_0402"
			(pin_numbers
				(hide yes)
			)
			(pin_names
				(hide yes)
			)
			(exclude_from_sim no)
			(in_bom yes)
			(on_board yes)
			(property "Reference" "R"
				(at 20.32 -5.08 0)
				(effects
					(font
						(size 1.27 1.27)
						(thickness 0.15)
					)
					(justify left bottom)
				)
			)
			(property "Value" "R_12k_0402"
				(at 20.32 -12.7 0)
				(effects
					(font
						(size 1.27 1.27)
						(thickness 0.15)
					)
					(justify left bottom)
					(hide yes)
				)
			)
			(property "Footprint" "antmicro-footprints:R_0402_1005Metric"
				(at 20.32 -15.24 0)
				(effects
					(font
						(size 1.27 1.27)
						(thickness 0.15)
					)
					(justify left bottom)
					(hide yes)
				)
			)
			(property "Datasheet" "https://www.bourns.com/docs/product-datasheets/cr.pdf"
				(at 20.32 -17.78 0)
				(effects
					(font
						(size 1.27 1.27)
						(thickness 0.15)
					)
					(justify left bottom)
					(hide yes)
				)
			)
			(property "Description" "SMD Chip Resistor, 12 kohm, ± 1%, 62.5 mW, 0402 [1005 Metric], Thick Film, General Purpose"
				(at 20.32 -30.48 0)
				(effects
					(font
						(size 1.27 1.27)
					)
					(justify left bottom)
					(hide yes)
				)
			)
			(property "MPN" "CR0402-FX-1202GLF"
				(at 20.32 -20.32 0)
				(effects
					(font
						(size 1.27 1.27)
						(thickness 0.15)
					)
					(justify left bottom)
					(hide yes)
				)
			)
			(property "Manufacturer" "Bourns"
				(at 20.32 -22.86 0)
				(effects
					(font
						(size 1.27 1.27)
						(thickness 0.15)
					)
					(justify left bottom)
					(hide yes)
				)
			)
			(property "License" "Apache-2.0"
				(at 20.32 -25.4 0)
				(effects
					(font
						(size 1.27 1.27)
						(thickness 0.15)
					)
					(justify left bottom)
					(hide yes)
				)
			)
			(property "Author" "Antmicro"
				(at 20.32 -27.94 0)
				(effects
					(font
						(size 1.27 1.27)
						(thickness 0.15)
					)
					(justify left bottom)
					(hide yes)
				)
			)
			(property "Val" "12k"
				(at 20.32 -7.62 0)
				(effects
					(font
						(size 1.27 1.27)
						(thickness 0.15)
					)
					(justify left bottom)
				)
			)
			(property "Tolerance" "1%"
				(at 20.32 -10.16 0)
				(effects
					(font
						(size 1.27 1.27)
					)
					(justify left bottom)
					(hide yes)
				)
			)
			(property "ki_keywords" "0402, SMT, RESISTOR, PASSIVE"
				(at 0 0 0)
				(effects
					(font
						(size 1.27 1.27)
					)
					(hide yes)
				)
			)
			(symbol "R_12k_0402_0_1"
				(rectangle
					(start 0.635 0.889)
					(end 4.445 -0.889)
					(stroke
						(width 0.254)
						(type default)
					)
					(fill
						(type none)
					)
				)
			)
			(symbol "R_12k_0402_1_1"
				(pin passive line
					(at 0 0 0)
					(length 0.635)
					(name "~"
						(effects
							(font
								(size 1.27 1.27)
							)
						)
					)
					(number "1"
						(effects
							(font
								(size 1.27 1.27)
							)
						)
					)
				)
				(pin passive line
					(at 5.08 0 180)
					(length 0.635)
					(name "~"
						(effects
							(font
								(size 1.27 1.27)
							)
						)
					)
					(number "2"
						(effects
							(font
								(size 1.27 1.27)
							)
						)
					)
				)
			)
		)
	(symbol "antmicroResistors0402:R_15k_0402"
			(pin_numbers
				(hide yes)
			)
			(pin_names
				(hide yes)
			)
			(exclude_from_sim no)
			(in_bom yes)
			(on_board yes)
			(property "Reference" "R"
				(at 20.32 -5.08 0)
				(effects
					(font
						(size 1.27 1.27)
						(thickness 0.15)
					)
					(justify left bottom)
				)
			)
			(property "Value" "R_15k_0402"
				(at 20.32 -12.7 0)
				(effects
					(font
						(size 1.27 1.27)
						(thickness 0.15)
					)
					(justify left bottom)
					(hide yes)
				)
			)
			(property "Footprint" "antmicro-footprints:R_0402_1005Metric"
				(at 20.32 -15.24 0)
				(effects
					(font
						(size 1.27 1.27)
						(thickness 0.15)
					)
					(justify left bottom)
					(hide yes)
				)
			)
			(property "Datasheet" "https://www.bourns.com/docs/product-datasheets/cr.pdf"
				(at 20.32 -17.78 0)
				(effects
					(font
						(size 1.27 1.27)
						(thickness 0.15)
					)
					(justify left bottom)
					(hide yes)
				)
			)
			(property "Description" "SMD Chip Resistor, 15 kohm, ± 1%, 62.5 mW, 0402 [1005 Metric], Thick Film, General Purpose"
				(at 20.32 -30.48 0)
				(effects
					(font
						(size 1.27 1.27)
					)
					(justify left bottom)
					(hide yes)
				)
			)
			(property "MPN" "CR0402-FX-1502GLF"
				(at 20.32 -20.32 0)
				(effects
					(font
						(size 1.27 1.27)
						(thickness 0.15)
					)
					(justify left bottom)
					(hide yes)
				)
			)
			(property "Manufacturer" "Bourns"
				(at 20.32 -22.86 0)
				(effects
					(font
						(size 1.27 1.27)
						(thickness 0.15)
					)
					(justify left bottom)
					(hide yes)
				)
			)
			(property "License" "Apache-2.0"
				(at 20.32 -25.4 0)
				(effects
					(font
						(size 1.27 1.27)
						(thickness 0.15)
					)
					(justify left bottom)
					(hide yes)
				)
			)
			(property "Author" "Antmicro"
				(at 20.32 -27.94 0)
				(effects
					(font
						(size 1.27 1.27)
						(thickness 0.15)
					)
					(justify left bottom)
					(hide yes)
				)
			)
			(property "Val" "15k"
				(at 20.32 -7.62 0)
				(effects
					(font
						(size 1.27 1.27)
						(thickness 0.15)
					)
					(justify left bottom)
				)
			)
			(property "Tolerance" "1%"
				(at 20.32 -10.16 0)
				(effects
					(font
						(size 1.27 1.27)
					)
					(justify left bottom)
					(hide yes)
				)
			)
			(property "ki_keywords" "0402, SMT, RESISTOR, PASSIVE"
				(at 0 0 0)
				(effects
					(font
						(size 1.27 1.27)
					)
					(hide yes)
				)
			)
			(symbol "R_15k_0402_0_1"
				(rectangle
					(start 0.635 0.889)
					(end 4.445 -0.889)
					(stroke
						(width 0.254)
						(type default)
					)
					(fill
						(type none)
					)
				)
			)
			(symbol "R_15k_0402_1_1"
				(pin passive line
					(at 0 0 0)
					(length 0.635)
					(name "~"
						(effects
							(font
								(size 1.27 1.27)
							)
						)
					)
					(number "1"
						(effects
							(font
								(size 1.27 1.27)
							)
						)
					)
				)
				(pin passive line
					(at 5.08 0 180)
					(length 0.635)
					(name "~"
						(effects
							(font
								(size 1.27 1.27)
							)
						)
					)
					(number "2"
						(effects
							(font
								(size 1.27 1.27)
							)
						)
					)
				)
			)
		)
	(symbol "antmicroResistors0402:R_191k_0402"
			(pin_numbers
				(hide yes)
			)
			(pin_names
				(hide yes)
			)
			(exclude_from_sim no)
			(in_bom yes)
			(on_board yes)
			(property "Reference" "R"
				(at 20.32 -5.08 0)
				(effects
					(font
						(size 1.27 1.27)
						(thickness 0.15)
					)
					(justify left bottom)
				)
			)
			(property "Value" "R_191k_0402"
				(at 20.32 -12.7 0)
				(effects
					(font
						(size 1.27 1.27)
						(thickness 0.15)
					)
					(justify left bottom)
					(hide yes)
				)
			)
			(property "Footprint" "antmicro-footprints:R_0402_1005Metric"
				(at 20.32 -15.24 0)
				(effects
					(font
						(size 1.27 1.27)
						(thickness 0.15)
					)
					(justify left bottom)
					(hide yes)
				)
			)
			(property "Datasheet" "https://www.bourns.com/docs/product-datasheets/cr.pdf"
				(at 20.32 -17.78 0)
				(effects
					(font
						(size 1.27 1.27)
						(thickness 0.15)
					)
					(justify left bottom)
					(hide yes)
				)
			)
			(property "Description" "SMD Chip Resistor, 191 kohm, ± 1%, 100 mW, 0402 [1005 Metric], Thick Film, Precision"
				(at 20.32 -30.48 0)
				(effects
					(font
						(size 1.27 1.27)
					)
					(justify left bottom)
					(hide yes)
				)
			)
			(property "MPN" "CR0402-FX-1913GLF"
				(at 20.32 -20.32 0)
				(effects
					(font
						(size 1.27 1.27)
						(thickness 0.15)
					)
					(justify left bottom)
					(hide yes)
				)
			)
			(property "Manufacturer" "Bourns"
				(at 20.32 -22.86 0)
				(effects
					(font
						(size 1.27 1.27)
						(thickness 0.15)
					)
					(justify left bottom)
					(hide yes)
				)
			)
			(property "License" "Apache-2.0"
				(at 20.32 -25.4 0)
				(effects
					(font
						(size 1.27 1.27)
						(thickness 0.15)
					)
					(justify left bottom)
					(hide yes)
				)
			)
			(property "Author" "Antmicro"
				(at 20.32 -27.94 0)
				(effects
					(font
						(size 1.27 1.27)
						(thickness 0.15)
					)
					(justify left bottom)
					(hide yes)
				)
			)
			(property "Val" "191k"
				(at 20.32 -7.62 0)
				(effects
					(font
						(size 1.27 1.27)
						(thickness 0.15)
					)
					(justify left bottom)
				)
			)
			(property "Tolerance" "1%"
				(at 20.32 -10.16 0)
				(effects
					(font
						(size 1.27 1.27)
					)
					(justify left bottom)
					(hide yes)
				)
			)
			(property "ki_keywords" "0402, SMT, RESISTOR, PASSIVE"
				(at 0 0 0)
				(effects
					(font
						(size 1.27 1.27)
					)
					(hide yes)
				)
			)
			(symbol "R_191k_0402_0_1"
				(rectangle
					(start 0.635 0.889)
					(end 4.445 -0.889)
					(stroke
						(width 0.254)
						(type default)
					)
					(fill
						(type none)
					)
				)
			)
			(symbol "R_191k_0402_1_1"
				(pin passive line
					(at 0 0 0)
					(length 0.635)
					(name "~"
						(effects
							(font
								(size 1.27 1.27)
							)
						)
					)
					(number "1"
						(effects
							(font
								(size 1.27 1.27)
							)
						)
					)
				)
				(pin passive line
					(at 5.08 0 180)
					(length 0.635)
					(name "~"
						(effects
							(font
								(size 1.27 1.27)
							)
						)
					)
					(number "2"
						(effects
							(font
								(size 1.27 1.27)
							)
						)
					)
				)
			)
		)
	(symbol "antmicroResistors0402:R_1k_0402"
			(pin_numbers
				(hide yes)
			)
			(pin_names
				(hide yes)
			)
			(exclude_from_sim no)
			(in_bom yes)
			(on_board yes)
			(property "Reference" "R"
				(at 20.32 -5.08 0)
				(effects
					(font
						(size 1.27 1.27)
						(thickness 0.15)
					)
					(justify left bottom)
				)
			)
			(property "Value" "R_1k_0402"
				(at 20.32 -12.7 0)
				(effects
					(font
						(size 1.27 1.27)
						(thickness 0.15)
					)
					(justify left bottom)
					(hide yes)
				)
			)
			(property "Footprint" "antmicro-footprints:R_0402_1005Metric"
				(at 20.32 -15.24 0)
				(effects
					(font
						(size 1.27 1.27)
						(thickness 0.15)
					)
					(justify left bottom)
					(hide yes)
				)
			)
			(property "Datasheet" "https://www.bourns.com/docs/product-datasheets/cr.pdf"
				(at 20.32 -17.78 0)
				(effects
					(font
						(size 1.27 1.27)
						(thickness 0.15)
					)
					(justify left bottom)
					(hide yes)
				)
			)
			(property "Description" "SMD Chip Resistor, 1 kohm, ± 1%, 63 mW, 0402 [1005 Metric], Thick Film, General Purpose"
				(at 20.32 -30.48 0)
				(effects
					(font
						(size 1.27 1.27)
					)
					(justify left bottom)
					(hide yes)
				)
			)
			(property "MPN" "CR0402-FX-1001GLF"
				(at 20.32 -20.32 0)
				(effects
					(font
						(size 1.27 1.27)
						(thickness 0.15)
					)
					(justify left bottom)
					(hide yes)
				)
			)
			(property "Manufacturer" "Bourns"
				(at 20.32 -22.86 0)
				(effects
					(font
						(size 1.27 1.27)
						(thickness 0.15)
					)
					(justify left bottom)
					(hide yes)
				)
			)
			(property "License" "Apache-2.0"
				(at 20.32 -25.4 0)
				(effects
					(font
						(size 1.27 1.27)
						(thickness 0.15)
					)
					(justify left bottom)
					(hide yes)
				)
			)
			(property "Author" "Antmicro"
				(at 20.32 -27.94 0)
				(effects
					(font
						(size 1.27 1.27)
						(thickness 0.15)
					)
					(justify left bottom)
					(hide yes)
				)
			)
			(property "Val" "1k"
				(at 20.32 -7.62 0)
				(effects
					(font
						(size 1.27 1.27)
						(thickness 0.15)
					)
					(justify left bottom)
				)
			)
			(property "Tolerance" "1%"
				(at 20.32 -10.16 0)
				(effects
					(font
						(size 1.27 1.27)
					)
					(justify left bottom)
					(hide yes)
				)
			)
			(property "ki_keywords" "0402, SMT, RESISTOR, PASSIVE"
				(at 0 0 0)
				(effects
					(font
						(size 1.27 1.27)
					)
					(hide yes)
				)
			)
			(symbol "R_1k_0402_0_1"
				(rectangle
					(start 0.635 0.889)
					(end 4.445 -0.889)
					(stroke
						(width 0.254)
						(type default)
					)
					(fill
						(type none)
					)
				)
			)
			(symbol "R_1k_0402_1_1"
				(pin passive line
					(at 0 0 0)
					(length 0.635)
					(name "~"
						(effects
							(font
								(size 1.27 1.27)
							)
						)
					)
					(number "1"
						(effects
							(font
								(size 1.27 1.27)
							)
						)
					)
				)
				(pin passive line
					(at 5.08 0 180)
					(length 0.635)
					(name "~"
						(effects
							(font
								(size 1.27 1.27)
							)
						)
					)
					(number "2"
						(effects
							(font
								(size 1.27 1.27)
							)
						)
					)
				)
			)
		)
	(symbol "antmicroResistors0402:R_200R_0402"
			(pin_numbers
				(hide yes)
			)
			(pin_names
				(hide yes)
			)
			(exclude_from_sim no)
			(in_bom yes)
			(on_board yes)
			(property "Reference" "R"
				(at 20.32 -5.08 0)
				(effects
					(font
						(size 1.27 1.27)
						(thickness 0.15)
					)
					(justify left bottom)
				)
			)
			(property "Value" "R_200R_0402"
				(at 20.32 -12.7 0)
				(effects
					(font
						(size 1.27 1.27)
						(thickness 0.15)
					)
					(justify left bottom)
					(hide yes)
				)
			)
			(property "Footprint" "antmicro-footprints:R_0402_1005Metric"
				(at 20.32 -15.24 0)
				(effects
					(font
						(size 1.27 1.27)
						(thickness 0.15)
					)
					(justify left bottom)
					(hide yes)
				)
			)
			(property "Datasheet" "https://www.bourns.com/docs/product-datasheets/cr.pdf"
				(at 20.32 -17.78 0)
				(effects
					(font
						(size 1.27 1.27)
						(thickness 0.15)
					)
					(justify left bottom)
					(hide yes)
				)
			)
			(property "Description" "SMD Chip Resistor, 200 ohm, ± 1%, 62.5 mW, 0402 [1005 Metric], Thick Film, General Purpose"
				(at 20.32 -30.48 0)
				(effects
					(font
						(size 1.27 1.27)
					)
					(justify left bottom)
					(hide yes)
				)
			)
			(property "MPN" "CR0402-FX-2000GLF"
				(at 20.32 -20.32 0)
				(effects
					(font
						(size 1.27 1.27)
						(thickness 0.15)
					)
					(justify left bottom)
					(hide yes)
				)
			)
			(property "Manufacturer" "Bourns"
				(at 20.32 -22.86 0)
				(effects
					(font
						(size 1.27 1.27)
						(thickness 0.15)
					)
					(justify left bottom)
					(hide yes)
				)
			)
			(property "License" "Apache-2.0"
				(at 20.32 -25.4 0)
				(effects
					(font
						(size 1.27 1.27)
						(thickness 0.15)
					)
					(justify left bottom)
					(hide yes)
				)
			)
			(property "Author" "Antmicro"
				(at 20.32 -27.94 0)
				(effects
					(font
						(size 1.27 1.27)
						(thickness 0.15)
					)
					(justify left bottom)
					(hide yes)
				)
			)
			(property "Val" "200R"
				(at 20.32 -7.62 0)
				(effects
					(font
						(size 1.27 1.27)
						(thickness 0.15)
					)
					(justify left bottom)
				)
			)
			(property "Tolerance" "1%"
				(at 20.32 -10.16 0)
				(effects
					(font
						(size 1.27 1.27)
					)
					(justify left bottom)
					(hide yes)
				)
			)
			(property "ki_keywords" "0402, SMT, RESISTOR, PASSIVE"
				(at 0 0 0)
				(effects
					(font
						(size 1.27 1.27)
					)
					(hide yes)
				)
			)
			(symbol "R_200R_0402_0_1"
				(rectangle
					(start 0.635 0.889)
					(end 4.445 -0.889)
					(stroke
						(width 0.254)
						(type default)
					)
					(fill
						(type none)
					)
				)
			)
			(symbol "R_200R_0402_1_1"
				(pin passive line
					(at 0 0 0)
					(length 0.635)
					(name "~"
						(effects
							(font
								(size 1.27 1.27)
							)
						)
					)
					(number "1"
						(effects
							(font
								(size 1.27 1.27)
							)
						)
					)
				)
				(pin passive line
					(at 5.08 0 180)
					(length 0.635)
					(name "~"
						(effects
							(font
								(size 1.27 1.27)
							)
						)
					)
					(number "2"
						(effects
							(font
								(size 1.27 1.27)
							)
						)
					)
				)
			)
		)
	(symbol "antmicroResistors0402:R_200k_0402"
			(pin_numbers
				(hide yes)
			)
			(pin_names
				(hide yes)
			)
			(exclude_from_sim no)
			(in_bom yes)
			(on_board yes)
			(property "Reference" "R"
				(at 20.32 -5.08 0)
				(effects
					(font
						(size 1.27 1.27)
						(thickness 0.15)
					)
					(justify left bottom)
				)
			)
			(property "Value" "R_200k_0402"
				(at 20.32 -12.7 0)
				(effects
					(font
						(size 1.27 1.27)
						(thickness 0.15)
					)
					(justify left bottom)
					(hide yes)
				)
			)
			(property "Footprint" "antmicro-footprints:R_0402_1005Metric"
				(at 20.32 -15.24 0)
				(effects
					(font
						(size 1.27 1.27)
						(thickness 0.15)
					)
					(justify left bottom)
					(hide yes)
				)
			)
			(property "Datasheet" "https://www.bourns.com/docs/product-datasheets/cr.pdf"
				(at 20.32 -17.78 0)
				(effects
					(font
						(size 1.27 1.27)
						(thickness 0.15)
					)
					(justify left bottom)
					(hide yes)
				)
			)
			(property "Description" "SMD Chip Resistor, 200 kohm, ± 1%, 62.5 mW, 0402 [1005 Metric], Thick Film, General Purpose"
				(at 20.32 -30.48 0)
				(effects
					(font
						(size 1.27 1.27)
					)
					(justify left bottom)
					(hide yes)
				)
			)
			(property "MPN" "CR0402-FX-2003GLF"
				(at 20.32 -20.32 0)
				(effects
					(font
						(size 1.27 1.27)
						(thickness 0.15)
					)
					(justify left bottom)
					(hide yes)
				)
			)
			(property "Manufacturer" "Bourns"
				(at 20.32 -22.86 0)
				(effects
					(font
						(size 1.27 1.27)
						(thickness 0.15)
					)
					(justify left bottom)
					(hide yes)
				)
			)
			(property "License" "Apache-2.0"
				(at 20.32 -25.4 0)
				(effects
					(font
						(size 1.27 1.27)
						(thickness 0.15)
					)
					(justify left bottom)
					(hide yes)
				)
			)
			(property "Author" "Antmicro"
				(at 20.32 -27.94 0)
				(effects
					(font
						(size 1.27 1.27)
						(thickness 0.15)
					)
					(justify left bottom)
					(hide yes)
				)
			)
			(property "Val" "200k"
				(at 20.32 -7.62 0)
				(effects
					(font
						(size 1.27 1.27)
						(thickness 0.15)
					)
					(justify left bottom)
				)
			)
			(property "Tolerance" "1%"
				(at 20.32 -10.16 0)
				(effects
					(font
						(size 1.27 1.27)
					)
					(justify left bottom)
					(hide yes)
				)
			)
			(property "ki_keywords" "0402, SMT, RESISTOR, PASSIVE"
				(at 0 0 0)
				(effects
					(font
						(size 1.27 1.27)
					)
					(hide yes)
				)
			)
			(symbol "R_200k_0402_0_1"
				(rectangle
					(start 0.635 0.889)
					(end 4.445 -0.889)
					(stroke
						(width 0.254)
						(type default)
					)
					(fill
						(type none)
					)
				)
			)
			(symbol "R_200k_0402_1_1"
				(pin passive line
					(at 0 0 0)
					(length 0.635)
					(name "~"
						(effects
							(font
								(size 1.27 1.27)
							)
						)
					)
					(number "1"
						(effects
							(font
								(size 1.27 1.27)
							)
						)
					)
				)
				(pin passive line
					(at 5.08 0 180)
					(length 0.635)
					(name "~"
						(effects
							(font
								(size 1.27 1.27)
							)
						)
					)
					(number "2"
						(effects
							(font
								(size 1.27 1.27)
							)
						)
					)
				)
			)
		)
	(symbol "antmicroResistors0402:R_232k_0402"
			(pin_numbers
				(hide yes)
			)
			(pin_names
				(hide yes)
			)
			(exclude_from_sim no)
			(in_bom yes)
			(on_board yes)
			(property "Reference" "R"
				(at 20.32 -5.08 0)
				(effects
					(font
						(size 1.27 1.27)
						(thickness 0.15)
					)
					(justify left bottom)
				)
			)
			(property "Value" "R_232k_0402"
				(at 20.32 -12.7 0)
				(effects
					(font
						(size 1.27 1.27)
						(thickness 0.15)
					)
					(justify left bottom)
					(hide yes)
				)
			)
			(property "Footprint" "antmicro-footprints:R_0402_1005Metric"
				(at 20.32 -15.24 0)
				(effects
					(font
						(size 1.27 1.27)
						(thickness 0.15)
					)
					(justify left bottom)
					(hide yes)
				)
			)
			(property "Datasheet" "https://www.mouser.com/datasheet/2/447/PYu_RT_1_to_0_01_RoHS_L_12-3003070.pdf"
				(at 20.32 -17.78 0)
				(effects
					(font
						(size 1.27 1.27)
						(thickness 0.15)
					)
					(justify left bottom)
					(hide yes)
				)
			)
			(property "Description" "SMD Chip Resistor"
				(at 20.32 -30.48 0)
				(effects
					(font
						(size 1.27 1.27)
					)
					(justify left bottom)
					(hide yes)
				)
			)
			(property "MPN" "RT0402FRE07232KL"
				(at 20.32 -20.32 0)
				(effects
					(font
						(size 1.27 1.27)
						(thickness 0.15)
					)
					(justify left bottom)
					(hide yes)
				)
			)
			(property "Manufacturer" "YAGEO"
				(at 20.32 -22.86 0)
				(effects
					(font
						(size 1.27 1.27)
						(thickness 0.15)
					)
					(justify left bottom)
					(hide yes)
				)
			)
			(property "License" "Apache-2.0"
				(at 20.32 -25.4 0)
				(effects
					(font
						(size 1.27 1.27)
						(thickness 0.15)
					)
					(justify left bottom)
					(hide yes)
				)
			)
			(property "Author" "Antmicro"
				(at 20.32 -27.94 0)
				(effects
					(font
						(size 1.27 1.27)
						(thickness 0.15)
					)
					(justify left bottom)
					(hide yes)
				)
			)
			(property "Val" "232k"
				(at 20.32 -7.62 0)
				(effects
					(font
						(size 1.27 1.27)
						(thickness 0.15)
					)
					(justify left bottom)
				)
			)
			(property "Tolerance" "1%"
				(at 20.32 -10.16 0)
				(effects
					(font
						(size 1.27 1.27)
					)
					(justify left bottom)
					(hide yes)
				)
			)
			(property "ki_keywords" "0402, SMT, RESISTOR, PASSIVE"
				(at 0 0 0)
				(effects
					(font
						(size 1.27 1.27)
					)
					(hide yes)
				)
			)
			(symbol "R_232k_0402_0_1"
				(rectangle
					(start 0.635 0.889)
					(end 4.445 -0.889)
					(stroke
						(width 0.254)
						(type default)
					)
					(fill
						(type none)
					)
				)
			)
			(symbol "R_232k_0402_1_1"
				(pin passive line
					(at 0 0 0)
					(length 0.635)
					(name "~"
						(effects
							(font
								(size 1.27 1.27)
							)
						)
					)
					(number "1"
						(effects
							(font
								(size 1.27 1.27)
							)
						)
					)
				)
				(pin passive line
					(at 5.08 0 180)
					(length 0.635)
					(name "~"
						(effects
							(font
								(size 1.27 1.27)
							)
						)
					)
					(number "2"
						(effects
							(font
								(size 1.27 1.27)
							)
						)
					)
				)
			)
		)
	(symbol "antmicroResistors0402:R_255k_0402"
			(pin_numbers
				(hide yes)
			)
			(pin_names
				(hide yes)
			)
			(exclude_from_sim no)
			(in_bom yes)
			(on_board yes)
			(property "Reference" "R"
				(at 20.32 -5.08 0)
				(effects
					(font
						(size 1.27 1.27)
						(thickness 0.15)
					)
					(justify left bottom)
				)
			)
			(property "Value" "R_255k_0402"
				(at 20.32 -12.7 0)
				(effects
					(font
						(size 1.27 1.27)
						(thickness 0.15)
					)
					(justify left bottom)
					(hide yes)
				)
			)
			(property "Footprint" "antmicro-footprints:R_0402_1005Metric"
				(at 20.32 -15.24 0)
				(effects
					(font
						(size 1.27 1.27)
						(thickness 0.15)
					)
					(justify left bottom)
					(hide yes)
				)
			)
			(property "Datasheet" "https://www.bourns.com/docs/product-datasheets/cr.pdf"
				(at 20.32 -17.78 0)
				(effects
					(font
						(size 1.27 1.27)
						(thickness 0.15)
					)
					(justify left bottom)
					(hide yes)
				)
			)
			(property "Description" "SMD Chip Resistor, 255 kohm, ± 1%, 100 mW, 0402 [1005 Metric], Thick Film, Precision"
				(at 20.32 -30.48 0)
				(effects
					(font
						(size 1.27 1.27)
					)
					(justify left bottom)
					(hide yes)
				)
			)
			(property "MPN" "CR0402-FX-2553GLF"
				(at 20.32 -20.32 0)
				(effects
					(font
						(size 1.27 1.27)
						(thickness 0.15)
					)
					(justify left bottom)
					(hide yes)
				)
			)
			(property "Manufacturer" "Bourns"
				(at 20.32 -22.86 0)
				(effects
					(font
						(size 1.27 1.27)
						(thickness 0.15)
					)
					(justify left bottom)
					(hide yes)
				)
			)
			(property "License" "Apache-2.0"
				(at 20.32 -25.4 0)
				(effects
					(font
						(size 1.27 1.27)
						(thickness 0.15)
					)
					(justify left bottom)
					(hide yes)
				)
			)
			(property "Author" "Antmicro"
				(at 20.32 -27.94 0)
				(effects
					(font
						(size 1.27 1.27)
						(thickness 0.15)
					)
					(justify left bottom)
					(hide yes)
				)
			)
			(property "Val" "255k"
				(at 20.32 -7.62 0)
				(effects
					(font
						(size 1.27 1.27)
						(thickness 0.15)
					)
					(justify left bottom)
				)
			)
			(property "Tolerance" "1%"
				(at 20.32 -10.16 0)
				(effects
					(font
						(size 1.27 1.27)
					)
					(justify left bottom)
					(hide yes)
				)
			)
			(property "ki_keywords" "0402, SMT, RESISTOR, PASSIVE"
				(at 0 0 0)
				(effects
					(font
						(size 1.27 1.27)
					)
					(hide yes)
				)
			)
			(symbol "R_255k_0402_0_1"
				(rectangle
					(start 0.635 0.889)
					(end 4.445 -0.889)
					(stroke
						(width 0.254)
						(type default)
					)
					(fill
						(type none)
					)
				)
			)
			(symbol "R_255k_0402_1_1"
				(pin passive line
					(at 0 0 0)
					(length 0.635)
					(name "~"
						(effects
							(font
								(size 1.27 1.27)
							)
						)
					)
					(number "1"
						(effects
							(font
								(size 1.27 1.27)
							)
						)
					)
				)
				(pin passive line
					(at 5.08 0 180)
					(length 0.635)
					(name "~"
						(effects
							(font
								(size 1.27 1.27)
							)
						)
					)
					(number "2"
						(effects
							(font
								(size 1.27 1.27)
							)
						)
					)
				)
			)
		)
	(symbol "antmicroResistors0402:R_27R_0402"
			(pin_numbers
				(hide yes)
			)
			(pin_names
				(hide yes)
			)
			(exclude_from_sim no)
			(in_bom yes)
			(on_board yes)
			(property "Reference" "R"
				(at 20.32 -5.08 0)
				(effects
					(font
						(size 1.27 1.27)
						(thickness 0.15)
					)
					(justify left bottom)
				)
			)
			(property "Value" "R_27R_0402"
				(at 20.32 -12.7 0)
				(effects
					(font
						(size 1.27 1.27)
						(thickness 0.15)
					)
					(justify left bottom)
					(hide yes)
				)
			)
			(property "Footprint" "antmicro-footprints:R_0402_1005Metric"
				(at 20.32 -15.24 0)
				(effects
					(font
						(size 1.27 1.27)
						(thickness 0.15)
					)
					(justify left bottom)
					(hide yes)
				)
			)
			(property "Datasheet" "https://www.bourns.com/docs/product-datasheets/cr.pdf"
				(at 20.32 -17.78 0)
				(effects
					(font
						(size 1.27 1.27)
						(thickness 0.15)
					)
					(justify left bottom)
					(hide yes)
				)
			)
			(property "Description" "SMD Chip Resistor, 27 ohm, ± 1%, 63 mW, 0402 [1005 Metric], Thick Film, General Purpose"
				(at 20.32 -30.48 0)
				(effects
					(font
						(size 1.27 1.27)
					)
					(justify left bottom)
					(hide yes)
				)
			)
			(property "MPN" "CR0402-FX-27R0GLF"
				(at 20.32 -20.32 0)
				(effects
					(font
						(size 1.27 1.27)
						(thickness 0.15)
					)
					(justify left bottom)
					(hide yes)
				)
			)
			(property "Manufacturer" "Bourns"
				(at 20.32 -22.86 0)
				(effects
					(font
						(size 1.27 1.27)
						(thickness 0.15)
					)
					(justify left bottom)
					(hide yes)
				)
			)
			(property "License" "Apache-2.0"
				(at 20.32 -25.4 0)
				(effects
					(font
						(size 1.27 1.27)
						(thickness 0.15)
					)
					(justify left bottom)
					(hide yes)
				)
			)
			(property "Author" "Antmicro"
				(at 20.32 -27.94 0)
				(effects
					(font
						(size 1.27 1.27)
						(thickness 0.15)
					)
					(justify left bottom)
					(hide yes)
				)
			)
			(property "Val" "27R"
				(at 20.32 -7.62 0)
				(effects
					(font
						(size 1.27 1.27)
						(thickness 0.15)
					)
					(justify left bottom)
				)
			)
			(property "Tolerance" "1%"
				(at 20.32 -10.16 0)
				(effects
					(font
						(size 1.27 1.27)
					)
					(justify left bottom)
					(hide yes)
				)
			)
			(property "ki_keywords" "0402, SMT, RESISTOR, PASSIVE"
				(at 0 0 0)
				(effects
					(font
						(size 1.27 1.27)
					)
					(hide yes)
				)
			)
			(symbol "R_27R_0402_0_1"
				(rectangle
					(start 0.635 0.889)
					(end 4.445 -0.889)
					(stroke
						(width 0.254)
						(type default)
					)
					(fill
						(type none)
					)
				)
			)
			(symbol "R_27R_0402_1_1"
				(pin passive line
					(at 0 0 0)
					(length 0.635)
					(name "~"
						(effects
							(font
								(size 1.27 1.27)
							)
						)
					)
					(number "1"
						(effects
							(font
								(size 1.27 1.27)
							)
						)
					)
				)
				(pin passive line
					(at 5.08 0 180)
					(length 0.635)
					(name "~"
						(effects
							(font
								(size 1.27 1.27)
							)
						)
					)
					(number "2"
						(effects
							(font
								(size 1.27 1.27)
							)
						)
					)
				)
			)
		)
	(symbol "antmicroResistors0402:R_2M_0402"
			(pin_numbers
				(hide yes)
			)
			(pin_names
				(hide yes)
			)
			(exclude_from_sim no)
			(in_bom yes)
			(on_board yes)
			(property "Reference" "R"
				(at 20.32 -5.08 0)
				(effects
					(font
						(size 1.27 1.27)
						(thickness 0.15)
					)
					(justify left bottom)
				)
			)
			(property "Value" "R_2M_0402"
				(at 20.32 -12.7 0)
				(effects
					(font
						(size 1.27 1.27)
						(thickness 0.15)
					)
					(justify left bottom)
					(hide yes)
				)
			)
			(property "Footprint" "antmicro-footprints:R_0402_1005Metric"
				(at 20.32 -15.24 0)
				(effects
					(font
						(size 1.27 1.27)
						(thickness 0.15)
					)
					(justify left bottom)
					(hide yes)
				)
			)
			(property "Datasheet" "https://www.mouser.com/datasheet/2/447/YAGEO_PYu_RC_Group_51_RoHS_L_12-3313492.pdf"
				(at 20.32 -17.78 0)
				(effects
					(font
						(size 1.27 1.27)
						(thickness 0.15)
					)
					(justify left bottom)
					(hide yes)
				)
			)
			(property "Description" "SMD Chip Resistor, 2 Mohm, ± 1%, 62.5 mW, 0402 [1005 Metric], Thick Film, General Purpose"
				(at 20.32 -30.48 0)
				(effects
					(font
						(size 1.27 1.27)
					)
					(justify left bottom)
					(hide yes)
				)
			)
			(property "MPN" "RC0402FR-072ML"
				(at 20.32 -20.32 0)
				(effects
					(font
						(size 1.27 1.27)
						(thickness 0.15)
					)
					(justify left bottom)
					(hide yes)
				)
			)
			(property "Manufacturer" "YAGEO"
				(at 20.32 -22.86 0)
				(effects
					(font
						(size 1.27 1.27)
						(thickness 0.15)
					)
					(justify left bottom)
					(hide yes)
				)
			)
			(property "License" "Apache-2.0"
				(at 20.32 -25.4 0)
				(effects
					(font
						(size 1.27 1.27)
						(thickness 0.15)
					)
					(justify left bottom)
					(hide yes)
				)
			)
			(property "Author" "Antmicro"
				(at 20.32 -27.94 0)
				(effects
					(font
						(size 1.27 1.27)
						(thickness 0.15)
					)
					(justify left bottom)
					(hide yes)
				)
			)
			(property "Val" "2M"
				(at 20.32 -7.62 0)
				(effects
					(font
						(size 1.27 1.27)
						(thickness 0.15)
					)
					(justify left bottom)
				)
			)
			(property "Tolerance" "1%"
				(at 20.32 -10.16 0)
				(effects
					(font
						(size 1.27 1.27)
					)
					(justify left bottom)
					(hide yes)
				)
			)
			(property "ki_keywords" "0402, SMT, RESISTOR, PASSIVE"
				(at 0 0 0)
				(effects
					(font
						(size 1.27 1.27)
					)
					(hide yes)
				)
			)
			(symbol "R_2M_0402_0_1"
				(rectangle
					(start 0.635 0.889)
					(end 4.445 -0.889)
					(stroke
						(width 0.254)
						(type default)
					)
					(fill
						(type none)
					)
				)
			)
			(symbol "R_2M_0402_1_1"
				(pin passive line
					(at 0 0 0)
					(length 0.635)
					(name "~"
						(effects
							(font
								(size 1.27 1.27)
							)
						)
					)
					(number "1"
						(effects
							(font
								(size 1.27 1.27)
							)
						)
					)
				)
				(pin passive line
					(at 5.08 0 180)
					(length 0.635)
					(name "~"
						(effects
							(font
								(size 1.27 1.27)
							)
						)
					)
					(number "2"
						(effects
							(font
								(size 1.27 1.27)
							)
						)
					)
				)
			)
		)
	(symbol "antmicroResistors0402:R_2R2_0402"
			(pin_numbers
				(hide yes)
			)
			(pin_names
				(hide yes)
			)
			(exclude_from_sim no)
			(in_bom yes)
			(on_board yes)
			(property "Reference" "R"
				(at 20.32 -5.08 0)
				(effects
					(font
						(size 1.27 1.27)
						(thickness 0.15)
					)
					(justify left bottom)
				)
			)
			(property "Value" "R_2R2_0402"
				(at 20.32 -12.7 0)
				(effects
					(font
						(size 1.27 1.27)
						(thickness 0.15)
					)
					(justify left bottom)
					(hide yes)
				)
			)
			(property "Footprint" "antmicro-footprints:R_0402_1005Metric"
				(at 20.32 -15.24 0)
				(effects
					(font
						(size 1.27 1.27)
						(thickness 0.15)
					)
					(justify left bottom)
					(hide yes)
				)
			)
			(property "Datasheet" "https://www.bourns.com/docs/product-datasheets/cr.pdf"
				(at 20.32 -17.78 0)
				(effects
					(font
						(size 1.27 1.27)
						(thickness 0.15)
					)
					(justify left bottom)
					(hide yes)
				)
			)
			(property "Description" "SMD Chip Resistor, 2.2 ohm, ± 1%, 62.5 mW, 0402 [1005 Metric], Thick Film, General Purpose"
				(at 20.32 -30.48 0)
				(effects
					(font
						(size 1.27 1.27)
					)
					(justify left bottom)
					(hide yes)
				)
			)
			(property "MPN" "CR0402-FX-2R20GLF"
				(at 20.32 -20.32 0)
				(effects
					(font
						(size 1.27 1.27)
						(thickness 0.15)
					)
					(justify left bottom)
					(hide yes)
				)
			)
			(property "Manufacturer" "Bourns"
				(at 20.32 -22.86 0)
				(effects
					(font
						(size 1.27 1.27)
						(thickness 0.15)
					)
					(justify left bottom)
					(hide yes)
				)
			)
			(property "License" "Apache-2.0"
				(at 20.32 -25.4 0)
				(effects
					(font
						(size 1.27 1.27)
						(thickness 0.15)
					)
					(justify left bottom)
					(hide yes)
				)
			)
			(property "Author" "Antmicro"
				(at 20.32 -27.94 0)
				(effects
					(font
						(size 1.27 1.27)
						(thickness 0.15)
					)
					(justify left bottom)
					(hide yes)
				)
			)
			(property "Val" "2R2"
				(at 20.32 -7.62 0)
				(effects
					(font
						(size 1.27 1.27)
						(thickness 0.15)
					)
					(justify left bottom)
				)
			)
			(property "Tolerance" "1%"
				(at 20.32 -10.16 0)
				(effects
					(font
						(size 1.27 1.27)
					)
					(justify left bottom)
					(hide yes)
				)
			)
			(property "ki_keywords" "0402, SMT, RESISTOR, PASSIVE"
				(at 0 0 0)
				(effects
					(font
						(size 1.27 1.27)
					)
					(hide yes)
				)
			)
			(symbol "R_2R2_0402_0_1"
				(rectangle
					(start 0.635 0.889)
					(end 4.445 -0.889)
					(stroke
						(width 0.254)
						(type default)
					)
					(fill
						(type none)
					)
				)
			)
			(symbol "R_2R2_0402_1_1"
				(pin passive line
					(at 0 0 0)
					(length 0.635)
					(name "~"
						(effects
							(font
								(size 1.27 1.27)
							)
						)
					)
					(number "1"
						(effects
							(font
								(size 1.27 1.27)
							)
						)
					)
				)
				(pin passive line
					(at 5.08 0 180)
					(length 0.635)
					(name "~"
						(effects
							(font
								(size 1.27 1.27)
							)
						)
					)
					(number "2"
						(effects
							(font
								(size 1.27 1.27)
							)
						)
					)
				)
			)
		)
	(symbol "antmicroResistors0402:R_2k2_0402"
			(pin_numbers
				(hide yes)
			)
			(pin_names
				(hide yes)
			)
			(exclude_from_sim no)
			(in_bom yes)
			(on_board yes)
			(property "Reference" "R"
				(at 20.32 -5.08 0)
				(effects
					(font
						(size 1.27 1.27)
						(thickness 0.15)
					)
					(justify left bottom)
				)
			)
			(property "Value" "R_2k2_0402"
				(at 20.32 -12.7 0)
				(effects
					(font
						(size 1.27 1.27)
						(thickness 0.15)
					)
					(justify left bottom)
					(hide yes)
				)
			)
			(property "Footprint" "antmicro-footprints:R_0402_1005Metric"
				(at 20.32 -15.24 0)
				(effects
					(font
						(size 1.27 1.27)
						(thickness 0.15)
					)
					(justify left bottom)
					(hide yes)
				)
			)
			(property "Datasheet" "https://www.bourns.com/docs/product-datasheets/cr.pdf"
				(at 20.32 -17.78 0)
				(effects
					(font
						(size 1.27 1.27)
						(thickness 0.15)
					)
					(justify left bottom)
					(hide yes)
				)
			)
			(property "Description" "SMD Chip Resistor, 2.2 kohm, ± 1%, 62.5 mW, 0402 [1005 Metric], Thick Film, General Purpose"
				(at 20.32 -30.48 0)
				(effects
					(font
						(size 1.27 1.27)
					)
					(justify left bottom)
					(hide yes)
				)
			)
			(property "MPN" "CR0402-FX-2201GLF"
				(at 20.32 -20.32 0)
				(effects
					(font
						(size 1.27 1.27)
						(thickness 0.15)
					)
					(justify left bottom)
					(hide yes)
				)
			)
			(property "Manufacturer" "Bourns"
				(at 20.32 -22.86 0)
				(effects
					(font
						(size 1.27 1.27)
						(thickness 0.15)
					)
					(justify left bottom)
					(hide yes)
				)
			)
			(property "License" "Apache-2.0"
				(at 20.32 -25.4 0)
				(effects
					(font
						(size 1.27 1.27)
						(thickness 0.15)
					)
					(justify left bottom)
					(hide yes)
				)
			)
			(property "Author" "Antmicro"
				(at 20.32 -27.94 0)
				(effects
					(font
						(size 1.27 1.27)
						(thickness 0.15)
					)
					(justify left bottom)
					(hide yes)
				)
			)
			(property "Val" "2k2"
				(at 20.32 -7.62 0)
				(effects
					(font
						(size 1.27 1.27)
						(thickness 0.15)
					)
					(justify left bottom)
				)
			)
			(property "Tolerance" "1%"
				(at 20.32 -10.16 0)
				(effects
					(font
						(size 1.27 1.27)
					)
					(justify left bottom)
					(hide yes)
				)
			)
			(property "ki_keywords" "0402, SMT, RESISTOR, PASSIVE"
				(at 0 0 0)
				(effects
					(font
						(size 1.27 1.27)
					)
					(hide yes)
				)
			)
			(symbol "R_2k2_0402_0_1"
				(rectangle
					(start 0.635 0.889)
					(end 4.445 -0.889)
					(stroke
						(width 0.254)
						(type default)
					)
					(fill
						(type none)
					)
				)
			)
			(symbol "R_2k2_0402_1_1"
				(pin passive line
					(at 0 0 0)
					(length 0.635)
					(name "~"
						(effects
							(font
								(size 1.27 1.27)
							)
						)
					)
					(number "1"
						(effects
							(font
								(size 1.27 1.27)
							)
						)
					)
				)
				(pin passive line
					(at 5.08 0 180)
					(length 0.635)
					(name "~"
						(effects
							(font
								(size 1.27 1.27)
							)
						)
					)
					(number "2"
						(effects
							(font
								(size 1.27 1.27)
							)
						)
					)
				)
			)
		)
	(symbol "antmicroResistors0402:R_2k37_0402"
			(pin_numbers
				(hide yes)
			)
			(pin_names
				(hide yes)
			)
			(exclude_from_sim no)
			(in_bom yes)
			(on_board yes)
			(property "Reference" "R"
				(at 20.32 -5.08 0)
				(effects
					(font
						(size 1.27 1.27)
						(thickness 0.15)
					)
					(justify left bottom)
				)
			)
			(property "Value" "R_2k37_0402"
				(at 20.32 -12.7 0)
				(effects
					(font
						(size 1.27 1.27)
						(thickness 0.15)
					)
					(justify left bottom)
					(hide yes)
				)
			)
			(property "Footprint" "antmicro-footprints:R_0402_1005Metric"
				(at 20.32 -15.24 0)
				(effects
					(font
						(size 1.27 1.27)
						(thickness 0.15)
					)
					(justify left bottom)
					(hide yes)
				)
			)
			(property "Datasheet" "https://www.bourns.com/docs/product-datasheets/cr.pdf"
				(at 20.32 -17.78 0)
				(effects
					(font
						(size 1.27 1.27)
						(thickness 0.15)
					)
					(justify left bottom)
					(hide yes)
				)
			)
			(property "Description" "SMD Chip Resistor"
				(at 20.32 -30.48 0)
				(effects
					(font
						(size 1.27 1.27)
					)
					(justify left bottom)
					(hide yes)
				)
			)
			(property "MPN" "CR0402-FX-2371GLF"
				(at 20.32 -20.32 0)
				(effects
					(font
						(size 1.27 1.27)
						(thickness 0.15)
					)
					(justify left bottom)
					(hide yes)
				)
			)
			(property "Manufacturer" "Bourns"
				(at 20.32 -22.86 0)
				(effects
					(font
						(size 1.27 1.27)
						(thickness 0.15)
					)
					(justify left bottom)
					(hide yes)
				)
			)
			(property "License" "Apache-2.0"
				(at 20.32 -25.4 0)
				(effects
					(font
						(size 1.27 1.27)
						(thickness 0.15)
					)
					(justify left bottom)
					(hide yes)
				)
			)
			(property "Author" "Antmicro"
				(at 20.32 -27.94 0)
				(effects
					(font
						(size 1.27 1.27)
						(thickness 0.15)
					)
					(justify left bottom)
					(hide yes)
				)
			)
			(property "Val" "2k37"
				(at 20.32 -7.62 0)
				(effects
					(font
						(size 1.27 1.27)
						(thickness 0.15)
					)
					(justify left bottom)
				)
			)
			(property "Tolerance" "1%"
				(at 20.32 -10.16 0)
				(effects
					(font
						(size 1.27 1.27)
					)
					(justify left bottom)
					(hide yes)
				)
			)
			(property "ki_keywords" "0402, SMT, RESISTOR, PASSIVE"
				(at 0 0 0)
				(effects
					(font
						(size 1.27 1.27)
					)
					(hide yes)
				)
			)
			(symbol "R_2k37_0402_0_1"
				(rectangle
					(start 0.635 0.889)
					(end 4.445 -0.889)
					(stroke
						(width 0.254)
						(type default)
					)
					(fill
						(type none)
					)
				)
			)
			(symbol "R_2k37_0402_1_1"
				(pin passive line
					(at 0 0 0)
					(length 0.635)
					(name "~"
						(effects
							(font
								(size 1.27 1.27)
							)
						)
					)
					(number "1"
						(effects
							(font
								(size 1.27 1.27)
							)
						)
					)
				)
				(pin passive line
					(at 5.08 0 180)
					(length 0.635)
					(name "~"
						(effects
							(font
								(size 1.27 1.27)
							)
						)
					)
					(number "2"
						(effects
							(font
								(size 1.27 1.27)
							)
						)
					)
				)
			)
		)
	(symbol "antmicroResistors0402:R_30k_0402"
			(pin_numbers
				(hide yes)
			)
			(pin_names
				(hide yes)
			)
			(exclude_from_sim no)
			(in_bom yes)
			(on_board yes)
			(property "Reference" "R"
				(at 20.32 -5.08 0)
				(effects
					(font
						(size 1.27 1.27)
						(thickness 0.15)
					)
					(justify left bottom)
				)
			)
			(property "Value" "R_30k_0402"
				(at 20.32 -12.7 0)
				(effects
					(font
						(size 1.27 1.27)
						(thickness 0.15)
					)
					(justify left bottom)
					(hide yes)
				)
			)
			(property "Footprint" "antmicro-footprints:R_0402_1005Metric"
				(at 20.32 -15.24 0)
				(effects
					(font
						(size 1.27 1.27)
						(thickness 0.15)
					)
					(justify left bottom)
					(hide yes)
				)
			)
			(property "Datasheet" "https://www.bourns.com/docs/product-datasheets/cr.pdf"
				(at 20.32 -17.78 0)
				(effects
					(font
						(size 1.27 1.27)
						(thickness 0.15)
					)
					(justify left bottom)
					(hide yes)
				)
			)
			(property "Description" "SMD Chip Resistor, 30 kohm, ± 1%, 63 mW, 0402 [1005 Metric], Thick Film, General Purpose"
				(at 20.32 -30.48 0)
				(effects
					(font
						(size 1.27 1.27)
					)
					(justify left bottom)
					(hide yes)
				)
			)
			(property "MPN" "CR0402-FX-3002GLF"
				(at 20.32 -20.32 0)
				(effects
					(font
						(size 1.27 1.27)
						(thickness 0.15)
					)
					(justify left bottom)
					(hide yes)
				)
			)
			(property "Manufacturer" "Bourns"
				(at 20.32 -22.86 0)
				(effects
					(font
						(size 1.27 1.27)
						(thickness 0.15)
					)
					(justify left bottom)
					(hide yes)
				)
			)
			(property "License" "Apache-2.0"
				(at 20.32 -25.4 0)
				(effects
					(font
						(size 1.27 1.27)
						(thickness 0.15)
					)
					(justify left bottom)
					(hide yes)
				)
			)
			(property "Author" "Antmicro"
				(at 20.32 -27.94 0)
				(effects
					(font
						(size 1.27 1.27)
						(thickness 0.15)
					)
					(justify left bottom)
					(hide yes)
				)
			)
			(property "Val" "30k"
				(at 20.32 -7.62 0)
				(effects
					(font
						(size 1.27 1.27)
						(thickness 0.15)
					)
					(justify left bottom)
				)
			)
			(property "Tolerance" "1%"
				(at 20.32 -10.16 0)
				(effects
					(font
						(size 1.27 1.27)
					)
					(justify left bottom)
					(hide yes)
				)
			)
			(property "ki_keywords" "0402, SMT, RESISTOR, PASSIVE"
				(at 0 0 0)
				(effects
					(font
						(size 1.27 1.27)
					)
					(hide yes)
				)
			)
			(symbol "R_30k_0402_0_1"
				(rectangle
					(start 0.635 0.889)
					(end 4.445 -0.889)
					(stroke
						(width 0.254)
						(type default)
					)
					(fill
						(type none)
					)
				)
			)
			(symbol "R_30k_0402_1_1"
				(pin passive line
					(at 0 0 0)
					(length 0.635)
					(name "~"
						(effects
							(font
								(size 1.27 1.27)
							)
						)
					)
					(number "1"
						(effects
							(font
								(size 1.27 1.27)
							)
						)
					)
				)
				(pin passive line
					(at 5.08 0 180)
					(length 0.635)
					(name "~"
						(effects
							(font
								(size 1.27 1.27)
							)
						)
					)
					(number "2"
						(effects
							(font
								(size 1.27 1.27)
							)
						)
					)
				)
			)
		)
	(symbol "antmicroResistors0402:R_31k6_0402"
			(pin_numbers
				(hide yes)
			)
			(pin_names
				(hide yes)
			)
			(exclude_from_sim no)
			(in_bom yes)
			(on_board yes)
			(property "Reference" "R"
				(at 20.32 -5.08 0)
				(effects
					(font
						(size 1.27 1.27)
						(thickness 0.15)
					)
					(justify left bottom)
				)
			)
			(property "Value" "R_31k6_0402"
				(at 20.32 -12.7 0)
				(effects
					(font
						(size 1.27 1.27)
						(thickness 0.15)
					)
					(justify left bottom)
					(hide yes)
				)
			)
			(property "Footprint" "antmicro-footprints:R_0402_1005Metric"
				(at 20.32 -15.24 0)
				(effects
					(font
						(size 1.27 1.27)
						(thickness 0.15)
					)
					(justify left bottom)
					(hide yes)
				)
			)
			(property "Datasheet" "https://www.bourns.com/docs/product-datasheets/cr.pdf"
				(at 20.32 -17.78 0)
				(effects
					(font
						(size 1.27 1.27)
						(thickness 0.15)
					)
					(justify left bottom)
					(hide yes)
				)
			)
			(property "Description" "SMD Chip Resistor"
				(at 20.32 -30.48 0)
				(effects
					(font
						(size 1.27 1.27)
					)
					(justify left bottom)
					(hide yes)
				)
			)
			(property "MPN" "CR0402-FX-3162GLF"
				(at 20.32 -20.32 0)
				(effects
					(font
						(size 1.27 1.27)
						(thickness 0.15)
					)
					(justify left bottom)
					(hide yes)
				)
			)
			(property "Manufacturer" "Bourns"
				(at 20.32 -22.86 0)
				(effects
					(font
						(size 1.27 1.27)
						(thickness 0.15)
					)
					(justify left bottom)
					(hide yes)
				)
			)
			(property "License" "Apache-2.0"
				(at 20.32 -25.4 0)
				(effects
					(font
						(size 1.27 1.27)
						(thickness 0.15)
					)
					(justify left bottom)
					(hide yes)
				)
			)
			(property "Author" "Antmicro"
				(at 20.32 -27.94 0)
				(effects
					(font
						(size 1.27 1.27)
						(thickness 0.15)
					)
					(justify left bottom)
					(hide yes)
				)
			)
			(property "Val" "31k6"
				(at 20.32 -7.62 0)
				(effects
					(font
						(size 1.27 1.27)
						(thickness 0.15)
					)
					(justify left bottom)
				)
			)
			(property "Tolerance" "1%"
				(at 20.32 -10.16 0)
				(effects
					(font
						(size 1.27 1.27)
					)
					(justify left bottom)
					(hide yes)
				)
			)
			(property "ki_keywords" "0402, SMT, RESISTOR, PASSIVE"
				(at 0 0 0)
				(effects
					(font
						(size 1.27 1.27)
					)
					(hide yes)
				)
			)
			(symbol "R_31k6_0402_0_1"
				(rectangle
					(start 0.635 0.889)
					(end 4.445 -0.889)
					(stroke
						(width 0.254)
						(type default)
					)
					(fill
						(type none)
					)
				)
			)
			(symbol "R_31k6_0402_1_1"
				(pin passive line
					(at 0 0 0)
					(length 0.635)
					(name "~"
						(effects
							(font
								(size 1.27 1.27)
							)
						)
					)
					(number "1"
						(effects
							(font
								(size 1.27 1.27)
							)
						)
					)
				)
				(pin passive line
					(at 5.08 0 180)
					(length 0.635)
					(name "~"
						(effects
							(font
								(size 1.27 1.27)
							)
						)
					)
					(number "2"
						(effects
							(font
								(size 1.27 1.27)
							)
						)
					)
				)
			)
		)
	(symbol "antmicroResistors0402:R_330R_0402"
			(pin_numbers
				(hide yes)
			)
			(pin_names
				(hide yes)
			)
			(exclude_from_sim no)
			(in_bom yes)
			(on_board yes)
			(property "Reference" "R"
				(at 20.32 -5.08 0)
				(effects
					(font
						(size 1.27 1.27)
						(thickness 0.15)
					)
					(justify left bottom)
				)
			)
			(property "Value" "R_330R_0402"
				(at 20.32 -12.7 0)
				(effects
					(font
						(size 1.27 1.27)
						(thickness 0.15)
					)
					(justify left bottom)
					(hide yes)
				)
			)
			(property "Footprint" "antmicro-footprints:R_0402_1005Metric"
				(at 20.32 -15.24 0)
				(effects
					(font
						(size 1.27 1.27)
						(thickness 0.15)
					)
					(justify left bottom)
					(hide yes)
				)
			)
			(property "Datasheet" "https://www.bourns.com/docs/product-datasheets/cr.pdf"
				(at 20.32 -17.78 0)
				(effects
					(font
						(size 1.27 1.27)
						(thickness 0.15)
					)
					(justify left bottom)
					(hide yes)
				)
			)
			(property "Description" "SMD Chip Resistor, 330 ohm, ± 1%, 62.5 mW, 0402 [1005 Metric], Thick Film, General Purpose"
				(at 20.32 -30.48 0)
				(effects
					(font
						(size 1.27 1.27)
					)
					(justify left bottom)
					(hide yes)
				)
			)
			(property "MPN" "CR0402-FX-3300GLF"
				(at 20.32 -20.32 0)
				(effects
					(font
						(size 1.27 1.27)
						(thickness 0.15)
					)
					(justify left bottom)
					(hide yes)
				)
			)
			(property "Manufacturer" "Bourns"
				(at 20.32 -22.86 0)
				(effects
					(font
						(size 1.27 1.27)
						(thickness 0.15)
					)
					(justify left bottom)
					(hide yes)
				)
			)
			(property "License" "Apache-2.0"
				(at 20.32 -25.4 0)
				(effects
					(font
						(size 1.27 1.27)
						(thickness 0.15)
					)
					(justify left bottom)
					(hide yes)
				)
			)
			(property "Author" "Antmicro"
				(at 20.32 -27.94 0)
				(effects
					(font
						(size 1.27 1.27)
						(thickness 0.15)
					)
					(justify left bottom)
					(hide yes)
				)
			)
			(property "Val" "330R"
				(at 20.32 -7.62 0)
				(effects
					(font
						(size 1.27 1.27)
						(thickness 0.15)
					)
					(justify left bottom)
				)
			)
			(property "Tolerance" "1%"
				(at 20.32 -10.16 0)
				(effects
					(font
						(size 1.27 1.27)
					)
					(justify left bottom)
					(hide yes)
				)
			)
			(property "ki_keywords" "0402, SMT, RESISTOR, PASSIVE"
				(at 0 0 0)
				(effects
					(font
						(size 1.27 1.27)
					)
					(hide yes)
				)
			)
			(symbol "R_330R_0402_0_1"
				(rectangle
					(start 0.635 0.889)
					(end 4.445 -0.889)
					(stroke
						(width 0.254)
						(type default)
					)
					(fill
						(type none)
					)
				)
			)
			(symbol "R_330R_0402_1_1"
				(pin passive line
					(at 0 0 0)
					(length 0.635)
					(name "~"
						(effects
							(font
								(size 1.27 1.27)
							)
						)
					)
					(number "1"
						(effects
							(font
								(size 1.27 1.27)
							)
						)
					)
				)
				(pin passive line
					(at 5.08 0 180)
					(length 0.635)
					(name "~"
						(effects
							(font
								(size 1.27 1.27)
							)
						)
					)
					(number "2"
						(effects
							(font
								(size 1.27 1.27)
							)
						)
					)
				)
			)
		)
	(symbol "antmicroResistors0402:R_330k_0402"
			(pin_numbers
				(hide yes)
			)
			(pin_names
				(hide yes)
			)
			(exclude_from_sim no)
			(in_bom yes)
			(on_board yes)
			(property "Reference" "R"
				(at 20.32 -5.08 0)
				(effects
					(font
						(size 1.27 1.27)
						(thickness 0.15)
					)
					(justify left bottom)
				)
			)
			(property "Value" "R_330k_0402"
				(at 20.32 -12.7 0)
				(effects
					(font
						(size 1.27 1.27)
						(thickness 0.15)
					)
					(justify left bottom)
					(hide yes)
				)
			)
			(property "Footprint" "antmicro-footprints:R_0402_1005Metric"
				(at 20.32 -15.24 0)
				(effects
					(font
						(size 1.27 1.27)
						(thickness 0.15)
					)
					(justify left bottom)
					(hide yes)
				)
			)
			(property "Datasheet" "https://www.bourns.com/docs/product-datasheets/cr.pdf"
				(at 20.32 -17.78 0)
				(effects
					(font
						(size 1.27 1.27)
						(thickness 0.15)
					)
					(justify left bottom)
					(hide yes)
				)
			)
			(property "Description" "SMD Chip Resistor"
				(at 20.32 -30.48 0)
				(effects
					(font
						(size 1.27 1.27)
					)
					(justify left bottom)
					(hide yes)
				)
			)
			(property "MPN" "CR0402-FX-3303GLF"
				(at 20.32 -20.32 0)
				(effects
					(font
						(size 1.27 1.27)
						(thickness 0.15)
					)
					(justify left bottom)
					(hide yes)
				)
			)
			(property "Manufacturer" "Bourns"
				(at 20.32 -22.86 0)
				(effects
					(font
						(size 1.27 1.27)
						(thickness 0.15)
					)
					(justify left bottom)
					(hide yes)
				)
			)
			(property "License" "Apache-2.0"
				(at 20.32 -25.4 0)
				(effects
					(font
						(size 1.27 1.27)
						(thickness 0.15)
					)
					(justify left bottom)
					(hide yes)
				)
			)
			(property "Author" "Antmicro"
				(at 20.32 -27.94 0)
				(effects
					(font
						(size 1.27 1.27)
						(thickness 0.15)
					)
					(justify left bottom)
					(hide yes)
				)
			)
			(property "Val" "330k"
				(at 20.32 -7.62 0)
				(effects
					(font
						(size 1.27 1.27)
						(thickness 0.15)
					)
					(justify left bottom)
				)
			)
			(property "Tolerance" "1%"
				(at 20.32 -10.16 0)
				(effects
					(font
						(size 1.27 1.27)
					)
					(justify left bottom)
					(hide yes)
				)
			)
			(property "ki_keywords" "0402, SMT, RESISTOR, PASSIVE"
				(at 0 0 0)
				(effects
					(font
						(size 1.27 1.27)
					)
					(hide yes)
				)
			)
			(symbol "R_330k_0402_0_1"
				(rectangle
					(start 0.635 0.889)
					(end 4.445 -0.889)
					(stroke
						(width 0.254)
						(type default)
					)
					(fill
						(type none)
					)
				)
			)
			(symbol "R_330k_0402_1_1"
				(pin passive line
					(at 0 0 0)
					(length 0.635)
					(name "~"
						(effects
							(font
								(size 1.27 1.27)
							)
						)
					)
					(number "1"
						(effects
							(font
								(size 1.27 1.27)
							)
						)
					)
				)
				(pin passive line
					(at 5.08 0 180)
					(length 0.635)
					(name "~"
						(effects
							(font
								(size 1.27 1.27)
							)
						)
					)
					(number "2"
						(effects
							(font
								(size 1.27 1.27)
							)
						)
					)
				)
			)
		)
	(symbol "antmicroResistors0402:R_33R_0402"
			(pin_numbers
				(hide yes)
			)
			(pin_names
				(hide yes)
			)
			(exclude_from_sim no)
			(in_bom yes)
			(on_board yes)
			(property "Reference" "R"
				(at 20.32 -5.08 0)
				(effects
					(font
						(size 1.27 1.27)
						(thickness 0.15)
					)
					(justify left bottom)
				)
			)
			(property "Value" "R_33R_0402"
				(at 20.32 -12.7 0)
				(effects
					(font
						(size 1.27 1.27)
						(thickness 0.15)
					)
					(justify left bottom)
					(hide yes)
				)
			)
			(property "Footprint" "antmicro-footprints:R_0402_1005Metric"
				(at 20.32 -15.24 0)
				(effects
					(font
						(size 1.27 1.27)
						(thickness 0.15)
					)
					(justify left bottom)
					(hide yes)
				)
			)
			(property "Datasheet" "https://www.bourns.com/docs/product-datasheets/cr.pdf"
				(at 20.32 -17.78 0)
				(effects
					(font
						(size 1.27 1.27)
						(thickness 0.15)
					)
					(justify left bottom)
					(hide yes)
				)
			)
			(property "Description" "SMD Chip Resistor, 33 ohm, ± 1%, 62.5 mW, 0402 [1005 Metric], Thick Film, General Purpose"
				(at 20.32 -30.48 0)
				(effects
					(font
						(size 1.27 1.27)
					)
					(justify left bottom)
					(hide yes)
				)
			)
			(property "MPN" "CR0402-FX-33R0GLF"
				(at 20.32 -20.32 0)
				(effects
					(font
						(size 1.27 1.27)
						(thickness 0.15)
					)
					(justify left bottom)
					(hide yes)
				)
			)
			(property "Manufacturer" "Bourns"
				(at 20.32 -22.86 0)
				(effects
					(font
						(size 1.27 1.27)
						(thickness 0.15)
					)
					(justify left bottom)
					(hide yes)
				)
			)
			(property "License" "Apache-2.0"
				(at 20.32 -25.4 0)
				(effects
					(font
						(size 1.27 1.27)
						(thickness 0.15)
					)
					(justify left bottom)
					(hide yes)
				)
			)
			(property "Author" "Antmicro"
				(at 20.32 -27.94 0)
				(effects
					(font
						(size 1.27 1.27)
						(thickness 0.15)
					)
					(justify left bottom)
					(hide yes)
				)
			)
			(property "Val" "33R"
				(at 20.32 -7.62 0)
				(effects
					(font
						(size 1.27 1.27)
						(thickness 0.15)
					)
					(justify left bottom)
				)
			)
			(property "Tolerance" "1%"
				(at 20.32 -10.16 0)
				(effects
					(font
						(size 1.27 1.27)
					)
					(justify left bottom)
					(hide yes)
				)
			)
			(property "ki_keywords" "0402, SMT, RESISTOR, PASSIVE"
				(at 0 0 0)
				(effects
					(font
						(size 1.27 1.27)
					)
					(hide yes)
				)
			)
			(symbol "R_33R_0402_0_1"
				(rectangle
					(start 0.635 0.889)
					(end 4.445 -0.889)
					(stroke
						(width 0.254)
						(type default)
					)
					(fill
						(type none)
					)
				)
			)
			(symbol "R_33R_0402_1_1"
				(pin passive line
					(at 0 0 0)
					(length 0.635)
					(name "~"
						(effects
							(font
								(size 1.27 1.27)
							)
						)
					)
					(number "1"
						(effects
							(font
								(size 1.27 1.27)
							)
						)
					)
				)
				(pin passive line
					(at 5.08 0 180)
					(length 0.635)
					(name "~"
						(effects
							(font
								(size 1.27 1.27)
							)
						)
					)
					(number "2"
						(effects
							(font
								(size 1.27 1.27)
							)
						)
					)
				)
			)
		)
	(symbol "antmicroResistors0402:R_3k92_0402"
			(pin_numbers
				(hide yes)
			)
			(pin_names
				(hide yes)
			)
			(exclude_from_sim no)
			(in_bom yes)
			(on_board yes)
			(property "Reference" "R"
				(at 20.32 -5.08 0)
				(effects
					(font
						(size 1.27 1.27)
						(thickness 0.15)
					)
					(justify left bottom)
				)
			)
			(property "Value" "R_3k92_0402"
				(at 20.32 -12.7 0)
				(effects
					(font
						(size 1.27 1.27)
						(thickness 0.15)
					)
					(justify left bottom)
					(hide yes)
				)
			)
			(property "Footprint" "antmicro-footprints:R_0402_1005Metric"
				(at 20.32 -15.24 0)
				(effects
					(font
						(size 1.27 1.27)
						(thickness 0.15)
					)
					(justify left bottom)
					(hide yes)
				)
			)
			(property "Datasheet" "https://www.bourns.com/docs/product-datasheets/cr.pdf"
				(at 20.32 -17.78 0)
				(effects
					(font
						(size 1.27 1.27)
						(thickness 0.15)
					)
					(justify left bottom)
					(hide yes)
				)
			)
			(property "Description" "SMD Chip Resistor, 3.92 kohm, ± 1%, 100 mW, 0402 [1005 Metric], Thick Film, Precision"
				(at 20.32 -30.48 0)
				(effects
					(font
						(size 1.27 1.27)
					)
					(justify left bottom)
					(hide yes)
				)
			)
			(property "MPN" "CR0402-FX-3921GLF"
				(at 20.32 -20.32 0)
				(effects
					(font
						(size 1.27 1.27)
						(thickness 0.15)
					)
					(justify left bottom)
					(hide yes)
				)
			)
			(property "Manufacturer" "Bourns"
				(at 20.32 -22.86 0)
				(effects
					(font
						(size 1.27 1.27)
						(thickness 0.15)
					)
					(justify left bottom)
					(hide yes)
				)
			)
			(property "License" "Apache-2.0"
				(at 20.32 -25.4 0)
				(effects
					(font
						(size 1.27 1.27)
						(thickness 0.15)
					)
					(justify left bottom)
					(hide yes)
				)
			)
			(property "Author" "Antmicro"
				(at 20.32 -27.94 0)
				(effects
					(font
						(size 1.27 1.27)
						(thickness 0.15)
					)
					(justify left bottom)
					(hide yes)
				)
			)
			(property "Val" "3k92"
				(at 20.32 -7.62 0)
				(effects
					(font
						(size 1.27 1.27)
						(thickness 0.15)
					)
					(justify left bottom)
				)
			)
			(property "Tolerance" "1%"
				(at 20.32 -10.16 0)
				(effects
					(font
						(size 1.27 1.27)
					)
					(justify left bottom)
					(hide yes)
				)
			)
			(property "ki_keywords" "0402, SMT, RESISTOR, PASSIVE"
				(at 0 0 0)
				(effects
					(font
						(size 1.27 1.27)
					)
					(hide yes)
				)
			)
			(symbol "R_3k92_0402_0_1"
				(rectangle
					(start 0.635 0.889)
					(end 4.445 -0.889)
					(stroke
						(width 0.254)
						(type default)
					)
					(fill
						(type none)
					)
				)
			)
			(symbol "R_3k92_0402_1_1"
				(pin passive line
					(at 0 0 0)
					(length 0.635)
					(name "~"
						(effects
							(font
								(size 1.27 1.27)
							)
						)
					)
					(number "1"
						(effects
							(font
								(size 1.27 1.27)
							)
						)
					)
				)
				(pin passive line
					(at 5.08 0 180)
					(length 0.635)
					(name "~"
						(effects
							(font
								(size 1.27 1.27)
							)
						)
					)
					(number "2"
						(effects
							(font
								(size 1.27 1.27)
							)
						)
					)
				)
			)
		)
	(symbol "antmicroResistors0402:R_43k_0402"
			(pin_numbers
				(hide yes)
			)
			(pin_names
				(hide yes)
			)
			(exclude_from_sim no)
			(in_bom yes)
			(on_board yes)
			(property "Reference" "R"
				(at 20.32 -5.08 0)
				(effects
					(font
						(size 1.27 1.27)
						(thickness 0.15)
					)
					(justify left bottom)
				)
			)
			(property "Value" "R_43k_0402"
				(at 20.32 -12.7 0)
				(effects
					(font
						(size 1.27 1.27)
						(thickness 0.15)
					)
					(justify left bottom)
					(hide yes)
				)
			)
			(property "Footprint" "antmicro-footprints:R_0402_1005Metric"
				(at 20.32 -15.24 0)
				(effects
					(font
						(size 1.27 1.27)
						(thickness 0.15)
					)
					(justify left bottom)
					(hide yes)
				)
			)
			(property "Datasheet" "https://www.bourns.com/docs/product-datasheets/cr.pdf"
				(at 20.32 -17.78 0)
				(effects
					(font
						(size 1.27 1.27)
						(thickness 0.15)
					)
					(justify left bottom)
					(hide yes)
				)
			)
			(property "Description" "SMD Chip Resistor"
				(at 20.32 -30.48 0)
				(effects
					(font
						(size 1.27 1.27)
					)
					(justify left bottom)
					(hide yes)
				)
			)
			(property "MPN" "CR0402-FX-4302GLF"
				(at 20.32 -20.32 0)
				(effects
					(font
						(size 1.27 1.27)
						(thickness 0.15)
					)
					(justify left bottom)
					(hide yes)
				)
			)
			(property "Manufacturer" "Bourns"
				(at 20.32 -22.86 0)
				(effects
					(font
						(size 1.27 1.27)
						(thickness 0.15)
					)
					(justify left bottom)
					(hide yes)
				)
			)
			(property "License" "Apache-2.0"
				(at 20.32 -25.4 0)
				(effects
					(font
						(size 1.27 1.27)
						(thickness 0.15)
					)
					(justify left bottom)
					(hide yes)
				)
			)
			(property "Author" "Antmicro"
				(at 20.32 -27.94 0)
				(effects
					(font
						(size 1.27 1.27)
						(thickness 0.15)
					)
					(justify left bottom)
					(hide yes)
				)
			)
			(property "Val" "43k"
				(at 20.32 -7.62 0)
				(effects
					(font
						(size 1.27 1.27)
						(thickness 0.15)
					)
					(justify left bottom)
				)
			)
			(property "Tolerance" "1%"
				(at 20.32 -10.16 0)
				(effects
					(font
						(size 1.27 1.27)
					)
					(justify left bottom)
					(hide yes)
				)
			)
			(property "ki_keywords" "0402, SMT, RESISTOR, PASSIVE"
				(at 0 0 0)
				(effects
					(font
						(size 1.27 1.27)
					)
					(hide yes)
				)
			)
			(symbol "R_43k_0402_0_1"
				(rectangle
					(start 0.635 0.889)
					(end 4.445 -0.889)
					(stroke
						(width 0.254)
						(type default)
					)
					(fill
						(type none)
					)
				)
			)
			(symbol "R_43k_0402_1_1"
				(pin passive line
					(at 0 0 0)
					(length 0.635)
					(name "~"
						(effects
							(font
								(size 1.27 1.27)
							)
						)
					)
					(number "1"
						(effects
							(font
								(size 1.27 1.27)
							)
						)
					)
				)
				(pin passive line
					(at 5.08 0 180)
					(length 0.635)
					(name "~"
						(effects
							(font
								(size 1.27 1.27)
							)
						)
					)
					(number "2"
						(effects
							(font
								(size 1.27 1.27)
							)
						)
					)
				)
			)
		)
	(symbol "antmicroResistors0402:R_45k3_0402"
			(pin_numbers
				(hide yes)
			)
			(pin_names
				(hide yes)
			)
			(exclude_from_sim no)
			(in_bom yes)
			(on_board yes)
			(property "Reference" "R"
				(at 20.32 -5.08 0)
				(effects
					(font
						(size 1.27 1.27)
						(thickness 0.15)
					)
					(justify left bottom)
				)
			)
			(property "Value" "R_45k3_0402"
				(at 20.32 -12.7 0)
				(effects
					(font
						(size 1.27 1.27)
						(thickness 0.15)
					)
					(justify left bottom)
					(hide yes)
				)
			)
			(property "Footprint" "antmicro-footprints:R_0402_1005Metric"
				(at 20.32 -15.24 0)
				(effects
					(font
						(size 1.27 1.27)
						(thickness 0.15)
					)
					(justify left bottom)
					(hide yes)
				)
			)
			(property "Datasheet" "https://www.bourns.com/docs/product-datasheets/cr.pdf"
				(at 20.32 -17.78 0)
				(effects
					(font
						(size 1.27 1.27)
						(thickness 0.15)
					)
					(justify left bottom)
					(hide yes)
				)
			)
			(property "Description" "SMD Chip Resistor"
				(at 20.32 -30.48 0)
				(effects
					(font
						(size 1.27 1.27)
					)
					(justify left bottom)
					(hide yes)
				)
			)
			(property "MPN" "CR0402-FX-4532GLF"
				(at 20.32 -20.32 0)
				(effects
					(font
						(size 1.27 1.27)
						(thickness 0.15)
					)
					(justify left bottom)
					(hide yes)
				)
			)
			(property "Manufacturer" "Bourns"
				(at 20.32 -22.86 0)
				(effects
					(font
						(size 1.27 1.27)
						(thickness 0.15)
					)
					(justify left bottom)
					(hide yes)
				)
			)
			(property "License" "Apache-2.0"
				(at 20.32 -25.4 0)
				(effects
					(font
						(size 1.27 1.27)
						(thickness 0.15)
					)
					(justify left bottom)
					(hide yes)
				)
			)
			(property "Author" "Antmicro"
				(at 20.32 -27.94 0)
				(effects
					(font
						(size 1.27 1.27)
						(thickness 0.15)
					)
					(justify left bottom)
					(hide yes)
				)
			)
			(property "Val" "45k3"
				(at 20.32 -7.62 0)
				(effects
					(font
						(size 1.27 1.27)
						(thickness 0.15)
					)
					(justify left bottom)
				)
			)
			(property "Tolerance" "1%"
				(at 20.32 -10.16 0)
				(effects
					(font
						(size 1.27 1.27)
					)
					(justify left bottom)
					(hide yes)
				)
			)
			(property "ki_keywords" "0402, SMT, RESISTOR, PASSIVE"
				(at 0 0 0)
				(effects
					(font
						(size 1.27 1.27)
					)
					(hide yes)
				)
			)
			(symbol "R_45k3_0402_0_1"
				(rectangle
					(start 0.635 0.889)
					(end 4.445 -0.889)
					(stroke
						(width 0.254)
						(type default)
					)
					(fill
						(type none)
					)
				)
			)
			(symbol "R_45k3_0402_1_1"
				(pin passive line
					(at 0 0 0)
					(length 0.635)
					(name "~"
						(effects
							(font
								(size 1.27 1.27)
							)
						)
					)
					(number "1"
						(effects
							(font
								(size 1.27 1.27)
							)
						)
					)
				)
				(pin passive line
					(at 5.08 0 180)
					(length 0.635)
					(name "~"
						(effects
							(font
								(size 1.27 1.27)
							)
						)
					)
					(number "2"
						(effects
							(font
								(size 1.27 1.27)
							)
						)
					)
				)
			)
		)
	(symbol "antmicroResistors0402:R_470R_0402"
			(pin_numbers
				(hide yes)
			)
			(pin_names
				(hide yes)
			)
			(exclude_from_sim no)
			(in_bom yes)
			(on_board yes)
			(property "Reference" "R"
				(at 20.32 -5.08 0)
				(effects
					(font
						(size 1.27 1.27)
						(thickness 0.15)
					)
					(justify left bottom)
				)
			)
			(property "Value" "R_470R_0402"
				(at 20.32 -12.7 0)
				(effects
					(font
						(size 1.27 1.27)
						(thickness 0.15)
					)
					(justify left bottom)
					(hide yes)
				)
			)
			(property "Footprint" "antmicro-footprints:R_0402_1005Metric"
				(at 20.32 -15.24 0)
				(effects
					(font
						(size 1.27 1.27)
						(thickness 0.15)
					)
					(justify left bottom)
					(hide yes)
				)
			)
			(property "Datasheet" "https://www.bourns.com/docs/product-datasheets/cr.pdf"
				(at 20.32 -17.78 0)
				(effects
					(font
						(size 1.27 1.27)
						(thickness 0.15)
					)
					(justify left bottom)
					(hide yes)
				)
			)
			(property "Description" "SMD Chip Resistor, 470 ohm, ± 1%, 62.5 mW, 0402 [1005 Metric], Thick Film, General Purpose"
				(at 20.32 -30.48 0)
				(effects
					(font
						(size 1.27 1.27)
					)
					(justify left bottom)
					(hide yes)
				)
			)
			(property "MPN" "CR0402-FX-4700GLF"
				(at 20.32 -20.32 0)
				(effects
					(font
						(size 1.27 1.27)
						(thickness 0.15)
					)
					(justify left bottom)
					(hide yes)
				)
			)
			(property "Manufacturer" "Bourns"
				(at 20.32 -22.86 0)
				(effects
					(font
						(size 1.27 1.27)
						(thickness 0.15)
					)
					(justify left bottom)
					(hide yes)
				)
			)
			(property "License" "Apache-2.0"
				(at 20.32 -25.4 0)
				(effects
					(font
						(size 1.27 1.27)
						(thickness 0.15)
					)
					(justify left bottom)
					(hide yes)
				)
			)
			(property "Author" "Antmicro"
				(at 20.32 -27.94 0)
				(effects
					(font
						(size 1.27 1.27)
						(thickness 0.15)
					)
					(justify left bottom)
					(hide yes)
				)
			)
			(property "Val" "470R"
				(at 20.32 -7.62 0)
				(effects
					(font
						(size 1.27 1.27)
						(thickness 0.15)
					)
					(justify left bottom)
				)
			)
			(property "Tolerance" "1%"
				(at 20.32 -10.16 0)
				(effects
					(font
						(size 1.27 1.27)
					)
					(justify left bottom)
					(hide yes)
				)
			)
			(property "ki_keywords" "0402, SMT, RESISTOR, PASSIVE"
				(at 0 0 0)
				(effects
					(font
						(size 1.27 1.27)
					)
					(hide yes)
				)
			)
			(symbol "R_470R_0402_0_1"
				(rectangle
					(start 0.635 0.889)
					(end 4.445 -0.889)
					(stroke
						(width 0.254)
						(type default)
					)
					(fill
						(type none)
					)
				)
			)
			(symbol "R_470R_0402_1_1"
				(pin passive line
					(at 0 0 0)
					(length 0.635)
					(name "~"
						(effects
							(font
								(size 1.27 1.27)
							)
						)
					)
					(number "1"
						(effects
							(font
								(size 1.27 1.27)
							)
						)
					)
				)
				(pin passive line
					(at 5.08 0 180)
					(length 0.635)
					(name "~"
						(effects
							(font
								(size 1.27 1.27)
							)
						)
					)
					(number "2"
						(effects
							(font
								(size 1.27 1.27)
							)
						)
					)
				)
			)
		)
	(symbol "antmicroResistors0402:R_47k_0402"
			(pin_numbers
				(hide yes)
			)
			(pin_names
				(hide yes)
			)
			(exclude_from_sim no)
			(in_bom yes)
			(on_board yes)
			(property "Reference" "R"
				(at 20.32 -5.08 0)
				(effects
					(font
						(size 1.27 1.27)
						(thickness 0.15)
					)
					(justify left bottom)
				)
			)
			(property "Value" "R_47k_0402"
				(at 20.32 -12.7 0)
				(effects
					(font
						(size 1.27 1.27)
						(thickness 0.15)
					)
					(justify left bottom)
					(hide yes)
				)
			)
			(property "Footprint" "antmicro-footprints:R_0402_1005Metric"
				(at 20.32 -15.24 0)
				(effects
					(font
						(size 1.27 1.27)
						(thickness 0.15)
					)
					(justify left bottom)
					(hide yes)
				)
			)
			(property "Datasheet" "https://www.bourns.com/docs/product-datasheets/cr.pdf"
				(at 20.32 -17.78 0)
				(effects
					(font
						(size 1.27 1.27)
						(thickness 0.15)
					)
					(justify left bottom)
					(hide yes)
				)
			)
			(property "Description" "SMD Chip Resistor, 47 kohm, ± 1%, 62.5 mW, 0402 [1005 Metric], Thick Film, General Purpose"
				(at 20.32 -30.48 0)
				(effects
					(font
						(size 1.27 1.27)
					)
					(justify left bottom)
					(hide yes)
				)
			)
			(property "MPN" "CR0402-FX-4702GLF"
				(at 20.32 -20.32 0)
				(effects
					(font
						(size 1.27 1.27)
						(thickness 0.15)
					)
					(justify left bottom)
					(hide yes)
				)
			)
			(property "Manufacturer" "Bourns"
				(at 20.32 -22.86 0)
				(effects
					(font
						(size 1.27 1.27)
						(thickness 0.15)
					)
					(justify left bottom)
					(hide yes)
				)
			)
			(property "License" "Apache-2.0"
				(at 20.32 -25.4 0)
				(effects
					(font
						(size 1.27 1.27)
						(thickness 0.15)
					)
					(justify left bottom)
					(hide yes)
				)
			)
			(property "Author" "Antmicro"
				(at 20.32 -27.94 0)
				(effects
					(font
						(size 1.27 1.27)
						(thickness 0.15)
					)
					(justify left bottom)
					(hide yes)
				)
			)
			(property "Val" "47k"
				(at 20.32 -7.62 0)
				(effects
					(font
						(size 1.27 1.27)
						(thickness 0.15)
					)
					(justify left bottom)
				)
			)
			(property "Tolerance" "1%"
				(at 20.32 -10.16 0)
				(effects
					(font
						(size 1.27 1.27)
					)
					(justify left bottom)
					(hide yes)
				)
			)
			(property "ki_keywords" "0402, SMT, RESISTOR, PASSIVE"
				(at 0 0 0)
				(effects
					(font
						(size 1.27 1.27)
					)
					(hide yes)
				)
			)
			(symbol "R_47k_0402_0_1"
				(rectangle
					(start 0.635 0.889)
					(end 4.445 -0.889)
					(stroke
						(width 0.254)
						(type default)
					)
					(fill
						(type none)
					)
				)
			)
			(symbol "R_47k_0402_1_1"
				(pin passive line
					(at 0 0 0)
					(length 0.635)
					(name "~"
						(effects
							(font
								(size 1.27 1.27)
							)
						)
					)
					(number "1"
						(effects
							(font
								(size 1.27 1.27)
							)
						)
					)
				)
				(pin passive line
					(at 5.08 0 180)
					(length 0.635)
					(name "~"
						(effects
							(font
								(size 1.27 1.27)
							)
						)
					)
					(number "2"
						(effects
							(font
								(size 1.27 1.27)
							)
						)
					)
				)
			)
		)
	(symbol "antmicroResistors0402:R_499k_0402"
			(pin_numbers
				(hide yes)
			)
			(pin_names
				(hide yes)
			)
			(exclude_from_sim no)
			(in_bom yes)
			(on_board yes)
			(property "Reference" "R"
				(at 20.32 -5.08 0)
				(effects
					(font
						(size 1.27 1.27)
						(thickness 0.15)
					)
					(justify left bottom)
				)
			)
			(property "Value" "R_499k_0402"
				(at 20.32 -12.7 0)
				(effects
					(font
						(size 1.27 1.27)
						(thickness 0.15)
					)
					(justify left bottom)
					(hide yes)
				)
			)
			(property "Footprint" "antmicro-footprints:R_0402_1005Metric"
				(at 20.32 -15.24 0)
				(effects
					(font
						(size 1.27 1.27)
						(thickness 0.15)
					)
					(justify left bottom)
					(hide yes)
				)
			)
			(property "Datasheet" "https://www.mouser.com/datasheet/2/54/cr-1858361.pdf"
				(at 20.32 -17.78 0)
				(effects
					(font
						(size 1.27 1.27)
						(thickness 0.15)
					)
					(justify left bottom)
					(hide yes)
				)
			)
			(property "Description" "SMD Chip Resistor, 499 kohm, ± 1%, 63 mW, 0402 [1005 Metric], Thick Film, General Purpose"
				(at 20.32 -30.48 0)
				(effects
					(font
						(size 1.27 1.27)
					)
					(justify left bottom)
					(hide yes)
				)
			)
			(property "MPN" "CR0402-FX-4993GLF"
				(at 20.32 -20.32 0)
				(effects
					(font
						(size 1.27 1.27)
						(thickness 0.15)
					)
					(justify left bottom)
					(hide yes)
				)
			)
			(property "Manufacturer" "Bourns"
				(at 20.32 -22.86 0)
				(effects
					(font
						(size 1.27 1.27)
						(thickness 0.15)
					)
					(justify left bottom)
					(hide yes)
				)
			)
			(property "License" "Apache-2.0"
				(at 20.32 -25.4 0)
				(effects
					(font
						(size 1.27 1.27)
						(thickness 0.15)
					)
					(justify left bottom)
					(hide yes)
				)
			)
			(property "Author" "Antmicro"
				(at 20.32 -27.94 0)
				(effects
					(font
						(size 1.27 1.27)
						(thickness 0.15)
					)
					(justify left bottom)
					(hide yes)
				)
			)
			(property "Val" "499k"
				(at 20.32 -7.62 0)
				(effects
					(font
						(size 1.27 1.27)
						(thickness 0.15)
					)
					(justify left bottom)
				)
			)
			(property "Tolerance" "1%"
				(at 20.32 -10.16 0)
				(effects
					(font
						(size 1.27 1.27)
					)
					(justify left bottom)
					(hide yes)
				)
			)
			(property "ki_keywords" "0402, SMT, RESISTOR, PASSIVE"
				(at 0 0 0)
				(effects
					(font
						(size 1.27 1.27)
					)
					(hide yes)
				)
			)
			(symbol "R_499k_0402_0_1"
				(rectangle
					(start 0.635 0.889)
					(end 4.445 -0.889)
					(stroke
						(width 0.254)
						(type default)
					)
					(fill
						(type none)
					)
				)
			)
			(symbol "R_499k_0402_1_1"
				(pin passive line
					(at 0 0 0)
					(length 0.635)
					(name "~"
						(effects
							(font
								(size 1.27 1.27)
							)
						)
					)
					(number "1"
						(effects
							(font
								(size 1.27 1.27)
							)
						)
					)
				)
				(pin passive line
					(at 5.08 0 180)
					(length 0.635)
					(name "~"
						(effects
							(font
								(size 1.27 1.27)
							)
						)
					)
					(number "2"
						(effects
							(font
								(size 1.27 1.27)
							)
						)
					)
				)
			)
		)
	(symbol "antmicroResistors0402:R_49R9_0402"
			(pin_numbers
				(hide yes)
			)
			(pin_names
				(hide yes)
			)
			(exclude_from_sim no)
			(in_bom yes)
			(on_board yes)
			(property "Reference" "R"
				(at 20.32 -5.08 0)
				(effects
					(font
						(size 1.27 1.27)
						(thickness 0.15)
					)
					(justify left bottom)
				)
			)
			(property "Value" "R_49R9_0402"
				(at 20.32 -12.7 0)
				(effects
					(font
						(size 1.27 1.27)
						(thickness 0.15)
					)
					(justify left bottom)
					(hide yes)
				)
			)
			(property "Footprint" "antmicro-footprints:R_0402_1005Metric"
				(at 20.32 -15.24 0)
				(effects
					(font
						(size 1.27 1.27)
						(thickness 0.15)
					)
					(justify left bottom)
					(hide yes)
				)
			)
			(property "Datasheet" "https://www.bourns.com/docs/product-datasheets/cr.pdf"
				(at 20.32 -17.78 0)
				(effects
					(font
						(size 1.27 1.27)
						(thickness 0.15)
					)
					(justify left bottom)
					(hide yes)
				)
			)
			(property "Description" "SMD Chip Resistor, 49.9 ohm, ± 1%, 62.5 mW, 0402 [1005 Metric], Thick Film, General Purpose"
				(at 20.32 -30.48 0)
				(effects
					(font
						(size 1.27 1.27)
					)
					(justify left bottom)
					(hide yes)
				)
			)
			(property "MPN" "CR0402-FX-49R9GLF"
				(at 20.32 -20.32 0)
				(effects
					(font
						(size 1.27 1.27)
						(thickness 0.15)
					)
					(justify left bottom)
					(hide yes)
				)
			)
			(property "Manufacturer" "Bourns"
				(at 20.32 -22.86 0)
				(effects
					(font
						(size 1.27 1.27)
						(thickness 0.15)
					)
					(justify left bottom)
					(hide yes)
				)
			)
			(property "License" "Apache-2.0"
				(at 20.32 -25.4 0)
				(effects
					(font
						(size 1.27 1.27)
						(thickness 0.15)
					)
					(justify left bottom)
					(hide yes)
				)
			)
			(property "Author" "Antmicro"
				(at 20.32 -27.94 0)
				(effects
					(font
						(size 1.27 1.27)
						(thickness 0.15)
					)
					(justify left bottom)
					(hide yes)
				)
			)
			(property "Val" "49R9"
				(at 20.32 -7.62 0)
				(effects
					(font
						(size 1.27 1.27)
						(thickness 0.15)
					)
					(justify left bottom)
				)
			)
			(property "Tolerance" "1%"
				(at 20.32 -10.16 0)
				(effects
					(font
						(size 1.27 1.27)
					)
					(justify left bottom)
					(hide yes)
				)
			)
			(property "ki_keywords" "0402, SMT, RESISTOR, PASSIVE"
				(at 0 0 0)
				(effects
					(font
						(size 1.27 1.27)
					)
					(hide yes)
				)
			)
			(symbol "R_49R9_0402_0_1"
				(rectangle
					(start 0.635 0.889)
					(end 4.445 -0.889)
					(stroke
						(width 0.254)
						(type default)
					)
					(fill
						(type none)
					)
				)
			)
			(symbol "R_49R9_0402_1_1"
				(pin passive line
					(at 0 0 0)
					(length 0.635)
					(name "~"
						(effects
							(font
								(size 1.27 1.27)
							)
						)
					)
					(number "1"
						(effects
							(font
								(size 1.27 1.27)
							)
						)
					)
				)
				(pin passive line
					(at 5.08 0 180)
					(length 0.635)
					(name "~"
						(effects
							(font
								(size 1.27 1.27)
							)
						)
					)
					(number "2"
						(effects
							(font
								(size 1.27 1.27)
							)
						)
					)
				)
			)
		)
	(symbol "antmicroResistors0402:R_49k9_0402"
			(pin_numbers
				(hide yes)
			)
			(pin_names
				(hide yes)
			)
			(exclude_from_sim no)
			(in_bom yes)
			(on_board yes)
			(property "Reference" "R"
				(at 20.32 -5.08 0)
				(effects
					(font
						(size 1.27 1.27)
						(thickness 0.15)
					)
					(justify left bottom)
				)
			)
			(property "Value" "R_49k9_0402"
				(at 20.32 -12.7 0)
				(effects
					(font
						(size 1.27 1.27)
						(thickness 0.15)
					)
					(justify left bottom)
					(hide yes)
				)
			)
			(property "Footprint" "antmicro-footprints:R_0402_1005Metric"
				(at 20.32 -15.24 0)
				(effects
					(font
						(size 1.27 1.27)
						(thickness 0.15)
					)
					(justify left bottom)
					(hide yes)
				)
			)
			(property "Datasheet" "https://www.bourns.com/docs/product-datasheets/cr.pdf"
				(at 20.32 -17.78 0)
				(effects
					(font
						(size 1.27 1.27)
						(thickness 0.15)
					)
					(justify left bottom)
					(hide yes)
				)
			)
			(property "Description" "SMD Chip Resistor, 49.9 kohm, ± 1%, 63 mW, 0402 [1005 Metric], Thick Film, General Purpose"
				(at 20.32 -30.48 0)
				(effects
					(font
						(size 1.27 1.27)
					)
					(justify left bottom)
					(hide yes)
				)
			)
			(property "MPN" "CR0402-FX-4992GLF"
				(at 20.32 -20.32 0)
				(effects
					(font
						(size 1.27 1.27)
						(thickness 0.15)
					)
					(justify left bottom)
					(hide yes)
				)
			)
			(property "Manufacturer" "Bourns"
				(at 20.32 -22.86 0)
				(effects
					(font
						(size 1.27 1.27)
						(thickness 0.15)
					)
					(justify left bottom)
					(hide yes)
				)
			)
			(property "License" "Apache-2.0"
				(at 20.32 -25.4 0)
				(effects
					(font
						(size 1.27 1.27)
						(thickness 0.15)
					)
					(justify left bottom)
					(hide yes)
				)
			)
			(property "Author" "Antmicro"
				(at 20.32 -27.94 0)
				(effects
					(font
						(size 1.27 1.27)
						(thickness 0.15)
					)
					(justify left bottom)
					(hide yes)
				)
			)
			(property "Val" "49k9"
				(at 20.32 -7.62 0)
				(effects
					(font
						(size 1.27 1.27)
						(thickness 0.15)
					)
					(justify left bottom)
				)
			)
			(property "Tolerance" "1%"
				(at 20.32 -10.16 0)
				(effects
					(font
						(size 1.27 1.27)
					)
					(justify left bottom)
					(hide yes)
				)
			)
			(property "ki_keywords" "0402, SMT, RESISTOR, PASSIVE"
				(at 0 0 0)
				(effects
					(font
						(size 1.27 1.27)
					)
					(hide yes)
				)
			)
			(symbol "R_49k9_0402_0_1"
				(rectangle
					(start 0.635 0.889)
					(end 4.445 -0.889)
					(stroke
						(width 0.254)
						(type default)
					)
					(fill
						(type none)
					)
				)
			)
			(symbol "R_49k9_0402_1_1"
				(pin passive line
					(at 0 0 0)
					(length 0.635)
					(name "~"
						(effects
							(font
								(size 1.27 1.27)
							)
						)
					)
					(number "1"
						(effects
							(font
								(size 1.27 1.27)
							)
						)
					)
				)
				(pin passive line
					(at 5.08 0 180)
					(length 0.635)
					(name "~"
						(effects
							(font
								(size 1.27 1.27)
							)
						)
					)
					(number "2"
						(effects
							(font
								(size 1.27 1.27)
							)
						)
					)
				)
			)
		)
	(symbol "antmicroResistors0402:R_4k7_0402"
			(pin_numbers
				(hide yes)
			)
			(pin_names
				(hide yes)
			)
			(exclude_from_sim no)
			(in_bom yes)
			(on_board yes)
			(property "Reference" "R"
				(at 20.32 -5.08 0)
				(effects
					(font
						(size 1.27 1.27)
						(thickness 0.15)
					)
					(justify left bottom)
				)
			)
			(property "Value" "R_4k7_0402"
				(at 20.32 -12.7 0)
				(effects
					(font
						(size 1.27 1.27)
						(thickness 0.15)
					)
					(justify left bottom)
					(hide yes)
				)
			)
			(property "Footprint" "antmicro-footprints:R_0402_1005Metric"
				(at 20.32 -15.24 0)
				(effects
					(font
						(size 1.27 1.27)
						(thickness 0.15)
					)
					(justify left bottom)
					(hide yes)
				)
			)
			(property "Datasheet" "https://www.bourns.com/docs/product-datasheets/cr.pdf"
				(at 20.32 -17.78 0)
				(effects
					(font
						(size 1.27 1.27)
						(thickness 0.15)
					)
					(justify left bottom)
					(hide yes)
				)
			)
			(property "Description" "SMD Chip Resistor, 4.7 kohm, ± 1%, 62.5 mW, 0402 [1005 Metric], Thick Film, General Purpose"
				(at 20.32 -30.48 0)
				(effects
					(font
						(size 1.27 1.27)
					)
					(justify left bottom)
					(hide yes)
				)
			)
			(property "MPN" "CR0402-FX-4701GLF"
				(at 20.32 -20.32 0)
				(effects
					(font
						(size 1.27 1.27)
						(thickness 0.15)
					)
					(justify left bottom)
					(hide yes)
				)
			)
			(property "Manufacturer" "Bourns"
				(at 20.32 -22.86 0)
				(effects
					(font
						(size 1.27 1.27)
						(thickness 0.15)
					)
					(justify left bottom)
					(hide yes)
				)
			)
			(property "License" "Apache-2.0"
				(at 20.32 -25.4 0)
				(effects
					(font
						(size 1.27 1.27)
						(thickness 0.15)
					)
					(justify left bottom)
					(hide yes)
				)
			)
			(property "Author" "Antmicro"
				(at 20.32 -27.94 0)
				(effects
					(font
						(size 1.27 1.27)
						(thickness 0.15)
					)
					(justify left bottom)
					(hide yes)
				)
			)
			(property "Val" "4k7"
				(at 20.32 -7.62 0)
				(effects
					(font
						(size 1.27 1.27)
						(thickness 0.15)
					)
					(justify left bottom)
				)
			)
			(property "Tolerance" "1%"
				(at 20.32 -10.16 0)
				(effects
					(font
						(size 1.27 1.27)
					)
					(justify left bottom)
					(hide yes)
				)
			)
			(property "ki_keywords" "0402, SMT, RESISTOR, PASSIVE"
				(at 0 0 0)
				(effects
					(font
						(size 1.27 1.27)
					)
					(hide yes)
				)
			)
			(symbol "R_4k7_0402_0_1"
				(rectangle
					(start 0.635 0.889)
					(end 4.445 -0.889)
					(stroke
						(width 0.254)
						(type default)
					)
					(fill
						(type none)
					)
				)
			)
			(symbol "R_4k7_0402_1_1"
				(pin passive line
					(at 0 0 0)
					(length 0.635)
					(name "~"
						(effects
							(font
								(size 1.27 1.27)
							)
						)
					)
					(number "1"
						(effects
							(font
								(size 1.27 1.27)
							)
						)
					)
				)
				(pin passive line
					(at 5.08 0 180)
					(length 0.635)
					(name "~"
						(effects
							(font
								(size 1.27 1.27)
							)
						)
					)
					(number "2"
						(effects
							(font
								(size 1.27 1.27)
							)
						)
					)
				)
			)
		)
	(symbol "antmicroResistors0402:R_51k_0402"
			(pin_numbers
				(hide yes)
			)
			(pin_names
				(hide yes)
			)
			(exclude_from_sim no)
			(in_bom yes)
			(on_board yes)
			(property "Reference" "R"
				(at 20.32 -5.08 0)
				(effects
					(font
						(size 1.27 1.27)
						(thickness 0.15)
					)
					(justify left bottom)
				)
			)
			(property "Value" "R_51k_0402"
				(at 20.32 -12.7 0)
				(effects
					(font
						(size 1.27 1.27)
						(thickness 0.15)
					)
					(justify left bottom)
					(hide yes)
				)
			)
			(property "Footprint" "antmicro-footprints:R_0402_1005Metric"
				(at 20.32 -15.24 0)
				(effects
					(font
						(size 1.27 1.27)
						(thickness 0.15)
					)
					(justify left bottom)
					(hide yes)
				)
			)
			(property "Datasheet" "https://www.bourns.com/docs/product-datasheets/cr.pdf"
				(at 20.32 -17.78 0)
				(effects
					(font
						(size 1.27 1.27)
						(thickness 0.15)
					)
					(justify left bottom)
					(hide yes)
				)
			)
			(property "Description" "SMD Chip Resistor, 51 kohm, ± 1%, 63 mW, 0402 [1005 Metric], Thick Film, General Purpose"
				(at 20.32 -30.48 0)
				(effects
					(font
						(size 1.27 1.27)
					)
					(justify left bottom)
					(hide yes)
				)
			)
			(property "MPN" "CR0402-FX-5102GLF"
				(at 20.32 -20.32 0)
				(effects
					(font
						(size 1.27 1.27)
						(thickness 0.15)
					)
					(justify left bottom)
					(hide yes)
				)
			)
			(property "Manufacturer" "Bourns"
				(at 20.32 -22.86 0)
				(effects
					(font
						(size 1.27 1.27)
						(thickness 0.15)
					)
					(justify left bottom)
					(hide yes)
				)
			)
			(property "License" "Apache-2.0"
				(at 20.32 -25.4 0)
				(effects
					(font
						(size 1.27 1.27)
						(thickness 0.15)
					)
					(justify left bottom)
					(hide yes)
				)
			)
			(property "Author" "Antmicro"
				(at 20.32 -27.94 0)
				(effects
					(font
						(size 1.27 1.27)
						(thickness 0.15)
					)
					(justify left bottom)
					(hide yes)
				)
			)
			(property "Val" "51k"
				(at 20.32 -7.62 0)
				(effects
					(font
						(size 1.27 1.27)
						(thickness 0.15)
					)
					(justify left bottom)
				)
			)
			(property "Tolerance" "1%"
				(at 20.32 -10.16 0)
				(effects
					(font
						(size 1.27 1.27)
					)
					(justify left bottom)
					(hide yes)
				)
			)
			(property "ki_keywords" "0402, SMT, RESISTOR, PASSIVE"
				(at 0 0 0)
				(effects
					(font
						(size 1.27 1.27)
					)
					(hide yes)
				)
			)
			(symbol "R_51k_0402_0_1"
				(rectangle
					(start 0.635 0.889)
					(end 4.445 -0.889)
					(stroke
						(width 0.254)
						(type default)
					)
					(fill
						(type none)
					)
				)
			)
			(symbol "R_51k_0402_1_1"
				(pin passive line
					(at 0 0 0)
					(length 0.635)
					(name "~"
						(effects
							(font
								(size 1.27 1.27)
							)
						)
					)
					(number "1"
						(effects
							(font
								(size 1.27 1.27)
							)
						)
					)
				)
				(pin passive line
					(at 5.08 0 180)
					(length 0.635)
					(name "~"
						(effects
							(font
								(size 1.27 1.27)
							)
						)
					)
					(number "2"
						(effects
							(font
								(size 1.27 1.27)
							)
						)
					)
				)
			)
		)
	(symbol "antmicroResistors0402:R_73k2_0402"
			(pin_numbers
				(hide yes)
			)
			(pin_names
				(hide yes)
			)
			(exclude_from_sim no)
			(in_bom yes)
			(on_board yes)
			(property "Reference" "R"
				(at 20.32 -5.08 0)
				(effects
					(font
						(size 1.27 1.27)
						(thickness 0.15)
					)
					(justify left bottom)
				)
			)
			(property "Value" "R_73k2_0402"
				(at 20.32 -12.7 0)
				(effects
					(font
						(size 1.27 1.27)
						(thickness 0.15)
					)
					(justify left bottom)
					(hide yes)
				)
			)
			(property "Footprint" "antmicro-footprints:R_0402_1005Metric"
				(at 20.32 -15.24 0)
				(effects
					(font
						(size 1.27 1.27)
						(thickness 0.15)
					)
					(justify left bottom)
					(hide yes)
				)
			)
			(property "Datasheet" "https://www.bourns.com/docs/product-datasheets/cr.pdf"
				(at 20.32 -17.78 0)
				(effects
					(font
						(size 1.27 1.27)
						(thickness 0.15)
					)
					(justify left bottom)
					(hide yes)
				)
			)
			(property "Description" "SMD Chip Resistor"
				(at 20.32 -30.48 0)
				(effects
					(font
						(size 1.27 1.27)
					)
					(justify left bottom)
					(hide yes)
				)
			)
			(property "MPN" "CR0402-FX-7322GLF"
				(at 20.32 -20.32 0)
				(effects
					(font
						(size 1.27 1.27)
						(thickness 0.15)
					)
					(justify left bottom)
					(hide yes)
				)
			)
			(property "Manufacturer" "Bourns"
				(at 20.32 -22.86 0)
				(effects
					(font
						(size 1.27 1.27)
						(thickness 0.15)
					)
					(justify left bottom)
					(hide yes)
				)
			)
			(property "License" "Apache-2.0"
				(at 20.32 -25.4 0)
				(effects
					(font
						(size 1.27 1.27)
						(thickness 0.15)
					)
					(justify left bottom)
					(hide yes)
				)
			)
			(property "Author" "Antmicro"
				(at 20.32 -27.94 0)
				(effects
					(font
						(size 1.27 1.27)
						(thickness 0.15)
					)
					(justify left bottom)
					(hide yes)
				)
			)
			(property "Val" "73k2"
				(at 20.32 -7.62 0)
				(effects
					(font
						(size 1.27 1.27)
						(thickness 0.15)
					)
					(justify left bottom)
				)
			)
			(property "Tolerance" "1%"
				(at 20.32 -10.16 0)
				(effects
					(font
						(size 1.27 1.27)
					)
					(justify left bottom)
					(hide yes)
				)
			)
			(property "ki_keywords" "0402, SMT, RESISTOR, PASSIVE"
				(at 0 0 0)
				(effects
					(font
						(size 1.27 1.27)
					)
					(hide yes)
				)
			)
			(symbol "R_73k2_0402_0_1"
				(rectangle
					(start 0.635 0.889)
					(end 4.445 -0.889)
					(stroke
						(width 0.254)
						(type default)
					)
					(fill
						(type none)
					)
				)
			)
			(symbol "R_73k2_0402_1_1"
				(pin passive line
					(at 0 0 0)
					(length 0.635)
					(name "~"
						(effects
							(font
								(size 1.27 1.27)
							)
						)
					)
					(number "1"
						(effects
							(font
								(size 1.27 1.27)
							)
						)
					)
				)
				(pin passive line
					(at 5.08 0 180)
					(length 0.635)
					(name "~"
						(effects
							(font
								(size 1.27 1.27)
							)
						)
					)
					(number "2"
						(effects
							(font
								(size 1.27 1.27)
							)
						)
					)
				)
			)
		)
	(symbol "antmicroResistors0402:R_887k_0402"
			(pin_numbers
				(hide yes)
			)
			(pin_names
				(hide yes)
			)
			(exclude_from_sim no)
			(in_bom yes)
			(on_board yes)
			(property "Reference" "R"
				(at 20.32 -5.08 0)
				(effects
					(font
						(size 1.27 1.27)
						(thickness 0.15)
					)
					(justify left bottom)
				)
			)
			(property "Value" "R_887k_0402"
				(at 20.32 -12.7 0)
				(effects
					(font
						(size 1.27 1.27)
						(thickness 0.15)
					)
					(justify left bottom)
					(hide yes)
				)
			)
			(property "Footprint" "antmicro-footprints:R_0402_1005Metric"
				(at 20.32 -15.24 0)
				(effects
					(font
						(size 1.27 1.27)
						(thickness 0.15)
					)
					(justify left bottom)
					(hide yes)
				)
			)
			(property "Datasheet" "https://eu.mouser.com/datasheet/2/315/AOA0000C304-1149620.pdf"
				(at 20.32 -17.78 0)
				(effects
					(font
						(size 1.27 1.27)
						(thickness 0.15)
					)
					(justify left bottom)
					(hide yes)
				)
			)
			(property "Description" "SMD Chip Resistor"
				(at 20.32 -30.48 0)
				(effects
					(font
						(size 1.27 1.27)
					)
					(justify left bottom)
					(hide yes)
				)
			)
			(property "MPN" "ERJ-2RKF8873X"
				(at 20.32 -20.32 0)
				(effects
					(font
						(size 1.27 1.27)
						(thickness 0.15)
					)
					(justify left bottom)
					(hide yes)
				)
			)
			(property "Manufacturer" "Panasonic"
				(at 20.32 -22.86 0)
				(effects
					(font
						(size 1.27 1.27)
						(thickness 0.15)
					)
					(justify left bottom)
					(hide yes)
				)
			)
			(property "License" "Apache-2.0"
				(at 20.32 -25.4 0)
				(effects
					(font
						(size 1.27 1.27)
						(thickness 0.15)
					)
					(justify left bottom)
					(hide yes)
				)
			)
			(property "Author" "Antmicro"
				(at 20.32 -27.94 0)
				(effects
					(font
						(size 1.27 1.27)
						(thickness 0.15)
					)
					(justify left bottom)
					(hide yes)
				)
			)
			(property "Val" "887k"
				(at 20.32 -7.62 0)
				(effects
					(font
						(size 1.27 1.27)
						(thickness 0.15)
					)
					(justify left bottom)
				)
			)
			(property "Tolerance" "1%"
				(at 20.32 -10.16 0)
				(effects
					(font
						(size 1.27 1.27)
					)
					(justify left bottom)
					(hide yes)
				)
			)
			(property "ki_keywords" "0402, SMT, RESISTOR, PASSIVE"
				(at 0 0 0)
				(effects
					(font
						(size 1.27 1.27)
					)
					(hide yes)
				)
			)
			(symbol "R_887k_0402_0_1"
				(rectangle
					(start 0.635 0.889)
					(end 4.445 -0.889)
					(stroke
						(width 0.254)
						(type default)
					)
					(fill
						(type none)
					)
				)
			)
			(symbol "R_887k_0402_1_1"
				(pin passive line
					(at 0 0 0)
					(length 0.635)
					(name "~"
						(effects
							(font
								(size 1.27 1.27)
							)
						)
					)
					(number "1"
						(effects
							(font
								(size 1.27 1.27)
							)
						)
					)
				)
				(pin passive line
					(at 5.08 0 180)
					(length 0.635)
					(name "~"
						(effects
							(font
								(size 1.27 1.27)
							)
						)
					)
					(number "2"
						(effects
							(font
								(size 1.27 1.27)
							)
						)
					)
				)
			)
		)
	(symbol "antmicroResistors0603:R_0R_22.4A_0603"
			(pin_numbers
				(hide yes)
			)
			(pin_names
				(hide yes)
			)
			(exclude_from_sim no)
			(in_bom yes)
			(on_board yes)
			(property "Reference" "R"
				(at 15.24 -2.54 0)
				(effects
					(font
						(size 1.27 1.27)
						(thickness 0.15)
					)
					(justify left bottom)
				)
			)
			(property "Value" "R_0R_22.4A_0603"
				(at 15.24 -5.08 0)
				(effects
					(font
						(size 1.27 1.27)
						(thickness 0.15)
					)
					(justify left bottom)
					(hide yes)
				)
			)
			(property "Footprint" "antmicro-footprints:R_0603_1608Metric"
				(at 15.24 -10.16 0)
				(effects
					(font
						(size 1.27 1.27)
						(thickness 0.15)
					)
					(justify left bottom)
					(hide yes)
				)
			)
			(property "Datasheet" "https://fscdn.rohm.com/en/products/databook/datasheet/passive/resistor/chip_resistor/pmr-jpw-e.pdf"
				(at 15.24 -12.7 0)
				(effects
					(font
						(size 1.27 1.27)
						(thickness 0.15)
					)
					(justify left bottom)
					(hide yes)
				)
			)
			(property "Description" "SMD Chip Resistor"
				(at 15.24 -27.94 0)
				(effects
					(font
						(size 1.27 1.27)
					)
					(justify left bottom)
					(hide yes)
				)
			)
			(property "MPN" "PMR03EZPJ000"
				(at 15.24 -15.24 0)
				(effects
					(font
						(size 1.27 1.27)
						(thickness 0.15)
					)
					(justify left bottom)
					(hide yes)
				)
			)
			(property "Manufacturer" "ROHM Semiconductor"
				(at 15.24 -17.78 0)
				(effects
					(font
						(size 1.27 1.27)
						(thickness 0.15)
					)
					(justify left bottom)
					(hide yes)
				)
			)
			(property "Val" "0R"
				(at 15.24 -7.62 0)
				(effects
					(font
						(size 1.27 1.27)
						(thickness 0.15)
					)
					(justify left bottom)
				)
			)
			(property "Max. Curr." "22.4A"
				(at 15.24 -20.32 0)
				(effects
					(font
						(size 1.27 1.27)
						(thickness 0.15)
					)
					(justify left bottom)
				)
			)
			(property "Author" "Antmicro"
				(at 15.24 -22.86 0)
				(effects
					(font
						(size 1.27 1.27)
						(thickness 0.15)
					)
					(justify left bottom)
					(hide yes)
				)
			)
			(property "License" "Apache-2.0"
				(at 15.24 -25.4 0)
				(effects
					(font
						(size 1.27 1.27)
						(thickness 0.15)
					)
					(justify left bottom)
					(hide yes)
				)
			)
			(property "Tolerance" "template_tolerance"
				(at 20.32 -10.16 0)
				(effects
					(font
						(size 1.27 1.27)
					)
					(justify left bottom)
					(hide yes)
				)
			)
			(property "ki_keywords" "0603, SMT, RESISTOR, PASSIVE"
				(at 0 0 0)
				(effects
					(font
						(size 1.27 1.27)
					)
					(hide yes)
				)
			)
			(symbol "R_0R_22.4A_0603_0_1"
				(rectangle
					(start 0.635 0.889)
					(end 4.445 -0.889)
					(stroke
						(width 0.254)
						(type default)
					)
					(fill
						(type none)
					)
				)
			)
			(symbol "R_0R_22.4A_0603_1_1"
				(pin passive line
					(at 0 0 0)
					(length 0.635)
					(name "~"
						(effects
							(font
								(size 1.27 1.27)
							)
						)
					)
					(number "1"
						(effects
							(font
								(size 1.27 1.27)
							)
						)
					)
				)
				(pin passive line
					(at 5.08 0 180)
					(length 0.635)
					(name "~"
						(effects
							(font
								(size 1.27 1.27)
							)
						)
					)
					(number "2"
						(effects
							(font
								(size 1.27 1.27)
							)
						)
					)
				)
			)
		)
	(symbol "antmicroResistorsmisc:R_0R001_0805"
			(pin_numbers
				(hide yes)
			)
			(pin_names
				(hide yes)
			)
			(exclude_from_sim no)
			(in_bom yes)
			(on_board yes)
			(property "Reference" "R"
				(at 20.32 -5.08 0)
				(effects
					(font
						(size 1.27 1.27)
						(thickness 0.15)
					)
					(justify left bottom)
				)
			)
			(property "Value" "R_0R001_0805"
				(at 20.32 -12.7 0)
				(effects
					(font
						(size 1.27 1.27)
						(thickness 0.15)
					)
					(justify left bottom)
					(hide yes)
				)
			)
			(property "Footprint" "antmicro-footprints:R_0805_2012Metric"
				(at 20.32 -15.24 0)
				(effects
					(font
						(size 1.27 1.27)
						(thickness 0.15)
					)
					(justify left bottom)
					(hide yes)
				)
			)
			(property "Datasheet" "https://www.eaton.com/content/dam/eaton/products/electronic-components/resources/data-sheet/eaton-msma-automotive-smd-current-sense-resistor-metal-strip-data-sheet-elx1179.pdf"
				(at 20.32 -17.78 0)
				(effects
					(font
						(size 1.27 1.27)
						(thickness 0.15)
					)
					(justify left bottom)
					(hide yes)
				)
			)
			(property "Description" "Current Sense Resistors - SMD MSMA, 0805 SIZE, 1/2 Watt, 1 mohm, 50 TCR MnCu Metal AEC-Q"
				(at 20.32 -30.48 0)
				(effects
					(font
						(size 1.27 1.27)
					)
					(justify left bottom)
					(hide yes)
				)
			)
			(property "MPN" "MSMA0805R0010FSM"
				(at 20.32 -20.32 0)
				(effects
					(font
						(size 1.27 1.27)
						(thickness 0.15)
					)
					(justify left bottom)
					(hide yes)
				)
			)
			(property "Manufacturer" "Eaton"
				(at 20.32 -22.86 0)
				(effects
					(font
						(size 1.27 1.27)
						(thickness 0.15)
					)
					(justify left bottom)
					(hide yes)
				)
			)
			(property "License" "Apache-2.0"
				(at 20.32 -25.4 0)
				(effects
					(font
						(size 1.27 1.27)
						(thickness 0.15)
					)
					(justify left bottom)
					(hide yes)
				)
			)
			(property "Author" "Antmicro"
				(at 20.32 -27.94 0)
				(effects
					(font
						(size 1.27 1.27)
						(thickness 0.15)
					)
					(justify left bottom)
					(hide yes)
				)
			)
			(property "Val" "0R001"
				(at 20.32 -7.62 0)
				(effects
					(font
						(size 1.27 1.27)
						(thickness 0.15)
					)
					(justify left bottom)
				)
			)
			(property "Tolerance" "1%"
				(at 20.32 -10.16 0)
				(effects
					(font
						(size 1.27 1.27)
					)
					(justify left bottom)
					(hide yes)
				)
			)
			(property "ki_keywords" "0805, SMT, RESISTOR, PASSIVE"
				(at 0 0 0)
				(effects
					(font
						(size 1.27 1.27)
					)
					(hide yes)
				)
			)
			(symbol "R_0R001_0805_0_1"
				(rectangle
					(start 0.635 0.889)
					(end 4.445 -0.889)
					(stroke
						(width 0.254)
						(type default)
					)
					(fill
						(type none)
					)
				)
			)
			(symbol "R_0R001_0805_1_1"
				(pin passive line
					(at 0 0 0)
					(length 0.635)
					(name "~"
						(effects
							(font
								(size 1.27 1.27)
							)
						)
					)
					(number "1"
						(effects
							(font
								(size 1.27 1.27)
							)
						)
					)
				)
				(pin passive line
					(at 5.08 0 180)
					(length 0.635)
					(name "~"
						(effects
							(font
								(size 1.27 1.27)
							)
						)
					)
					(number "2"
						(effects
							(font
								(size 1.27 1.27)
							)
						)
					)
				)
			)
		)
	(symbol "antmicroResistorsmisc:R_220R_1206"
			(pin_numbers
				(hide yes)
			)
			(pin_names
				(hide yes)
			)
			(exclude_from_sim no)
			(in_bom yes)
			(on_board yes)
			(property "Reference" "R"
				(at 20.32 -5.08 0)
				(effects
					(font
						(size 1.27 1.27)
						(thickness 0.15)
					)
					(justify left bottom)
				)
			)
			(property "Value" "R_220R_1206"
				(at 20.32 -12.7 0)
				(effects
					(font
						(size 1.27 1.27)
						(thickness 0.15)
					)
					(justify left bottom)
					(hide yes)
				)
			)
			(property "Footprint" "antmicro-footprints:R_1206_3216Metric"
				(at 20.32 -15.24 0)
				(effects
					(font
						(size 1.27 1.27)
						(thickness 0.15)
					)
					(justify left bottom)
					(hide yes)
				)
			)
			(property "Datasheet" "https://www.bourns.com/docs/product-datasheets/cr.pdf"
				(at 20.32 -17.78 0)
				(effects
					(font
						(size 1.27 1.27)
						(thickness 0.15)
					)
					(justify left bottom)
					(hide yes)
				)
			)
			(property "Description" "SMT Chip Resistor, 220 ohm, ± 1%, 250 mW, 1206 [3216 Metric]"
				(at 20.32 -30.48 0)
				(effects
					(font
						(size 1.27 1.27)
					)
					(justify left bottom)
					(hide yes)
				)
			)
			(property "MPN" "CR1206-FX-2200ELF"
				(at 20.32 -20.32 0)
				(effects
					(font
						(size 1.27 1.27)
						(thickness 0.15)
					)
					(justify left bottom)
					(hide yes)
				)
			)
			(property "Manufacturer" "Bourns"
				(at 20.32 -22.86 0)
				(effects
					(font
						(size 1.27 1.27)
						(thickness 0.15)
					)
					(justify left bottom)
					(hide yes)
				)
			)
			(property "License" "Apache-2.0"
				(at 20.32 -25.4 0)
				(effects
					(font
						(size 1.27 1.27)
						(thickness 0.15)
					)
					(justify left bottom)
					(hide yes)
				)
			)
			(property "Author" "Antmicro"
				(at 20.32 -27.94 0)
				(effects
					(font
						(size 1.27 1.27)
						(thickness 0.15)
					)
					(justify left bottom)
					(hide yes)
				)
			)
			(property "Val" "220R"
				(at 20.32 -7.62 0)
				(effects
					(font
						(size 1.27 1.27)
						(thickness 0.15)
					)
					(justify left bottom)
				)
			)
			(property "Tolerance" "1%"
				(at 20.32 -10.16 0)
				(effects
					(font
						(size 1.27 1.27)
					)
					(justify left bottom)
					(hide yes)
				)
			)
			(property "ki_keywords" "1206, SMT, RESISTOR, PASSIVE"
				(at 0 0 0)
				(effects
					(font
						(size 1.27 1.27)
					)
					(hide yes)
				)
			)
			(symbol "R_220R_1206_0_1"
				(rectangle
					(start 0.635 0.889)
					(end 4.445 -0.889)
					(stroke
						(width 0.254)
						(type default)
					)
					(fill
						(type none)
					)
				)
			)
			(symbol "R_220R_1206_1_1"
				(pin passive line
					(at 0 0 0)
					(length 0.635)
					(name "~"
						(effects
							(font
								(size 1.27 1.27)
							)
						)
					)
					(number "1"
						(effects
							(font
								(size 1.27 1.27)
							)
						)
					)
				)
				(pin passive line
					(at 5.08 0 180)
					(length 0.635)
					(name "~"
						(effects
							(font
								(size 1.27 1.27)
							)
						)
					)
					(number "2"
						(effects
							(font
								(size 1.27 1.27)
							)
						)
					)
				)
			)
		)
	(symbol "antmicroSlideSwitches:SW_SPDT_PCM12SMTR"
			(exclude_from_sim no)
			(in_bom yes)
			(on_board yes)
			(property "Reference" "SW"
				(at 27.94 -5.08 0)
				(effects
					(font
						(size 1.27 1.27)
						(thickness 0.15)
					)
					(justify left bottom)
				)
			)
			(property "Value" "SW_SPDT_PCM12SMTR"
				(at 27.94 -7.62 0)
				(effects
					(font
						(size 1.27 1.27)
						(thickness 0.15)
					)
					(justify left bottom)
				)
			)
			(property "Footprint" "antmicro-footprints:PCM12SMTR"
				(at 27.94 -10.16 0)
				(effects
					(font
						(size 1.27 1.27)
						(thickness 0.15)
					)
					(justify left bottom)
					(hide yes)
				)
			)
			(property "Datasheet" "https://www.mouser.com/datasheet/2/60/pcm-1841544.pdf"
				(at 27.94 -12.7 0)
				(effects
					(font
						(size 1.27 1.27)
						(thickness 0.15)
					)
					(justify left bottom)
					(hide yes)
				)
			)
			(property "Description" "Slide switch"
				(at 27.94 -25.4 0)
				(effects
					(font
						(size 1.27 1.27)
					)
					(justify left bottom)
					(hide yes)
				)
			)
			(property "Manufacturer" "C&K"
				(at 27.94 -15.24 0)
				(effects
					(font
						(size 1.27 1.27)
						(thickness 0.15)
					)
					(justify left bottom)
					(hide yes)
				)
			)
			(property "MPN" "PCM12SMTR"
				(at 27.94 -17.78 0)
				(effects
					(font
						(size 1.27 1.27)
						(thickness 0.15)
					)
					(justify left bottom)
					(hide yes)
				)
			)
			(property "Author" "Antmicro"
				(at 27.94 -20.32 0)
				(effects
					(font
						(size 1.27 1.27)
						(thickness 0.15)
					)
					(justify left bottom)
					(hide yes)
				)
			)
			(property "License" "Apache-2.0"
				(at 27.94 -22.86 0)
				(effects
					(font
						(size 1.27 1.27)
						(thickness 0.15)
					)
					(justify left bottom)
					(hide yes)
				)
			)
			(property "ki_keywords" "VERTICAL, SMT, SWITCH, SWITCH, SLIDE"
				(at 0 0 0)
				(effects
					(font
						(size 1.27 1.27)
					)
					(hide yes)
				)
			)
			(symbol "SW_SPDT_PCM12SMTR_1_1"
				(rectangle
					(start 2.54 3.81)
					(end 10.16 -3.81)
					(stroke
						(width 0.254)
						(type default)
					)
					(fill
						(type background)
					)
				)
				(polyline
					(pts
						(xy 3.81 0) (xy 2.54 0)
					)
					(stroke
						(width 0.254)
						(type default)
					)
					(fill
						(type none)
					)
				)
				(circle
					(center 4.064 0)
					(radius 0.3556)
					(stroke
						(width 0.254)
						(type default)
					)
					(fill
						(type outline)
					)
				)
				(polyline
					(pts
						(xy 4.318 0) (xy 8.89 -2.54)
					)
					(stroke
						(width 0.254)
						(type default)
					)
					(fill
						(type none)
					)
				)
				(circle
					(center 8.636 -2.54)
					(radius 0.3556)
					(stroke
						(width 0.254)
						(type default)
					)
					(fill
						(type outline)
					)
				)
				(circle
					(center 8.89 2.54)
					(radius 0.3556)
					(stroke
						(width 0.254)
						(type default)
					)
					(fill
						(type outline)
					)
				)
				(polyline
					(pts
						(xy 10.16 2.54) (xy 8.89 2.54)
					)
					(stroke
						(width 0.254)
						(type default)
					)
					(fill
						(type none)
					)
				)
				(polyline
					(pts
						(xy 10.16 -2.54) (xy 8.89 -2.54)
					)
					(stroke
						(width 0.254)
						(type default)
					)
					(fill
						(type none)
					)
				)
				(pin passive line
					(at 0 0 0)
					(length 2.54)
					(name "~"
						(effects
							(font
								(size 1.27 1.27)
							)
						)
					)
					(number "2"
						(effects
							(font
								(size 1.27 1.27)
							)
						)
					)
				)
				(pin passive line
					(at 0 -2.54 0)
					(length 2.54)
					(hide yes)
					(name "SH"
						(effects
							(font
								(size 1.27 1.27)
							)
						)
					)
					(number "S1"
						(effects
							(font
								(size 1.27 1.27)
							)
						)
					)
				)
				(pin passive line
					(at 0 -2.54 0)
					(length 2.54)
					(hide yes)
					(name "SH"
						(effects
							(font
								(size 1.27 1.27)
							)
						)
					)
					(number "S2"
						(effects
							(font
								(size 1.27 1.27)
							)
						)
					)
				)
				(pin passive line
					(at 0 -2.54 0)
					(length 2.54)
					(hide yes)
					(name "SH"
						(effects
							(font
								(size 1.27 1.27)
							)
						)
					)
					(number "S3"
						(effects
							(font
								(size 1.27 1.27)
							)
						)
					)
				)
				(pin passive line
					(at 0 -2.54 0)
					(length 2.54)
					(name "SH"
						(effects
							(font
								(size 1.27 1.27)
							)
						)
					)
					(number "S4"
						(effects
							(font
								(size 1.27 1.27)
							)
						)
					)
				)
				(pin passive line
					(at 12.7 2.54 180)
					(length 2.54)
					(name "~"
						(effects
							(font
								(size 1.27 1.27)
							)
						)
					)
					(number "1"
						(effects
							(font
								(size 1.27 1.27)
							)
						)
					)
				)
				(pin passive line
					(at 12.7 -2.54 180)
					(length 2.54)
					(name "~"
						(effects
							(font
								(size 1.27 1.27)
							)
						)
					)
					(number "3"
						(effects
							(font
								(size 1.27 1.27)
							)
						)
					)
				)
			)
		)
	(symbol "antmicroTVSDiodes:ESDA25P35-1U1M"
			(pin_numbers
				(hide yes)
			)
			(pin_names
				(hide yes)
			)
			(exclude_from_sim no)
			(in_bom yes)
			(on_board yes)
			(property "Reference" "D"
				(at 24.13 -5.08 0)
				(effects
					(font
						(size 1.27 1.27)
						(thickness 0.15)
					)
					(justify left bottom)
				)
			)
			(property "Value" "ESDA25P35-1U1M"
				(at 24.13 -15.24 0)
				(effects
					(font
						(size 1.27 1.27)
						(thickness 0.15)
					)
					(justify left bottom)
					(hide yes)
				)
			)
			(property "Footprint" "antmicro-footprints:QFN-2L_1.6x1x0.55mm"
				(at 24.13 -10.16 0)
				(effects
					(font
						(size 1.27 1.27)
						(thickness 0.15)
					)
					(justify left bottom)
					(hide yes)
				)
			)
			(property "Datasheet" "https://www.st.com/resource/en/datasheet/esda25p35-1u1m.pdf"
				(at 24.13 -12.7 0)
				(effects
					(font
						(size 1.27 1.27)
						(thickness 0.15)
					)
					(justify left bottom)
					(hide yes)
				)
			)
			(property "Description" "Unidirectional TVS, 30 kV, QFN-2L, 22 V, 195 pF"
				(at 24.13 -25.4 0)
				(effects
					(font
						(size 1.27 1.27)
					)
					(justify left bottom)
					(hide yes)
				)
			)
			(property "MPN" "ESDA25P35-1U1M"
				(at 24.13 -7.62 0)
				(effects
					(font
						(size 1.27 1.27)
						(thickness 0.15)
					)
					(justify left bottom)
				)
			)
			(property "Manufacturer" "STMicroelectronics"
				(at 24.13 -17.78 0)
				(effects
					(font
						(size 1.27 1.27)
						(thickness 0.15)
					)
					(justify left bottom)
					(hide yes)
				)
			)
			(property "Author" "Antmicro"
				(at 24.13 -20.32 0)
				(effects
					(font
						(size 1.27 1.27)
						(thickness 0.15)
					)
					(justify left bottom)
					(hide yes)
				)
			)
			(property "License" "Apache-2.0"
				(at 24.13 -22.86 0)
				(effects
					(font
						(size 1.27 1.27)
						(thickness 0.15)
					)
					(justify left bottom)
					(hide yes)
				)
			)
			(property "ki_keywords" "DIODE, SEMICONDUCTOR, TVS, ESD"
				(at 0 0 0)
				(effects
					(font
						(size 1.27 1.27)
					)
					(hide yes)
				)
			)
			(symbol "ESDA25P35-1U1M_0_1"
				(polyline
					(pts
						(xy 1.905 0) (xy 0.635 0)
					)
					(stroke
						(width 0)
						(type default)
					)
					(fill
						(type none)
					)
				)
				(polyline
					(pts
						(xy 4.445 0) (xy 3.175 0)
					)
					(stroke
						(width 0)
						(type default)
					)
					(fill
						(type none)
					)
				)
			)
			(symbol "ESDA25P35-1U1M_1_1"
				(polyline
					(pts
						(xy 1.778 1.016) (xy 1.397 1.016)
					)
					(stroke
						(width 0.254)
						(type default)
					)
					(fill
						(type none)
					)
				)
				(polyline
					(pts
						(xy 1.778 1.016) (xy 1.778 -1.016)
					)
					(stroke
						(width 0.254)
						(type default)
					)
					(fill
						(type none)
					)
				)
				(polyline
					(pts
						(xy 2.159 -1.016) (xy 1.778 -1.016)
					)
					(stroke
						(width 0.254)
						(type default)
					)
					(fill
						(type none)
					)
				)
				(polyline
					(pts
						(xy 3.302 1.016) (xy 3.302 -1.016) (xy 1.778 0) (xy 3.302 1.016)
					)
					(stroke
						(width 0.254)
						(type default)
					)
					(fill
						(type outline)
					)
				)
				(pin passive line
					(at 0 0 0)
					(length 0.635)
					(name "C"
						(effects
							(font
								(size 1.27 1.27)
							)
						)
					)
					(number "1"
						(effects
							(font
								(size 1.27 1.27)
							)
						)
					)
				)
				(pin passive line
					(at 5.08 0 180)
					(length 0.635)
					(name "A"
						(effects
							(font
								(size 1.27 1.27)
							)
						)
					)
					(number "2"
						(effects
							(font
								(size 1.27 1.27)
							)
						)
					)
				)
			)
		)
	(symbol "antmicroTVSDiodes:PESD5Z5_0F"
			(pin_numbers
				(hide yes)
			)
			(pin_names
				(hide yes)
			)
			(exclude_from_sim no)
			(in_bom yes)
			(on_board yes)
			(property "Reference" "D"
				(at 15.24 0 0)
				(effects
					(font
						(size 1.27 1.27)
						(thickness 0.15)
					)
					(justify left bottom)
				)
			)
			(property "Value" "PESD5Z5_0F"
				(at 15.24 -12.7 0)
				(effects
					(font
						(size 1.27 1.27)
						(thickness 0.15)
					)
					(justify left bottom)
					(hide yes)
				)
			)
			(property "Footprint" "antmicro-footprints:SOD-523"
				(at 15.24 -5.08 0)
				(effects
					(font
						(size 1.27 1.27)
						(thickness 0.15)
					)
					(justify left bottom)
					(hide yes)
				)
			)
			(property "Datasheet" "https://assets.nexperia.com/documents/data-sheet/PESD5Z5_0.pdf"
				(at 15.24 -7.62 0)
				(effects
					(font
						(size 1.27 1.27)
						(thickness 0.15)
					)
					(justify left bottom)
					(hide yes)
				)
			)
			(property "Description" "Unidirectional TVS, 30 kV,  SOD-523, 5 V, 89 pF"
				(at 15.24 -20.32 0)
				(effects
					(font
						(size 1.27 1.27)
					)
					(justify left bottom)
					(hide yes)
				)
			)
			(property "Manufacturer" "Nexperia"
				(at 15.24 -10.16 0)
				(effects
					(font
						(size 1.27 1.27)
						(thickness 0.15)
					)
					(justify left bottom)
					(hide yes)
				)
			)
			(property "MPN" "PESD5Z5.0F"
				(at 15.24 -2.54 0)
				(effects
					(font
						(size 1.27 1.27)
						(thickness 0.15)
					)
					(justify left bottom)
				)
			)
			(property "Author" "Antmicro"
				(at 15.24 -15.24 0)
				(effects
					(font
						(size 1.27 1.27)
						(thickness 0.15)
					)
					(justify left bottom)
					(hide yes)
				)
			)
			(property "License" "Apache-2.0"
				(at 15.24 -17.78 0)
				(effects
					(font
						(size 1.27 1.27)
						(thickness 0.15)
					)
					(justify left bottom)
					(hide yes)
				)
			)
			(property "ki_keywords" "DIODE, SEMICONDUCTOR, TVS, ESD"
				(at 0 0 0)
				(effects
					(font
						(size 1.27 1.27)
					)
					(hide yes)
				)
			)
			(symbol "PESD5Z5_0F_0_1"
				(polyline
					(pts
						(xy 1.905 0) (xy 0.635 0)
					)
					(stroke
						(width 0)
						(type default)
					)
					(fill
						(type none)
					)
				)
				(polyline
					(pts
						(xy 4.445 0) (xy 3.175 0)
					)
					(stroke
						(width 0)
						(type default)
					)
					(fill
						(type none)
					)
				)
			)
			(symbol "PESD5Z5_0F_1_1"
				(polyline
					(pts
						(xy 1.778 1.016) (xy 1.397 1.016)
					)
					(stroke
						(width 0.254)
						(type default)
					)
					(fill
						(type none)
					)
				)
				(polyline
					(pts
						(xy 1.778 1.016) (xy 1.778 -1.016)
					)
					(stroke
						(width 0.254)
						(type default)
					)
					(fill
						(type none)
					)
				)
				(polyline
					(pts
						(xy 2.159 -1.016) (xy 1.778 -1.016)
					)
					(stroke
						(width 0.254)
						(type default)
					)
					(fill
						(type none)
					)
				)
				(polyline
					(pts
						(xy 3.302 1.016) (xy 3.302 -1.016) (xy 1.778 0) (xy 3.302 1.016)
					)
					(stroke
						(width 0.254)
						(type default)
					)
					(fill
						(type outline)
					)
				)
				(pin passive line
					(at 0 0 0)
					(length 0.635)
					(name "C"
						(effects
							(font
								(size 1.27 1.27)
							)
						)
					)
					(number "1"
						(effects
							(font
								(size 1.27 1.27)
							)
						)
					)
				)
				(pin passive line
					(at 5.08 0 180)
					(length 0.635)
					(name "A"
						(effects
							(font
								(size 1.27 1.27)
							)
						)
					)
					(number "2"
						(effects
							(font
								(size 1.27 1.27)
							)
						)
					)
				)
			)
		)
	(symbol "antmicroTVSDiodes:PTVS26VS1UR,115"
			(pin_numbers
				(hide yes)
			)
			(pin_names
				(hide yes)
			)
			(exclude_from_sim no)
			(in_bom yes)
			(on_board yes)
			(property "Reference" "D"
				(at 20.32 -2.54 0)
				(effects
					(font
						(size 1.27 1.27)
						(thickness 0.15)
					)
					(justify left bottom)
				)
			)
			(property "Value" "PTVS26VS1UR,115"
				(at 20.32 -5.08 0)
				(effects
					(font
						(size 1.27 1.27)
						(thickness 0.15)
					)
					(justify left bottom)
					(hide yes)
				)
			)
			(property "Footprint" "antmicro-footprints:D_SOD-123"
				(at 20.32 -7.62 0)
				(effects
					(font
						(size 1.27 1.27)
						(thickness 0.15)
					)
					(justify left bottom)
					(hide yes)
				)
			)
			(property "Datasheet" "https://www.mouser.com/datasheet/2/916/PTVSXS1UR_SER-1545507.pdf"
				(at 20.32 -10.16 0)
				(effects
					(font
						(size 1.27 1.27)
						(thickness 0.15)
					)
					(justify left bottom)
					(hide yes)
				)
			)
			(property "Description" "Unidirectional TVS, 8 kV,  SOD-123F, 26 V, 400 W"
				(at 20.32 -22.86 0)
				(effects
					(font
						(size 1.27 1.27)
					)
					(justify left bottom)
					(hide yes)
				)
			)
			(property "Author" "Antmicro"
				(at 20.32 -17.78 0)
				(effects
					(font
						(size 1.27 1.27)
						(thickness 0.15)
					)
					(justify left bottom)
					(hide yes)
				)
			)
			(property "License" "Apache-2.0"
				(at 20.32 -20.32 0)
				(effects
					(font
						(size 1.27 1.27)
						(thickness 0.15)
					)
					(justify left bottom)
					(hide yes)
				)
			)
			(property "Manufacturer" "Nexperia"
				(at 20.32 -15.24 0)
				(effects
					(font
						(size 1.27 1.27)
					)
					(justify left bottom)
					(hide yes)
				)
			)
			(property "MPN" "PTVS26VS1UR,115"
				(at 20.32 -12.7 0)
				(effects
					(font
						(size 1.27 1.27)
					)
					(justify left bottom)
				)
			)
			(property "ki_keywords" "DIODE, SEMICONDUCTOR, TVS, ESD"
				(at 0 0 0)
				(effects
					(font
						(size 1.27 1.27)
					)
					(hide yes)
				)
			)
			(symbol "PTVS26VS1UR,115_0_1"
				(polyline
					(pts
						(xy 1.905 0) (xy 0.635 0)
					)
					(stroke
						(width 0)
						(type default)
					)
					(fill
						(type none)
					)
				)
				(polyline
					(pts
						(xy 4.445 0) (xy 3.175 0)
					)
					(stroke
						(width 0)
						(type default)
					)
					(fill
						(type none)
					)
				)
			)
			(symbol "PTVS26VS1UR,115_1_1"
				(polyline
					(pts
						(xy 1.778 1.016) (xy 1.397 1.016)
					)
					(stroke
						(width 0.254)
						(type default)
					)
					(fill
						(type none)
					)
				)
				(polyline
					(pts
						(xy 1.778 1.016) (xy 1.778 -1.016)
					)
					(stroke
						(width 0.254)
						(type default)
					)
					(fill
						(type none)
					)
				)
				(polyline
					(pts
						(xy 2.159 -1.016) (xy 1.778 -1.016)
					)
					(stroke
						(width 0.254)
						(type default)
					)
					(fill
						(type none)
					)
				)
				(polyline
					(pts
						(xy 3.302 1.016) (xy 3.302 -1.016) (xy 1.778 0) (xy 3.302 1.016)
					)
					(stroke
						(width 0.254)
						(type default)
					)
					(fill
						(type outline)
					)
				)
				(pin passive line
					(at 0 0 0)
					(length 0.635)
					(name "C"
						(effects
							(font
								(size 1.27 1.27)
							)
						)
					)
					(number "1"
						(effects
							(font
								(size 1.27 1.27)
							)
						)
					)
				)
				(pin passive line
					(at 5.08 0 180)
					(length 0.635)
					(name "A"
						(effects
							(font
								(size 1.27 1.27)
							)
						)
					)
					(number "2"
						(effects
							(font
								(size 1.27 1.27)
							)
						)
					)
				)
			)
		)
	(symbol "antmicroTVSDiodes:TPD1E0B04_XDFN-2"
			(pin_numbers
				(hide yes)
			)
			(pin_names
				(hide yes)
			)
			(exclude_from_sim no)
			(in_bom yes)
			(on_board yes)
			(property "Reference" "D"
				(at 15.24 0 0)
				(effects
					(font
						(size 1.27 1.27)
						(thickness 0.15)
					)
					(justify left bottom)
				)
			)
			(property "Value" "TPD1E0B04_XDFN-2"
				(at 15.24 -10.16 0)
				(effects
					(font
						(size 1.27 1.27)
						(thickness 0.15)
					)
					(justify left bottom)
					(hide yes)
				)
			)
			(property "Footprint" "antmicro-footprints:XDFN-2_1x0.60mm"
				(at 15.24 -5.08 0)
				(effects
					(font
						(size 1.27 1.27)
						(thickness 0.15)
					)
					(justify left bottom)
					(hide yes)
				)
			)
			(property "Datasheet" "https://www.ti.com/general/docs/suppproductinfo.tsp?distId=26&gotoUrl=https://www.ti.com/lit/gpn/tpd1e0b04"
				(at 15.24 -7.62 0)
				(effects
					(font
						(size 1.27 1.27)
						(thickness 0.15)
					)
					(justify left bottom)
					(hide yes)
				)
			)
			(property "Description" "Bidirectional TVS, 8 kV,  XDFN-2, 3.6 V, 0.18 pF"
				(at 15.24 -20.32 0)
				(effects
					(font
						(size 1.27 1.27)
					)
					(justify left bottom)
					(hide yes)
				)
			)
			(property "MPN" "TPD1E0B04DPYR"
				(at 15.24 -2.54 0)
				(effects
					(font
						(size 1.27 1.27)
						(thickness 0.15)
					)
					(justify left bottom)
				)
			)
			(property "Manufacturer" "Texas Instruments"
				(at 15.24 -12.7 0)
				(effects
					(font
						(size 1.27 1.27)
						(thickness 0.15)
					)
					(justify left bottom)
					(hide yes)
				)
			)
			(property "Author" "Antmicro"
				(at 15.24 -15.24 0)
				(effects
					(font
						(size 1.27 1.27)
						(thickness 0.15)
					)
					(justify left bottom)
					(hide yes)
				)
			)
			(property "License" "Apache-2.0"
				(at 15.24 -17.78 0)
				(effects
					(font
						(size 1.27 1.27)
						(thickness 0.15)
					)
					(justify left bottom)
					(hide yes)
				)
			)
			(property "ki_keywords" "DIODE, SEMICONDUCTOR, TVS, ESD"
				(at 0 0 0)
				(effects
					(font
						(size 1.27 1.27)
					)
					(hide yes)
				)
			)
			(symbol "TPD1E0B04_XDFN-2_0_0"
				(text ""
					(at 7.62 -1.27 0)
					(effects
						(font
							(size 1.27 1.27)
						)
					)
				)
			)
			(symbol "TPD1E0B04_XDFN-2_0_1"
				(polyline
					(pts
						(xy 0.635 0) (xy 4.445 0)
					)
					(stroke
						(width 0)
						(type default)
					)
					(fill
						(type none)
					)
				)
			)
			(symbol "TPD1E0B04_XDFN-2_1_1"
				(polyline
					(pts
						(xy 1.016 -1.016) (xy 1.016 1.016) (xy 2.54 0) (xy 1.016 -1.016)
					)
					(stroke
						(width 0.254)
						(type default)
					)
					(fill
						(type outline)
					)
				)
				(polyline
					(pts
						(xy 2.54 1.016) (xy 2.159 1.016)
					)
					(stroke
						(width 0.254)
						(type default)
					)
					(fill
						(type none)
					)
				)
				(polyline
					(pts
						(xy 2.54 1.016) (xy 2.54 -1.016)
					)
					(stroke
						(width 0.254)
						(type default)
					)
					(fill
						(type none)
					)
				)
				(polyline
					(pts
						(xy 2.921 -1.016) (xy 2.54 -1.016)
					)
					(stroke
						(width 0.254)
						(type default)
					)
					(fill
						(type none)
					)
				)
				(polyline
					(pts
						(xy 4.064 1.016) (xy 4.064 -1.016) (xy 2.54 0) (xy 4.064 1.016)
					)
					(stroke
						(width 0.254)
						(type default)
					)
					(fill
						(type outline)
					)
				)
				(pin passive line
					(at 0 0 0)
					(length 0.635)
					(name "C"
						(effects
							(font
								(size 1.27 1.27)
							)
						)
					)
					(number "1"
						(effects
							(font
								(size 1.27 1.27)
							)
						)
					)
				)
				(pin passive line
					(at 5.08 0 180)
					(length 0.635)
					(name "A"
						(effects
							(font
								(size 1.27 1.27)
							)
						)
					)
					(number "2"
						(effects
							(font
								(size 1.27 1.27)
							)
						)
					)
				)
			)
		)
	(symbol "antmicroTVSDiodes:TPD4E05U06QDQARQ1"
			(exclude_from_sim no)
			(in_bom yes)
			(on_board yes)
			(property "Reference" "U"
				(at 24.13 0 0)
				(effects
					(font
						(size 1.27 1.27)
						(thickness 0.15)
					)
					(justify left bottom)
				)
			)
			(property "Value" "TPD4E05U06QDQARQ1"
				(at 24.13 -10.16 0)
				(effects
					(font
						(size 1.27 1.27)
						(thickness 0.15)
					)
					(justify left bottom)
					(hide yes)
				)
			)
			(property "Footprint" "antmicro-footprints:USON-10_2.5x1mm_P0.5mm"
				(at 24.13 -5.08 0)
				(effects
					(font
						(size 1.27 1.27)
						(thickness 0.15)
					)
					(justify left bottom)
					(hide yes)
				)
			)
			(property "Datasheet" "https://www.ti.com/lit/ds/symlink/tpd4e05u06-q1.pdf?HQS=dis-mous-null-mousermode-dsf-pf-null-wwe&ts=1663591265741&ref_url=https%253A%252F%252Fwww.mouser.com%252F"
				(at 24.13 -7.62 0)
				(effects
					(font
						(size 1.27 1.27)
						(thickness 0.15)
					)
					(justify left bottom)
					(hide yes)
				)
			)
			(property "Description" "TVS diode array, 12 kV, USON-10, 5.5 V, 0.5 pF"
				(at 24.13 -20.32 0)
				(effects
					(font
						(size 1.27 1.27)
					)
					(justify left bottom)
					(hide yes)
				)
			)
			(property "MPN" "TPD4E05U06QDQARQ1"
				(at 24.13 -2.54 0)
				(effects
					(font
						(size 1.27 1.27)
						(thickness 0.15)
					)
					(justify left bottom)
				)
			)
			(property "Manufacturer" "Texas Instruments"
				(at 24.13 -12.7 0)
				(effects
					(font
						(size 1.27 1.27)
						(thickness 0.15)
					)
					(justify left bottom)
					(hide yes)
				)
			)
			(property "Author" "Antmicro"
				(at 24.13 -15.24 0)
				(effects
					(font
						(size 1.27 1.27)
						(thickness 0.15)
					)
					(justify left bottom)
					(hide yes)
				)
			)
			(property "License" "Apache-2.0"
				(at 24.13 -17.78 0)
				(effects
					(font
						(size 1.27 1.27)
						(thickness 0.15)
					)
					(justify left bottom)
					(hide yes)
				)
			)
			(property "ki_keywords" "SMT, DIODE, SEMICONDUCTOR, TVS, ESD"
				(at 0 0 0)
				(effects
					(font
						(size 1.27 1.27)
					)
					(hide yes)
				)
			)
			(symbol "TPD4E05U06QDQARQ1_1_1"
				(rectangle
					(start 2.54 2.54)
					(end 8.89 -11.43)
					(stroke
						(width 0.254)
						(type default)
					)
					(fill
						(type background)
					)
				)
				(polyline
					(pts
						(xy 2.54 0) (xy 7.62 0)
					)
					(stroke
						(width 0.254)
						(type default)
					)
					(fill
						(type background)
					)
				)
				(polyline
					(pts
						(xy 2.54 -2.54) (xy 7.62 -2.54)
					)
					(stroke
						(width 0.254)
						(type default)
					)
					(fill
						(type background)
					)
				)
				(polyline
					(pts
						(xy 2.54 -5.08) (xy 7.62 -5.08)
					)
					(stroke
						(width 0.254)
						(type default)
					)
					(fill
						(type background)
					)
				)
				(polyline
					(pts
						(xy 2.54 -7.62) (xy 7.62 -7.62)
					)
					(stroke
						(width 0.254)
						(type default)
					)
					(fill
						(type background)
					)
				)
				(polyline
					(pts
						(xy 4.826 -0.635) (xy 5.08 -0.381) (xy 5.08 0.381) (xy 5.334 0.635)
					)
					(stroke
						(width 0.254)
						(type default)
					)
					(fill
						(type background)
					)
				)
				(polyline
					(pts
						(xy 4.826 -3.175) (xy 5.08 -2.921) (xy 5.08 -2.159) (xy 5.334 -1.905)
					)
					(stroke
						(width 0.254)
						(type default)
					)
					(fill
						(type background)
					)
				)
				(polyline
					(pts
						(xy 4.826 -5.715) (xy 5.08 -5.461) (xy 5.08 -4.699) (xy 5.334 -4.445)
					)
					(stroke
						(width 0.254)
						(type default)
					)
					(fill
						(type background)
					)
				)
				(polyline
					(pts
						(xy 4.826 -8.255) (xy 5.08 -8.001) (xy 5.08 -7.239) (xy 5.334 -6.985)
					)
					(stroke
						(width 0.254)
						(type default)
					)
					(fill
						(type background)
					)
				)
				(polyline
					(pts
						(xy 5.08 0) (xy 3.81 -0.635) (xy 3.81 0.635) (xy 5.08 0)
					)
					(stroke
						(width 0.254)
						(type default)
					)
					(fill
						(type background)
					)
				)
				(polyline
					(pts
						(xy 5.08 0) (xy 6.35 -0.635) (xy 6.35 0.635) (xy 5.08 0)
					)
					(stroke
						(width 0.254)
						(type default)
					)
					(fill
						(type background)
					)
				)
				(polyline
					(pts
						(xy 5.08 -2.54) (xy 3.81 -3.175) (xy 3.81 -1.905) (xy 5.08 -2.54)
					)
					(stroke
						(width 0.254)
						(type default)
					)
					(fill
						(type background)
					)
				)
				(polyline
					(pts
						(xy 5.08 -2.54) (xy 6.35 -3.175) (xy 6.35 -1.905) (xy 5.08 -2.54)
					)
					(stroke
						(width 0.254)
						(type default)
					)
					(fill
						(type background)
					)
				)
				(polyline
					(pts
						(xy 5.08 -5.08) (xy 3.81 -5.715) (xy 3.81 -4.445) (xy 5.08 -5.08)
					)
					(stroke
						(width 0.254)
						(type default)
					)
					(fill
						(type background)
					)
				)
				(polyline
					(pts
						(xy 5.08 -5.08) (xy 6.35 -4.445) (xy 6.35 -5.715) (xy 5.08 -5.08)
					)
					(stroke
						(width 0.254)
						(type default)
					)
					(fill
						(type background)
					)
				)
				(polyline
					(pts
						(xy 5.08 -7.62) (xy 3.81 -8.255) (xy 3.81 -6.985) (xy 5.08 -7.62)
					)
					(stroke
						(width 0.254)
						(type default)
					)
					(fill
						(type background)
					)
				)
				(polyline
					(pts
						(xy 6.35 -6.985) (xy 6.35 -8.255) (xy 5.08 -7.62) (xy 6.35 -6.985)
					)
					(stroke
						(width 0.254)
						(type default)
					)
					(fill
						(type background)
					)
				)
				(polyline
					(pts
						(xy 7.62 0) (xy 7.62 -10.16)
					)
					(stroke
						(width 0.254)
						(type default)
					)
					(fill
						(type background)
					)
				)
				(circle
					(center 7.62 -2.54)
					(radius 0.254)
					(stroke
						(width 0.254)
						(type default)
					)
					(fill
						(type background)
					)
				)
				(circle
					(center 7.62 -5.08)
					(radius 0.254)
					(stroke
						(width 0.254)
						(type default)
					)
					(fill
						(type background)
					)
				)
				(circle
					(center 7.62 -5.08)
					(radius 0.254)
					(stroke
						(width 0.254)
						(type default)
					)
					(fill
						(type background)
					)
				)
				(circle
					(center 7.62 -7.62)
					(radius 0.254)
					(stroke
						(width 0.254)
						(type default)
					)
					(fill
						(type background)
					)
				)
				(polyline
					(pts
						(xy 7.62 -10.16) (xy 2.54 -10.16)
					)
					(stroke
						(width 0.254)
						(type default)
					)
					(fill
						(type background)
					)
				)
				(pin passive line
					(at 0 0 0)
					(length 2.54)
					(name "~"
						(effects
							(font
								(size 1.27 1.27)
							)
						)
					)
					(number "1"
						(effects
							(font
								(size 1.27 1.27)
							)
						)
					)
				)
				(pin passive line
					(at 0 0 0)
					(length 2.54)
					(hide yes)
					(name "~"
						(effects
							(font
								(size 1.27 1.27)
							)
						)
					)
					(number "10"
						(effects
							(font
								(size 1.27 1.27)
							)
						)
					)
				)
				(pin passive line
					(at 0 -2.54 0)
					(length 2.54)
					(name "~"
						(effects
							(font
								(size 1.27 1.27)
							)
						)
					)
					(number "2"
						(effects
							(font
								(size 1.27 1.27)
							)
						)
					)
				)
				(pin passive line
					(at 0 -2.54 0)
					(length 2.54)
					(hide yes)
					(name "~"
						(effects
							(font
								(size 1.27 1.27)
							)
						)
					)
					(number "9"
						(effects
							(font
								(size 1.27 1.27)
							)
						)
					)
				)
				(pin passive line
					(at 0 -5.08 0)
					(length 2.54)
					(name "~"
						(effects
							(font
								(size 1.27 1.27)
							)
						)
					)
					(number "4"
						(effects
							(font
								(size 1.27 1.27)
							)
						)
					)
				)
				(pin passive line
					(at 0 -5.08 0)
					(length 2.54)
					(hide yes)
					(name "~"
						(effects
							(font
								(size 1.27 1.27)
							)
						)
					)
					(number "7"
						(effects
							(font
								(size 1.27 1.27)
							)
						)
					)
				)
				(pin passive line
					(at 0 -7.62 0)
					(length 2.54)
					(name "~"
						(effects
							(font
								(size 1.27 1.27)
							)
						)
					)
					(number "5"
						(effects
							(font
								(size 1.27 1.27)
							)
						)
					)
				)
				(pin passive line
					(at 0 -7.62 0)
					(length 2.54)
					(hide yes)
					(name "~"
						(effects
							(font
								(size 1.27 1.27)
							)
						)
					)
					(number "6"
						(effects
							(font
								(size 1.27 1.27)
							)
						)
					)
				)
				(pin power_in line
					(at 0 -10.16 0)
					(length 2.54)
					(name "~"
						(effects
							(font
								(size 1.27 1.27)
							)
						)
					)
					(number "3"
						(effects
							(font
								(size 1.27 1.27)
							)
						)
					)
				)
				(pin passive line
					(at 0 -10.16 0)
					(length 2.54)
					(hide yes)
					(name "~"
						(effects
							(font
								(size 1.27 1.27)
							)
						)
					)
					(number "8"
						(effects
							(font
								(size 1.27 1.27)
							)
						)
					)
				)
			)
		)
	(symbol "antmicroTestPoints:TP_0.75mm_SMD"
			(pin_names
				(hide yes)
			)
			(exclude_from_sim no)
			(in_bom no)
			(on_board yes)
			(property "Reference" "TP"
				(at 10.16 -1.27 0)
				(effects
					(font
						(size 1.27 1.27)
						(thickness 0.15)
					)
					(justify left bottom)
				)
			)
			(property "Value" "TP_0.75mm_SMD"
				(at 10.16 -3.81 0)
				(effects
					(font
						(size 1.27 1.27)
						(thickness 0.15)
					)
					(justify left bottom)
					(hide yes)
				)
			)
			(property "Footprint" "antmicro-footprints:TP_SMD_0.75mm"
				(at 10.16 -6.35 0)
				(effects
					(font
						(size 1.27 1.27)
						(thickness 0.15)
					)
					(justify left bottom)
					(hide yes)
				)
			)
			(property "Datasheet" ""
				(at 17.78 -12.7 0)
				(effects
					(font
						(size 1.27 1.27)
						(thickness 0.15)
					)
					(justify left bottom)
					(hide yes)
				)
			)
			(property "Description" "SMT test point"
				(at 10.795 -13.97 0)
				(effects
					(font
						(size 1.27 1.27)
					)
					(justify left bottom)
					(hide yes)
				)
			)
			(property "MPN" ""
				(at 10.795 -11.43 0)
				(effects
					(font
						(size 1.27 1.27)
						(thickness 0.15)
					)
					(justify left bottom)
					(hide yes)
				)
			)
			(property "Manufacturer" ""
				(at 10.795 -6.35 0)
				(effects
					(font
						(size 1.27 1.27)
						(thickness 0.15)
					)
					(justify left bottom)
					(hide yes)
				)
			)
			(property "Author" "Antmicro"
				(at 10.16 -8.89 0)
				(effects
					(font
						(size 1.27 1.27)
						(thickness 0.15)
					)
					(justify left bottom)
					(hide yes)
				)
			)
			(property "License" "Apache-2.0"
				(at 10.16 -11.43 0)
				(effects
					(font
						(size 1.27 1.27)
						(thickness 0.15)
					)
					(justify left bottom)
					(hide yes)
				)
			)
			(property "ki_keywords" "TESTPOINT"
				(at 0 0 0)
				(effects
					(font
						(size 1.27 1.27)
					)
					(hide yes)
				)
			)
			(symbol "TP_0.75mm_SMD_1_1"
				(circle
					(center 3.175 0)
					(radius 0.635)
					(stroke
						(width 0.254)
						(type default)
					)
					(fill
						(type none)
					)
				)
				(pin passive line
					(at 0 0 0)
					(length 2.54)
					(name "1"
						(effects
							(font
								(size 1.27 1.27)
							)
						)
					)
					(number "1"
						(effects
							(font
								(size 1.27 1.27)
							)
						)
					)
				)
			)
		)
	(symbol "antmicroTestPoints:Tag-Connect_TC2050-IDC-NL_2x5_P1.27mm"
			(exclude_from_sim no)
			(in_bom no)
			(on_board yes)
			(property "Reference" "J"
				(at 39.37 -1.27 0)
				(effects
					(font
						(size 1.27 1.27)
						(thickness 0.15)
					)
					(justify left bottom)
				)
			)
			(property "Value" "Tag-Connect_TC2050-IDC-NL_2x5_P1.27mm"
				(at 39.37 -3.81 0)
				(effects
					(font
						(size 1.27 1.27)
						(thickness 0.15)
					)
					(justify left bottom)
					(hide yes)
				)
			)
			(property "Footprint" "antmicro-footprints:Tag-Connect_TC2050-IDC-NL_2x5_P1.27mm"
				(at 39.37 -6.35 0)
				(effects
					(font
						(size 1.27 1.27)
						(thickness 0.15)
					)
					(justify left bottom)
					(hide yes)
				)
			)
			(property "Datasheet" "https://www.tag-connect.com/wp-content/uploads/bsk-pdf-manager/TC2050-IDC-NL_Datasheet_8.pdf"
				(at 39.37 -8.89 0)
				(effects
					(font
						(size 1.27 1.27)
						(thickness 0.15)
					)
					(justify left bottom)
					(hide yes)
				)
			)
			(property "Description" "Tag Connect 2x5 1.27mm terminal"
				(at 39.37 -21.59 0)
				(effects
					(font
						(size 1.27 1.27)
					)
					(justify left bottom)
					(hide yes)
				)
			)
			(property "MPN" "TC2050-IDC-NL"
				(at 39.37 -11.43 0)
				(effects
					(font
						(size 1.27 1.27)
						(thickness 0.15)
					)
					(justify left bottom)
				)
			)
			(property "Manufacturer" "Tag Connect"
				(at 39.37 -13.97 0)
				(effects
					(font
						(size 1.27 1.27)
						(thickness 0.15)
					)
					(justify left bottom)
					(hide yes)
				)
			)
			(property "Author" "Antmicro"
				(at 39.37 -16.51 0)
				(effects
					(font
						(size 1.27 1.27)
						(thickness 0.15)
					)
					(justify left bottom)
					(hide yes)
				)
			)
			(property "License" "Apache-2.0"
				(at 39.37 -19.05 0)
				(effects
					(font
						(size 1.27 1.27)
						(thickness 0.15)
					)
					(justify left bottom)
					(hide yes)
				)
			)
			(property "ki_keywords" "POGO-PIN, CONNECTOR"
				(at 0 0 0)
				(effects
					(font
						(size 1.27 1.27)
					)
					(hide yes)
				)
			)
			(symbol "Tag-Connect_TC2050-IDC-NL_2x5_P1.27mm_1_1"
				(rectangle
					(start 2.54 2.54)
					(end 29.21 -12.7)
					(stroke
						(width 0)
						(type default)
					)
					(fill
						(type background)
					)
				)
				(circle
					(center 15.113 -7.5184)
					(radius 0.4572)
					(stroke
						(width 0)
						(type default)
					)
					(fill
						(type none)
					)
				)
				(polyline
					(pts
						(xy 15.24 -8.636) (xy 17.145 -8.636) (xy 17.78 -8.001) (xy 17.78 -2.921) (xy 16.51 -1.016) (xy 15.24 -1.016)
						(xy 13.97 -2.921) (xy 13.97 -8.001) (xy 14.605 -8.636) (xy 15.24 -8.636)
					)
					(stroke
						(width 0)
						(type default)
					)
					(fill
						(type none)
					)
				)
				(circle
					(center 15.367 -3.4544)
					(radius 0.2032)
					(stroke
						(width 0)
						(type default)
					)
					(fill
						(type outline)
					)
				)
				(circle
					(center 15.367 -4.1656)
					(radius 0.2032)
					(stroke
						(width 0)
						(type default)
					)
					(fill
						(type outline)
					)
				)
				(circle
					(center 15.367 -4.9276)
					(radius 0.2032)
					(stroke
						(width 0)
						(type default)
					)
					(fill
						(type outline)
					)
				)
				(circle
					(center 15.367 -5.6388)
					(radius 0.2032)
					(stroke
						(width 0)
						(type default)
					)
					(fill
						(type outline)
					)
				)
				(circle
					(center 15.367 -6.4008)
					(radius 0.2032)
					(stroke
						(width 0)
						(type default)
					)
					(fill
						(type outline)
					)
				)
				(circle
					(center 15.875 -2.1336)
					(radius 0.4572)
					(stroke
						(width 0)
						(type default)
					)
					(fill
						(type none)
					)
				)
				(circle
					(center 16.383 -3.4544)
					(radius 0.2032)
					(stroke
						(width 0)
						(type default)
					)
					(fill
						(type outline)
					)
				)
				(circle
					(center 16.383 -4.1656)
					(radius 0.2032)
					(stroke
						(width 0)
						(type default)
					)
					(fill
						(type outline)
					)
				)
				(circle
					(center 16.383 -4.9276)
					(radius 0.2032)
					(stroke
						(width 0)
						(type default)
					)
					(fill
						(type outline)
					)
				)
				(circle
					(center 16.383 -5.6388)
					(radius 0.2032)
					(stroke
						(width 0)
						(type default)
					)
					(fill
						(type outline)
					)
				)
				(circle
					(center 16.383 -6.4008)
					(radius 0.2032)
					(stroke
						(width 0)
						(type default)
					)
					(fill
						(type outline)
					)
				)
				(circle
					(center 16.7386 -7.5184)
					(radius 0.4572)
					(stroke
						(width 0)
						(type default)
					)
					(fill
						(type none)
					)
				)
				(text "Tag-Connect"
					(at 15.875 1.651 0)
					(effects
						(font
							(size 0.7 0.7)
						)
					)
				)
				(text "ALT: 3.3V I2C/JTAG/SPI/SWD/FTDI"
					(at 16.002 -11.938 0)
					(effects
						(font
							(size 0.7 0.7)
						)
					)
				)
				(pin passive line
					(at 0 0 0)
					(length 2.54)
					(name "1"
						(effects
							(font
								(size 1.27 1.27)
							)
						)
					)
					(number "1"
						(effects
							(font
								(size 1.27 1.27)
							)
						)
					)
					(alternate "3V3" passive line)
				)
				(pin passive line
					(at 0 -2.54 0)
					(length 2.54)
					(name "2"
						(effects
							(font
								(size 1.27 1.27)
							)
						)
					)
					(number "2"
						(effects
							(font
								(size 1.27 1.27)
							)
						)
					)
					(alternate "ADBUS3" passive line)
					(alternate "I2C_NC" passive line)
					(alternate "JTAG_TMS" passive line)
					(alternate "SPI_CS" passive line)
					(alternate "SWD_NC" passive line)
				)
				(pin passive line
					(at 0 -5.08 0)
					(length 2.54)
					(name "3"
						(effects
							(font
								(size 1.27 1.27)
							)
						)
					)
					(number "3"
						(effects
							(font
								(size 1.27 1.27)
							)
						)
					)
					(alternate "GND" passive line)
				)
				(pin passive line
					(at 0 -7.62 0)
					(length 2.54)
					(name "4"
						(effects
							(font
								(size 1.27 1.27)
							)
						)
					)
					(number "4"
						(effects
							(font
								(size 1.27 1.27)
							)
						)
					)
					(alternate "ADBUS0" passive line)
					(alternate "I2C_SCL" passive line)
					(alternate "JTAG_TCK" passive line)
					(alternate "SPI_SCK" passive line)
					(alternate "SWD_CLK" passive line)
				)
				(pin passive line
					(at 0 -10.16 0)
					(length 2.54)
					(name "5"
						(effects
							(font
								(size 1.27 1.27)
							)
						)
					)
					(number "5"
						(effects
							(font
								(size 1.27 1.27)
							)
						)
					)
					(alternate "GND" passive line)
				)
				(pin passive line
					(at 31.75 0 180)
					(length 2.54)
					(name "10"
						(effects
							(font
								(size 1.27 1.27)
							)
						)
					)
					(number "10"
						(effects
							(font
								(size 1.27 1.27)
							)
						)
					)
					(alternate "ADBUS5" passive line)
					(alternate "I2C_NC" passive line)
					(alternate "JTAG_~{RESET}" passive line)
					(alternate "SPI_NC" passive line)
					(alternate "SWD_NC" passive line)
				)
				(pin passive line
					(at 31.75 -2.54 180)
					(length 2.54)
					(name "9"
						(effects
							(font
								(size 1.27 1.27)
							)
						)
					)
					(number "9"
						(effects
							(font
								(size 1.27 1.27)
							)
						)
					)
					(alternate "GND" passive line)
				)
				(pin passive line
					(at 31.75 -5.08 180)
					(length 2.54)
					(name "8"
						(effects
							(font
								(size 1.27 1.27)
							)
						)
					)
					(number "8"
						(effects
							(font
								(size 1.27 1.27)
							)
						)
					)
					(alternate "ADBUS1" passive line)
					(alternate "I2C_SDA" passive line)
					(alternate "JTAG_TDI" passive line)
					(alternate "SPI_MOSI" passive line)
					(alternate "SWD_IO" passive line)
				)
				(pin passive line
					(at 31.75 -7.62 180)
					(length 2.54)
					(name "7"
						(effects
							(font
								(size 1.27 1.27)
							)
						)
					)
					(number "7"
						(effects
							(font
								(size 1.27 1.27)
							)
						)
					)
					(alternate "NC" passive line)
				)
				(pin passive line
					(at 31.75 -10.16 180)
					(length 2.54)
					(name "6"
						(effects
							(font
								(size 1.27 1.27)
							)
						)
					)
					(number "6"
						(effects
							(font
								(size 1.27 1.27)
							)
						)
					)
					(alternate "ADBUS2" passive line)
					(alternate "I2C_SDA" passive line)
					(alternate "JTAG_TDO" passive line)
					(alternate "SPI_MISO" passive line)
					(alternate "SWD_IO" passive line)
				)
			)
		)
	(symbol "antmicroTransistorsFETsMOSFETsArrays:DMC2400UV-7"
			(pin_names
				(offset 0)
			)
			(exclude_from_sim no)
			(in_bom yes)
			(on_board yes)
			(property "Reference" "Q"
				(at 27.94 -2.54 0)
				(effects
					(font
						(size 1.27 1.27)
						(thickness 0.15)
					)
					(justify left bottom)
				)
			)
			(property "Value" "DMC2400UV-7"
				(at 27.94 -5.08 0)
				(effects
					(font
						(size 1.27 1.27)
						(thickness 0.15)
					)
					(justify left bottom)
					(hide yes)
				)
			)
			(property "Footprint" "antmicro-footprints:SOT-563"
				(at 27.94 -7.62 0)
				(effects
					(font
						(size 1.27 1.27)
						(thickness 0.15)
					)
					(justify left bottom)
					(hide yes)
				)
			)
			(property "Datasheet" "https://www.mouser.com/datasheet/2/115/DIOD_S_A0010038249_1-2543538.pdf"
				(at 27.94 -10.16 0)
				(effects
					(font
						(size 1.27 1.27)
						(thickness 0.15)
					)
					(justify left bottom)
					(hide yes)
				)
			)
			(property "Description" "Dual MOSFET, Complementary N and P Channel, 20 V, 20 V, 1.03 A, 1.03 A, 0.3 ohm"
				(at 27.94 -22.86 0)
				(effects
					(font
						(size 1.27 1.27)
					)
					(justify left bottom)
					(hide yes)
				)
			)
			(property "MPN" "DMC2400UV-7"
				(at 27.94 -12.7 0)
				(effects
					(font
						(size 1.27 1.27)
						(thickness 0.15)
					)
					(justify left bottom)
				)
			)
			(property "Manufacturer" "Diodes Incorporated"
				(at 27.94 -15.24 0)
				(effects
					(font
						(size 1.27 1.27)
						(thickness 0.15)
					)
					(justify left bottom)
					(hide yes)
				)
			)
			(property "Author" "Antmicro"
				(at 27.94 -17.78 0)
				(effects
					(font
						(size 1.27 1.27)
						(thickness 0.15)
					)
					(justify left bottom)
					(hide yes)
				)
			)
			(property "License" "Apache-2.0"
				(at 27.94 -20.32 0)
				(effects
					(font
						(size 1.27 1.27)
						(thickness 0.15)
					)
					(justify left bottom)
					(hide yes)
				)
			)
			(property "ki_keywords" "MOSFET, TRANSISTOR, ARRAY, SMT"
				(at 0 0 0)
				(effects
					(font
						(size 1.27 1.27)
					)
					(hide yes)
				)
			)
			(symbol "DMC2400UV-7_1_1"
				(polyline
					(pts
						(xy 2.54 1.27) (xy 10.16 1.27) (xy 10.16 -11.43) (xy 2.54 -11.43) (xy 2.54 1.27)
					)
					(stroke
						(width 0.254)
						(type default)
					)
					(fill
						(type background)
					)
				)
				(polyline
					(pts
						(xy 2.54 -5.08) (xy 5.08 -5.08) (xy 5.08 -3.81)
					)
					(stroke
						(width 0.254)
						(type default)
					)
					(fill
						(type background)
					)
				)
				(polyline
					(pts
						(xy 3.81 -6.35) (xy 8.89 -6.35)
					)
					(stroke
						(width 0.254)
						(type default)
					)
					(fill
						(type background)
					)
				)
				(polyline
					(pts
						(xy 4.445 -1.27) (xy 4.445 0)
					)
					(stroke
						(width 0.254)
						(type default)
					)
					(fill
						(type background)
					)
				)
				(polyline
					(pts
						(xy 4.445 -6.985) (xy 4.445 -10.16)
					)
					(stroke
						(width 0.254)
						(type default)
					)
					(fill
						(type background)
					)
				)
				(polyline
					(pts
						(xy 5.08 0) (xy 2.54 0)
					)
					(stroke
						(width 0.254)
						(type default)
					)
					(fill
						(type background)
					)
				)
				(polyline
					(pts
						(xy 5.08 0) (xy 10.16 0)
					)
					(stroke
						(width 0.254)
						(type default)
					)
					(fill
						(type background)
					)
				)
				(polyline
					(pts
						(xy 5.08 -3.175) (xy 3.81 -3.175)
					)
					(stroke
						(width 0.254)
						(type default)
					)
					(fill
						(type background)
					)
				)
				(polyline
					(pts
						(xy 5.08 -6.985) (xy 3.81 -6.985)
					)
					(stroke
						(width 0.254)
						(type default)
					)
					(fill
						(type background)
					)
				)
				(polyline
					(pts
						(xy 5.715 -0.635) (xy 6.985 0) (xy 5.715 0.635) (xy 5.715 -0.635)
					)
					(stroke
						(width 0.254)
						(type default)
					)
					(fill
						(type outline)
					)
				)
				(polyline
					(pts
						(xy 5.715 -1.905) (xy 6.35 -3.175) (xy 6.985 -1.905) (xy 5.715 -1.905)
					)
					(stroke
						(width 0.254)
						(type default)
					)
					(fill
						(type outline)
					)
				)
				(polyline
					(pts
						(xy 5.715 -3.175) (xy 6.985 -3.175)
					)
					(stroke
						(width 0.254)
						(type default)
					)
					(fill
						(type background)
					)
				)
				(polyline
					(pts
						(xy 5.715 -6.985) (xy 6.35 -8.255) (xy 6.985 -6.985) (xy 5.715 -6.985)
					)
					(stroke
						(width 0.254)
						(type default)
					)
					(fill
						(type outline)
					)
				)
				(polyline
					(pts
						(xy 5.715 -10.795) (xy 6.985 -10.16) (xy 5.715 -9.525) (xy 5.715 -10.795)
					)
					(stroke
						(width 0.254)
						(type default)
					)
					(fill
						(type outline)
					)
				)
				(polyline
					(pts
						(xy 6.35 -1.905) (xy 6.35 -1.27) (xy 4.445 -1.27) (xy 4.445 -3.175)
					)
					(stroke
						(width 0.254)
						(type default)
					)
					(fill
						(type background)
					)
				)
				(polyline
					(pts
						(xy 6.35 -8.255) (xy 6.35 -8.89) (xy 8.255 -8.89) (xy 8.255 -6.985)
					)
					(stroke
						(width 0.254)
						(type default)
					)
					(fill
						(type background)
					)
				)
				(polyline
					(pts
						(xy 6.985 -0.635) (xy 6.985 0.635)
					)
					(stroke
						(width 0.254)
						(type default)
					)
					(fill
						(type background)
					)
				)
				(polyline
					(pts
						(xy 6.985 -6.985) (xy 5.715 -6.985)
					)
					(stroke
						(width 0.254)
						(type default)
					)
					(fill
						(type background)
					)
				)
				(polyline
					(pts
						(xy 6.985 -9.525) (xy 6.985 -10.795)
					)
					(stroke
						(width 0.254)
						(type default)
					)
					(fill
						(type background)
					)
				)
				(polyline
					(pts
						(xy 7.62 -3.175) (xy 8.89 -3.175)
					)
					(stroke
						(width 0.254)
						(type default)
					)
					(fill
						(type background)
					)
				)
				(polyline
					(pts
						(xy 7.62 -6.985) (xy 8.89 -6.985)
					)
					(stroke
						(width 0.254)
						(type default)
					)
					(fill
						(type background)
					)
				)
				(polyline
					(pts
						(xy 7.62 -10.16) (xy 2.54 -10.16)
					)
					(stroke
						(width 0.254)
						(type default)
					)
					(fill
						(type background)
					)
				)
				(polyline
					(pts
						(xy 7.62 -10.16) (xy 10.16 -10.16)
					)
					(stroke
						(width 0.254)
						(type default)
					)
					(fill
						(type background)
					)
				)
				(polyline
					(pts
						(xy 8.255 -3.175) (xy 8.255 0)
					)
					(stroke
						(width 0.254)
						(type default)
					)
					(fill
						(type background)
					)
				)
				(polyline
					(pts
						(xy 8.255 -8.89) (xy 8.255 -10.16)
					)
					(stroke
						(width 0.254)
						(type default)
					)
					(fill
						(type background)
					)
				)
				(polyline
					(pts
						(xy 8.89 -3.81) (xy 3.81 -3.81)
					)
					(stroke
						(width 0.254)
						(type default)
					)
					(fill
						(type background)
					)
				)
				(polyline
					(pts
						(xy 10.16 -5.08) (xy 7.62 -5.08) (xy 7.62 -6.35)
					)
					(stroke
						(width 0.254)
						(type default)
					)
					(fill
						(type background)
					)
				)
				(pin passive line
					(at 0 0 0)
					(length 2.54)
					(name "S1"
						(effects
							(font
								(size 1.27 1.27)
							)
						)
					)
					(number "1"
						(effects
							(font
								(size 1.27 1.27)
							)
						)
					)
				)
				(pin input line
					(at 0 -5.08 0)
					(length 2.54)
					(name "G1"
						(effects
							(font
								(size 1.27 1.27)
							)
						)
					)
					(number "2"
						(effects
							(font
								(size 1.27 1.27)
							)
						)
					)
				)
				(pin passive line
					(at 0 -10.16 0)
					(length 2.54)
					(name "D2"
						(effects
							(font
								(size 1.27 1.27)
							)
						)
					)
					(number "3"
						(effects
							(font
								(size 1.27 1.27)
							)
						)
					)
				)
				(pin passive line
					(at 12.7 0 180)
					(length 2.54)
					(name "D1"
						(effects
							(font
								(size 1.27 1.27)
							)
						)
					)
					(number "6"
						(effects
							(font
								(size 1.27 1.27)
							)
						)
					)
				)
				(pin input line
					(at 12.7 -5.08 180)
					(length 2.54)
					(name "G2"
						(effects
							(font
								(size 1.27 1.27)
							)
						)
					)
					(number "5"
						(effects
							(font
								(size 1.27 1.27)
							)
						)
					)
				)
				(pin passive line
					(at 12.7 -10.16 180)
					(length 2.54)
					(name "S2"
						(effects
							(font
								(size 1.27 1.27)
							)
						)
					)
					(number "4"
						(effects
							(font
								(size 1.27 1.27)
							)
						)
					)
				)
			)
		)
	(symbol "antmicroTransistorsFETsMOSFETsSingle:DMG1012T-7"
			(pin_names
				(offset 0)
			)
			(exclude_from_sim no)
			(in_bom no)
			(on_board yes)
			(property "Reference" "Q"
				(at 10.16 3.81 0)
				(effects
					(font
						(size 1.27 1.27)
						(thickness 0.15)
					)
					(justify left bottom)
				)
			)
			(property "Value" "DMG1012T-7"
				(at 10.16 -3.81 0)
				(effects
					(font
						(size 1.27 1.27)
						(thickness 0.15)
					)
					(justify left bottom)
					(hide yes)
				)
			)
			(property "Footprint" "antmicro-footprints:SOT-523"
				(at 10.16 -6.35 0)
				(effects
					(font
						(size 1.27 1.27)
						(thickness 0.15)
					)
					(justify left bottom)
					(hide yes)
				)
			)
			(property "Datasheet" "https://www.diodes.com/assets/Datasheets/ds31783.pdf"
				(at 10.16 -8.89 0)
				(effects
					(font
						(size 1.27 1.27)
						(thickness 0.15)
					)
					(justify left bottom)
					(hide yes)
				)
			)
			(property "Description" "Power MOSFET, N Channel, 20 V, 630 mA, 0.3 ohm, SOT-523, Surface Mount"
				(at 10.16 -16.51 0)
				(effects
					(font
						(size 1.27 1.27)
					)
					(justify left bottom)
					(hide yes)
				)
			)
			(property "MPN" "DMG1012T-7"
				(at 10.16 1.27 0)
				(effects
					(font
						(size 1.27 1.27)
						(thickness 0.15)
					)
					(justify left bottom)
				)
			)
			(property "Manufacturer" "Diodes Incorporated"
				(at 10.16 -1.27 0)
				(effects
					(font
						(size 1.27 1.27)
						(thickness 0.15)
					)
					(justify left bottom)
					(hide yes)
				)
			)
			(property "Author" "Antmicro"
				(at 10.16 -11.43 0)
				(effects
					(font
						(size 1.27 1.27)
						(thickness 0.15)
					)
					(justify left bottom)
					(hide yes)
				)
			)
			(property "License" "Apache-2.0"
				(at 10.16 -13.97 0)
				(effects
					(font
						(size 1.27 1.27)
						(thickness 0.15)
					)
					(justify left bottom)
					(hide yes)
				)
			)
			(property "ki_keywords" "SMT, MOSFET, SEMICONDUCTOR"
				(at 0 0 0)
				(effects
					(font
						(size 1.27 1.27)
					)
					(hide yes)
				)
			)
			(symbol "DMG1012T-7_1_1"
				(polyline
					(pts
						(xy 1.27 0) (xy 3.302 0) (xy 3.302 3.937)
					)
					(stroke
						(width 0.254)
						(type default)
					)
					(fill
						(type none)
					)
				)
				(polyline
					(pts
						(xy 3.81 4.445) (xy 3.81 3.429)
					)
					(stroke
						(width 0.254)
						(type default)
					)
					(fill
						(type background)
					)
				)
				(polyline
					(pts
						(xy 3.81 2.54) (xy 3.81 3.048)
					)
					(stroke
						(width 0.254)
						(type default)
					)
					(fill
						(type background)
					)
				)
				(polyline
					(pts
						(xy 3.81 2.54) (xy 3.81 2.032)
					)
					(stroke
						(width 0.254)
						(type default)
					)
					(fill
						(type background)
					)
				)
				(polyline
					(pts
						(xy 3.81 2.54) (xy 4.572 3.048) (xy 4.572 2.032) (xy 3.81 2.54)
					)
					(stroke
						(width 0.254)
						(type default)
					)
					(fill
						(type outline)
					)
				)
				(polyline
					(pts
						(xy 3.81 1.143) (xy 3.81 1.651)
					)
					(stroke
						(width 0.254)
						(type default)
					)
					(fill
						(type background)
					)
				)
				(polyline
					(pts
						(xy 3.81 1.143) (xy 3.81 0.635)
					)
					(stroke
						(width 0.254)
						(type default)
					)
					(fill
						(type background)
					)
				)
				(circle
					(center 5.08 2.54)
					(radius 3.302)
					(stroke
						(width 0.254)
						(type default)
					)
					(fill
						(type background)
					)
				)
				(polyline
					(pts
						(xy 6.223 0.635) (xy 7.366 0.635) (xy 7.366 3.937) (xy 7.366 4.445) (xy 6.223 4.445)
					)
					(stroke
						(width 0.254)
						(type default)
					)
					(fill
						(type none)
					)
				)
				(polyline
					(pts
						(xy 6.35 6.35) (xy 6.35 3.937) (xy 3.81 3.937)
					)
					(stroke
						(width 0.254)
						(type default)
					)
					(fill
						(type none)
					)
				)
				(circle
					(center 6.35 4.445)
					(radius 0.127)
					(stroke
						(width 0.254)
						(type default)
					)
					(fill
						(type background)
					)
				)
				(polyline
					(pts
						(xy 6.35 1.143) (xy 3.81 1.143)
					)
					(stroke
						(width 0.254)
						(type default)
					)
					(fill
						(type background)
					)
				)
				(circle
					(center 6.35 1.143)
					(radius 0.127)
					(stroke
						(width 0.254)
						(type default)
					)
					(fill
						(type background)
					)
				)
				(circle
					(center 6.35 0.635)
					(radius 0.127)
					(stroke
						(width 0.254)
						(type default)
					)
					(fill
						(type background)
					)
				)
				(polyline
					(pts
						(xy 6.35 -1.27) (xy 6.35 2.54) (xy 3.81 2.54)
					)
					(stroke
						(width 0.254)
						(type default)
					)
					(fill
						(type none)
					)
				)
				(polyline
					(pts
						(xy 7.366 3.048) (xy 6.858 2.286) (xy 7.874 2.286) (xy 7.366 3.048)
					)
					(stroke
						(width 0.254)
						(type default)
					)
					(fill
						(type outline)
					)
				)
				(polyline
					(pts
						(xy 7.874 3.048) (xy 6.858 3.048)
					)
					(stroke
						(width 0.254)
						(type default)
					)
					(fill
						(type background)
					)
				)
				(pin input line
					(at 0 0 0)
					(length 2.54)
					(name "G"
						(effects
							(font
								(size 1.27 1.27)
							)
						)
					)
					(number "1"
						(effects
							(font
								(size 1.27 1.27)
							)
						)
					)
				)
				(pin passive line
					(at 6.35 7.62 270)
					(length 2.54)
					(name "D"
						(effects
							(font
								(size 1.27 1.27)
							)
						)
					)
					(number "3"
						(effects
							(font
								(size 1.27 1.27)
							)
						)
					)
				)
				(pin passive line
					(at 6.35 -2.54 90)
					(length 2.54)
					(name "S"
						(effects
							(font
								(size 1.27 1.27)
							)
						)
					)
					(number "2"
						(effects
							(font
								(size 1.27 1.27)
							)
						)
					)
				)
			)
		)
	(symbol "antmicroTransistorsFETsMOSFETsSingle:SISS05DN-T1-GE3"
			(pin_names
				(offset 0)
			)
			(exclude_from_sim no)
			(in_bom no)
			(on_board yes)
			(property "Reference" "Q"
				(at 15.24 -5.08 0)
				(effects
					(font
						(size 1.27 1.27)
						(thickness 0.15)
					)
					(justify left bottom)
				)
			)
			(property "Value" "SISS05DN-T1-GE3"
				(at 15.24 -10.16 0)
				(effects
					(font
						(size 1.27 1.27)
						(thickness 0.15)
					)
					(justify left bottom)
					(hide yes)
				)
			)
			(property "Footprint" "antmicro-footprints:Vishay_PowerPAK_1212-8_Single"
				(at 15.24 -12.7 0)
				(effects
					(font
						(size 1.27 1.27)
						(thickness 0.15)
					)
					(justify left bottom)
					(hide yes)
				)
			)
			(property "Datasheet" "https://www.vishay.com/docs/77029/siss05dn.pdf"
				(at 15.24 -15.24 0)
				(effects
					(font
						(size 1.27 1.27)
						(thickness 0.15)
					)
					(justify left bottom)
					(hide yes)
				)
			)
			(property "Description" "Power MOSFET, P Channel, 30 V, 108 A, 0.0035 ohm, PowerPAK 1212, Surface Mount"
				(at 15.24 -27.94 0)
				(effects
					(font
						(size 1.27 1.27)
						(thickness 0.15)
					)
					(justify left bottom)
					(hide yes)
				)
			)
			(property "MPN" "SISS05DN-T1-GE3"
				(at 15.24 -7.62 0)
				(effects
					(font
						(size 1.27 1.27)
						(thickness 0.15)
					)
					(justify left bottom)
				)
			)
			(property "Manufacturer" "Vishay"
				(at 15.24 -20.32 0)
				(effects
					(font
						(size 1.27 1.27)
						(thickness 0.15)
					)
					(justify left bottom)
					(hide yes)
				)
			)
			(property "Author" "Antmicro"
				(at 15.24 -22.86 0)
				(effects
					(font
						(size 1.27 1.27)
						(thickness 0.15)
					)
					(justify left bottom)
					(hide yes)
				)
			)
			(property "License" "Apache-2.0"
				(at 15.24 -25.4 0)
				(effects
					(font
						(size 1.27 1.27)
						(thickness 0.15)
					)
					(justify left bottom)
					(hide yes)
				)
			)
			(property "ki_keywords" "SMT, TRANSISTOR, SEMICONDUCTOR, MOSFET, PMOS"
				(at 0 0 0)
				(effects
					(font
						(size 1.27 1.27)
					)
					(hide yes)
				)
			)
			(symbol "SISS05DN-T1-GE3_1_1"
				(polyline
					(pts
						(xy 1.27 0) (xy 3.302 0) (xy 3.302 3.937)
					)
					(stroke
						(width 0.254)
						(type default)
					)
					(fill
						(type none)
					)
				)
				(polyline
					(pts
						(xy 3.81 4.445) (xy 3.81 3.429)
					)
					(stroke
						(width 0.254)
						(type default)
					)
					(fill
						(type background)
					)
				)
				(polyline
					(pts
						(xy 3.81 2.54) (xy 3.81 3.048)
					)
					(stroke
						(width 0.254)
						(type default)
					)
					(fill
						(type background)
					)
				)
				(polyline
					(pts
						(xy 3.81 2.54) (xy 3.81 2.032)
					)
					(stroke
						(width 0.254)
						(type default)
					)
					(fill
						(type background)
					)
				)
				(polyline
					(pts
						(xy 3.81 1.143) (xy 3.81 1.651)
					)
					(stroke
						(width 0.254)
						(type default)
					)
					(fill
						(type background)
					)
				)
				(polyline
					(pts
						(xy 3.81 1.143) (xy 3.81 0.635)
					)
					(stroke
						(width 0.254)
						(type default)
					)
					(fill
						(type background)
					)
				)
				(circle
					(center 5.08 2.54)
					(radius 3.302)
					(stroke
						(width 0.254)
						(type default)
					)
					(fill
						(type background)
					)
				)
				(polyline
					(pts
						(xy 6.096 2.54) (xy 5.334 2.032) (xy 5.334 3.048) (xy 6.096 2.54)
					)
					(stroke
						(width 0.254)
						(type default)
					)
					(fill
						(type outline)
					)
				)
				(polyline
					(pts
						(xy 6.223 0.635) (xy 7.366 0.635) (xy 7.366 3.937) (xy 7.366 4.445) (xy 6.223 4.445)
					)
					(stroke
						(width 0.254)
						(type default)
					)
					(fill
						(type none)
					)
				)
				(polyline
					(pts
						(xy 6.35 6.35) (xy 6.35 3.937) (xy 3.81 3.937)
					)
					(stroke
						(width 0.254)
						(type default)
					)
					(fill
						(type none)
					)
				)
				(circle
					(center 6.35 4.445)
					(radius 0.127)
					(stroke
						(width 0.254)
						(type default)
					)
					(fill
						(type background)
					)
				)
				(polyline
					(pts
						(xy 6.35 1.143) (xy 3.81 1.143)
					)
					(stroke
						(width 0.254)
						(type default)
					)
					(fill
						(type background)
					)
				)
				(circle
					(center 6.35 1.143)
					(radius 0.127)
					(stroke
						(width 0.254)
						(type default)
					)
					(fill
						(type background)
					)
				)
				(circle
					(center 6.35 0.635)
					(radius 0.127)
					(stroke
						(width 0.254)
						(type default)
					)
					(fill
						(type background)
					)
				)
				(polyline
					(pts
						(xy 6.35 -1.27) (xy 6.35 2.54) (xy 3.81 2.54)
					)
					(stroke
						(width 0.254)
						(type default)
					)
					(fill
						(type none)
					)
				)
				(polyline
					(pts
						(xy 7.366 2.286) (xy 7.874 3.048) (xy 6.858 3.048) (xy 7.366 2.286)
					)
					(stroke
						(width 0.254)
						(type default)
					)
					(fill
						(type outline)
					)
				)
				(polyline
					(pts
						(xy 7.874 2.286) (xy 6.858 2.286)
					)
					(stroke
						(width 0.254)
						(type default)
					)
					(fill
						(type background)
					)
				)
				(pin input line
					(at 0 0 0)
					(length 2.54)
					(name "G"
						(effects
							(font
								(size 1.27 1.27)
							)
						)
					)
					(number "4"
						(effects
							(font
								(size 1.27 1.27)
							)
						)
					)
				)
				(pin passive line
					(at 6.35 7.62 270)
					(length 2.54)
					(name "D"
						(effects
							(font
								(size 1.27 1.27)
							)
						)
					)
					(number "5"
						(effects
							(font
								(size 1.27 1.27)
							)
						)
					)
				)
				(pin passive line
					(at 6.35 -2.54 90)
					(length 2.54)
					(name "S"
						(effects
							(font
								(size 1.27 1.27)
							)
						)
					)
					(number "1"
						(effects
							(font
								(size 1.27 1.27)
							)
						)
					)
				)
				(pin passive line
					(at 6.35 -2.54 90)
					(length 2.54)
					(hide yes)
					(name "S"
						(effects
							(font
								(size 1.27 1.27)
							)
						)
					)
					(number "2"
						(effects
							(font
								(size 1.27 1.27)
							)
						)
					)
				)
				(pin passive line
					(at 6.35 -2.54 90)
					(length 2.54)
					(hide yes)
					(name "S"
						(effects
							(font
								(size 1.27 1.27)
							)
						)
					)
					(number "3"
						(effects
							(font
								(size 1.27 1.27)
							)
						)
					)
				)
			)
		)
	(symbol "antmicroUSBConnectors:USB-C_Kycon_KUSBX-SL2-CS1N24-B-TR"
			(exclude_from_sim no)
			(in_bom yes)
			(on_board yes)
			(property "Reference" "J"
				(at 43.18 -2.54 0)
				(effects
					(font
						(size 1.27 1.27)
						(thickness 0.15)
					)
					(justify left bottom)
				)
			)
			(property "Value" "USB-C_Kycon_KUSBX-SL2-CS1N24-B-TR"
				(at 43.18 -5.08 0)
				(effects
					(font
						(size 1.27 1.27)
						(thickness 0.15)
					)
					(justify left bottom)
					(hide yes)
				)
			)
			(property "Footprint" "antmicro-footprints:USB-C_Receptacle_Kycon_KUSBX-SL2-CS1N24-B-TR"
				(at 43.18 -7.62 0)
				(effects
					(font
						(size 1.27 1.27)
						(thickness 0.15)
					)
					(justify left bottom)
					(hide yes)
				)
			)
			(property "Datasheet" "https://www.kycon.com/Pub_Eng_Draw/KUSBX-SL2-CS1N24-B-TR.pdf"
				(at 43.18 -10.16 0)
				(effects
					(font
						(size 1.27 1.27)
						(thickness 0.15)
					)
					(justify left bottom)
					(hide yes)
				)
			)
			(property "Description" "USB-C (USB TYPE-C) USB 3.2 Gen 2 (USB 3.1 Gen 2, Superspeed + (USB 3.1)) USB PD Receptacle Connector 24 Position Surface Mount"
				(at 43.18 -22.86 0)
				(effects
					(font
						(size 1.27 1.27)
					)
					(justify left bottom)
					(hide yes)
				)
			)
			(property "MPN" "KUSBX-SL2-CS1N24-B-TR"
				(at 43.18 -12.7 0)
				(effects
					(font
						(size 1.27 1.27)
						(thickness 0.15)
					)
					(justify left bottom)
				)
			)
			(property "Manufacturer" "Kycon"
				(at 43.18 -15.24 0)
				(effects
					(font
						(size 1.27 1.27)
						(thickness 0.15)
					)
					(justify left bottom)
					(hide yes)
				)
			)
			(property "License" "Apache-2.0"
				(at 43.18 -17.78 0)
				(effects
					(font
						(size 1.27 1.27)
						(thickness 0.15)
					)
					(justify left bottom)
					(hide yes)
				)
			)
			(property "Author" "Antmicro"
				(at 43.18 -20.32 0)
				(effects
					(font
						(size 1.27 1.27)
						(thickness 0.15)
					)
					(justify left bottom)
					(hide yes)
				)
			)
			(property "ki_keywords" "USB, CONNECTOR, SMT, HORIZONTAL"
				(at 0 0 0)
				(effects
					(font
						(size 1.27 1.27)
					)
					(hide yes)
				)
			)
			(symbol "USB-C_Kycon_KUSBX-SL2-CS1N24-B-TR_1_1"
				(rectangle
					(start -22.86 -68.58)
					(end -3.81 2.54)
					(stroke
						(width 0.254)
						(type default)
					)
					(fill
						(type background)
					)
				)
				(circle
					(center -20.066 -33.274)
					(radius 0.284)
					(stroke
						(width 0.254)
						(type default)
					)
					(fill
						(type outline)
					)
				)
				(polyline
					(pts
						(xy -19.812 -31.623) (xy -19.177 -30.48) (xy -18.542 -31.623) (xy -19.812 -31.623)
					)
					(stroke
						(width 0.254)
						(type default)
					)
					(fill
						(type outline)
					)
				)
				(polyline
					(pts
						(xy -19.177 -34.798) (xy -18.288 -33.909) (xy -18.288 -33.274)
					)
					(stroke
						(width 0.254)
						(type default)
					)
					(fill
						(type background)
					)
				)
				(polyline
					(pts
						(xy -19.177 -35.179) (xy -20.066 -34.29) (xy -20.066 -33.655)
					)
					(stroke
						(width 0.254)
						(type default)
					)
					(fill
						(type background)
					)
				)
				(polyline
					(pts
						(xy -19.177 -35.941) (xy -19.177 -31.623)
					)
					(stroke
						(width 0.254)
						(type default)
					)
					(fill
						(type background)
					)
				)
				(circle
					(center -19.177 -36.068)
					(radius 0.5236)
					(stroke
						(width 0.254)
						(type default)
					)
					(fill
						(type outline)
					)
				)
				(rectangle
					(start -18.669 -33.274)
					(end -17.907 -32.512)
					(stroke
						(width 0.254)
						(type default)
					)
					(fill
						(type outline)
					)
				)
				(polyline
					(pts
						(xy -16.51 -36.83) (xy -16.51 -29.21)
					)
					(stroke
						(width 0.254)
						(type default)
					)
					(fill
						(type background)
					)
				)
				(rectangle
					(start -15.24 -36.83)
					(end -13.97 -29.21)
					(stroke
						(width 0.254)
						(type default)
					)
					(fill
						(type outline)
					)
				)
				(arc
					(start -15.24 -29.21)
					(mid -14.605 -28.5777)
					(end -13.97 -29.21)
					(stroke
						(width 0.254)
						(type default)
					)
					(fill
						(type outline)
					)
				)
				(arc
					(start -15.24 -29.21)
					(mid -14.605 -28.5777)
					(end -13.97 -29.21)
					(stroke
						(width 0.254)
						(type default)
					)
					(fill
						(type background)
					)
				)
				(arc
					(start -16.51 -29.21)
					(mid -14.605 -27.3133)
					(end -12.7 -29.21)
					(stroke
						(width 0.254)
						(type default)
					)
					(fill
						(type background)
					)
				)
				(arc
					(start -12.7 -36.83)
					(mid -14.605 -38.7267)
					(end -16.51 -36.83)
					(stroke
						(width 0.254)
						(type default)
					)
					(fill
						(type background)
					)
				)
				(arc
					(start -13.97 -36.83)
					(mid -14.605 -37.4623)
					(end -15.24 -36.83)
					(stroke
						(width 0.254)
						(type default)
					)
					(fill
						(type outline)
					)
				)
				(arc
					(start -13.97 -36.83)
					(mid -14.605 -37.4623)
					(end -15.24 -36.83)
					(stroke
						(width 0.254)
						(type default)
					)
					(fill
						(type background)
					)
				)
				(polyline
					(pts
						(xy -12.7 -29.21) (xy -12.7 -36.83)
					)
					(stroke
						(width 0.254)
						(type default)
					)
					(fill
						(type background)
					)
				)
				(pin power_in line
					(at 0 0 180)
					(length 3.81)
					(name "VBUS"
						(effects
							(font
								(size 1.27 1.27)
							)
						)
					)
					(number "A4"
						(effects
							(font
								(size 1.27 1.27)
							)
						)
					)
				)
				(pin passive line
					(at 0 0 180)
					(length 3.81)
					(hide yes)
					(name "VBUS"
						(effects
							(font
								(size 1.27 1.27)
							)
						)
					)
					(number "A9"
						(effects
							(font
								(size 1.27 1.27)
							)
						)
					)
				)
				(pin passive line
					(at 0 0 180)
					(length 3.81)
					(hide yes)
					(name "VBUS"
						(effects
							(font
								(size 1.27 1.27)
							)
						)
					)
					(number "B4"
						(effects
							(font
								(size 1.27 1.27)
							)
						)
					)
				)
				(pin passive line
					(at 0 0 180)
					(length 3.81)
					(hide yes)
					(name "VBUS"
						(effects
							(font
								(size 1.27 1.27)
							)
						)
					)
					(number "B9"
						(effects
							(font
								(size 1.27 1.27)
							)
						)
					)
				)
				(pin bidirectional line
					(at 0 -5.08 180)
					(length 3.81)
					(name "CC_{1}"
						(effects
							(font
								(size 1.27 1.27)
							)
						)
					)
					(number "A5"
						(effects
							(font
								(size 1.27 1.27)
							)
						)
					)
				)
				(pin bidirectional line
					(at 0 -7.62 180)
					(length 3.81)
					(name "CC_{2}"
						(effects
							(font
								(size 1.27 1.27)
							)
						)
					)
					(number "B5"
						(effects
							(font
								(size 1.27 1.27)
							)
						)
					)
				)
				(pin bidirectional line
					(at 0 -12.7 180)
					(length 3.81)
					(name "D_{A}+"
						(effects
							(font
								(size 1.27 1.27)
							)
						)
					)
					(number "A6"
						(effects
							(font
								(size 1.27 1.27)
							)
						)
					)
				)
				(pin bidirectional line
					(at 0 -15.24 180)
					(length 3.81)
					(name "D_{A}-"
						(effects
							(font
								(size 1.27 1.27)
							)
						)
					)
					(number "A7"
						(effects
							(font
								(size 1.27 1.27)
							)
						)
					)
				)
				(pin bidirectional line
					(at 0 -17.78 180)
					(length 3.81)
					(name "D_{B}+"
						(effects
							(font
								(size 1.27 1.27)
							)
						)
					)
					(number "B6"
						(effects
							(font
								(size 1.27 1.27)
							)
						)
					)
				)
				(pin bidirectional line
					(at 0 -20.32 180)
					(length 3.81)
					(name "D_{B}-"
						(effects
							(font
								(size 1.27 1.27)
							)
						)
					)
					(number "B7"
						(effects
							(font
								(size 1.27 1.27)
							)
						)
					)
				)
				(pin bidirectional line
					(at 0 -25.4 180)
					(length 3.81)
					(name "RX_{1}+"
						(effects
							(font
								(size 1.27 1.27)
							)
						)
					)
					(number "B11"
						(effects
							(font
								(size 1.27 1.27)
							)
						)
					)
				)
				(pin bidirectional line
					(at 0 -27.94 180)
					(length 3.81)
					(name "RX_{1}-"
						(effects
							(font
								(size 1.27 1.27)
							)
						)
					)
					(number "B10"
						(effects
							(font
								(size 1.27 1.27)
							)
						)
					)
				)
				(pin bidirectional line
					(at 0 -33.02 180)
					(length 3.81)
					(name "TX_{1}+"
						(effects
							(font
								(size 1.27 1.27)
							)
						)
					)
					(number "A2"
						(effects
							(font
								(size 1.27 1.27)
							)
						)
					)
				)
				(pin bidirectional line
					(at 0 -35.56 180)
					(length 3.81)
					(name "TX_{1}-"
						(effects
							(font
								(size 1.27 1.27)
							)
						)
					)
					(number "A3"
						(effects
							(font
								(size 1.27 1.27)
							)
						)
					)
				)
				(pin bidirectional line
					(at 0 -40.64 180)
					(length 3.81)
					(name "RX_{2}+"
						(effects
							(font
								(size 1.27 1.27)
							)
						)
					)
					(number "A11"
						(effects
							(font
								(size 1.27 1.27)
							)
						)
					)
				)
				(pin bidirectional line
					(at 0 -43.18 180)
					(length 3.81)
					(name "RX_{2}-"
						(effects
							(font
								(size 1.27 1.27)
							)
						)
					)
					(number "A10"
						(effects
							(font
								(size 1.27 1.27)
							)
						)
					)
				)
				(pin bidirectional line
					(at 0 -48.26 180)
					(length 3.81)
					(name "TX_{2}+"
						(effects
							(font
								(size 1.27 1.27)
							)
						)
					)
					(number "B2"
						(effects
							(font
								(size 1.27 1.27)
							)
						)
					)
				)
				(pin bidirectional line
					(at 0 -50.8 180)
					(length 3.81)
					(name "TX_{2}-"
						(effects
							(font
								(size 1.27 1.27)
							)
						)
					)
					(number "B3"
						(effects
							(font
								(size 1.27 1.27)
							)
						)
					)
				)
				(pin bidirectional line
					(at 0 -55.88 180)
					(length 3.81)
					(name "SBU_{1}"
						(effects
							(font
								(size 1.27 1.27)
							)
						)
					)
					(number "A8"
						(effects
							(font
								(size 1.27 1.27)
							)
						)
					)
				)
				(pin bidirectional line
					(at 0 -58.42 180)
					(length 3.81)
					(name "SBU_{2}"
						(effects
							(font
								(size 1.27 1.27)
							)
						)
					)
					(number "B8"
						(effects
							(font
								(size 1.27 1.27)
							)
						)
					)
				)
				(pin power_in line
					(at 0 -63.5 180)
					(length 3.81)
					(name "GND"
						(effects
							(font
								(size 1.27 1.27)
							)
						)
					)
					(number "A1"
						(effects
							(font
								(size 1.27 1.27)
							)
						)
					)
				)
				(pin passive line
					(at 0 -63.5 180)
					(length 3.81)
					(hide yes)
					(name "GND"
						(effects
							(font
								(size 1.27 1.27)
							)
						)
					)
					(number "A12"
						(effects
							(font
								(size 1.27 1.27)
							)
						)
					)
				)
				(pin passive line
					(at 0 -63.5 180)
					(length 3.81)
					(hide yes)
					(name "GND"
						(effects
							(font
								(size 1.27 1.27)
							)
						)
					)
					(number "B1"
						(effects
							(font
								(size 1.27 1.27)
							)
						)
					)
				)
				(pin passive line
					(at 0 -63.5 180)
					(length 3.81)
					(hide yes)
					(name "GND"
						(effects
							(font
								(size 1.27 1.27)
							)
						)
					)
					(number "B12"
						(effects
							(font
								(size 1.27 1.27)
							)
						)
					)
				)
				(pin passive line
					(at 0 -66.04 180)
					(length 3.81)
					(name "SH"
						(effects
							(font
								(size 1.27 1.27)
							)
						)
					)
					(number "SH"
						(effects
							(font
								(size 1.27 1.27)
							)
						)
					)
				)
			)
		)
	(symbol "antmicroWire2BoardConnectors:Amphenol_SFP28_1x20_UE763GA202600T"
			(exclude_from_sim no)
			(in_bom yes)
			(on_board yes)
			(property "Reference" "J"
				(at 38.1 -2.54 0)
				(effects
					(font
						(size 1.27 1.27)
						(thickness 0.15)
					)
					(justify left bottom)
				)
			)
			(property "Value" "Amphenol_SFP28_1x20_UE763GA202600T"
				(at 38.1 -7.62 0)
				(effects
					(font
						(size 1.27 1.27)
						(thickness 0.15)
					)
					(justify left bottom)
					(hide yes)
				)
			)
			(property "Footprint" "antmicro-footprints:Conn_Amphenol_SFP28_1x20_UE763GA202600T"
				(at 38.1 -10.16 0)
				(effects
					(font
						(size 1.27 1.27)
						(thickness 0.15)
					)
					(justify left bottom)
					(hide yes)
				)
			)
			(property "Datasheet" "https://cdn.amphenol-cs.com/media/wysiwyg/files/documentation/datasheet/inputoutput/hsio_cn_ultraport_sfp.pdf"
				(at 38.1 -12.7 0)
				(effects
					(font
						(size 1.27 1.27)
						(thickness 0.15)
					)
					(justify left bottom)
					(hide yes)
				)
			)
			(property "Description" "20 Position SFP28 Receptacle with no Cage, Right Angle"
				(at 38.1 -15.24 0)
				(effects
					(font
						(size 1.27 1.27)
						(thickness 0.15)
					)
					(justify left bottom)
					(hide yes)
				)
			)
			(property "MPN" "UE763GA202600T"
				(at 38.1 -5.08 0)
				(effects
					(font
						(size 1.27 1.27)
						(thickness 0.15)
					)
					(justify left bottom)
				)
			)
			(property "Manufacturer" "Amphenol"
				(at 38.1 -17.78 0)
				(effects
					(font
						(size 1.27 1.27)
						(thickness 0.15)
					)
					(justify left bottom)
					(hide yes)
				)
			)
			(property "Author" "Antmicro"
				(at 38.1 -20.32 0)
				(effects
					(font
						(size 1.27 1.27)
						(thickness 0.15)
					)
					(justify left bottom)
					(hide yes)
				)
			)
			(property "License" "Apache-2.0"
				(at 38.1 -22.86 0)
				(effects
					(font
						(size 1.27 1.27)
						(thickness 0.15)
					)
					(justify left bottom)
					(hide yes)
				)
			)
			(property "ki_keywords" "CONNECTOR"
				(at 0 0 0)
				(effects
					(font
						(size 1.27 1.27)
					)
					(hide yes)
				)
			)
			(symbol "Amphenol_SFP28_1x20_UE763GA202600T_1_1"
				(rectangle
					(start 2.54 2.54)
					(end 22.86 -45.72)
					(stroke
						(width 0.254)
						(type default)
					)
					(fill
						(type background)
					)
				)
				(text "SFP28\n"
					(at 16.51 0 0)
					(effects
						(font
							(size 1.27 1.27)
							(thickness 0.15)
						)
						(justify left bottom)
					)
				)
				(pin power_in line
					(at 0 0 0)
					(length 2.54)
					(name "V_{CC}(R)"
						(effects
							(font
								(size 1.27 1.27)
							)
						)
					)
					(number "15"
						(effects
							(font
								(size 1.27 1.27)
							)
						)
					)
				)
				(pin power_in line
					(at 0 -2.54 0)
					(length 2.54)
					(name "V_{CC}(T)"
						(effects
							(font
								(size 1.27 1.27)
							)
						)
					)
					(number "16"
						(effects
							(font
								(size 1.27 1.27)
							)
						)
					)
				)
				(pin bidirectional line
					(at 0 -7.62 0)
					(length 2.54)
					(name "SDA"
						(effects
							(font
								(size 1.27 1.27)
							)
						)
					)
					(number "4"
						(effects
							(font
								(size 1.27 1.27)
							)
						)
					)
				)
				(pin bidirectional line
					(at 0 -10.16 0)
					(length 2.54)
					(name "SCL"
						(effects
							(font
								(size 1.27 1.27)
							)
						)
					)
					(number "5"
						(effects
							(font
								(size 1.27 1.27)
							)
						)
					)
				)
				(pin passive line
					(at 0 -15.24 0)
					(length 2.54)
					(name "MOD_{ABS}"
						(effects
							(font
								(size 1.27 1.27)
							)
						)
					)
					(number "6"
						(effects
							(font
								(size 1.27 1.27)
							)
						)
					)
				)
				(pin open_collector line
					(at 0 -17.78 0)
					(length 2.54)
					(name "RX_{LOS}"
						(effects
							(font
								(size 1.27 1.27)
							)
						)
					)
					(number "8"
						(effects
							(font
								(size 1.27 1.27)
							)
						)
					)
				)
				(pin open_collector line
					(at 0 -20.32 0)
					(length 2.54)
					(name "TX_{FAULT}"
						(effects
							(font
								(size 1.27 1.27)
							)
						)
					)
					(number "2"
						(effects
							(font
								(size 1.27 1.27)
							)
						)
					)
				)
				(pin input line
					(at 0 -22.86 0)
					(length 2.54)
					(name "TX_{DISABLE}"
						(effects
							(font
								(size 1.27 1.27)
							)
						)
					)
					(number "3"
						(effects
							(font
								(size 1.27 1.27)
							)
						)
					)
				)
				(pin input line
					(at 0 -25.4 0)
					(length 2.54)
					(name "RS1"
						(effects
							(font
								(size 1.27 1.27)
							)
						)
					)
					(number "9"
						(effects
							(font
								(size 1.27 1.27)
							)
						)
					)
				)
				(pin input line
					(at 0 -27.94 0)
					(length 2.54)
					(name "RS0"
						(effects
							(font
								(size 1.27 1.27)
							)
						)
					)
					(number "7"
						(effects
							(font
								(size 1.27 1.27)
							)
						)
					)
				)
				(pin input line
					(at 0 -33.02 0)
					(length 2.54)
					(name "TD+"
						(effects
							(font
								(size 1.27 1.27)
							)
						)
					)
					(number "18"
						(effects
							(font
								(size 1.27 1.27)
							)
						)
					)
				)
				(pin input line
					(at 0 -35.56 0)
					(length 2.54)
					(name "TD-"
						(effects
							(font
								(size 1.27 1.27)
							)
						)
					)
					(number "19"
						(effects
							(font
								(size 1.27 1.27)
							)
						)
					)
				)
				(pin output line
					(at 0 -40.64 0)
					(length 2.54)
					(name "RD+"
						(effects
							(font
								(size 1.27 1.27)
							)
						)
					)
					(number "13"
						(effects
							(font
								(size 1.27 1.27)
							)
						)
					)
				)
				(pin output line
					(at 0 -43.18 0)
					(length 2.54)
					(name "RD-"
						(effects
							(font
								(size 1.27 1.27)
							)
						)
					)
					(number "12"
						(effects
							(font
								(size 1.27 1.27)
							)
						)
					)
				)
				(pin passive line
					(at 25.4 -40.64 180)
					(length 2.54)
					(name "V_{EE}(T)"
						(effects
							(font
								(size 1.27 1.27)
							)
						)
					)
					(number "1"
						(effects
							(font
								(size 1.27 1.27)
							)
						)
					)
				)
				(pin passive line
					(at 25.4 -40.64 180)
					(length 2.54)
					(hide yes)
					(name "V_{EE}(T)"
						(effects
							(font
								(size 1.27 1.27)
							)
						)
					)
					(number "17"
						(effects
							(font
								(size 1.27 1.27)
							)
						)
					)
				)
				(pin passive line
					(at 25.4 -40.64 180)
					(length 2.54)
					(hide yes)
					(name "V_{EE}(T)"
						(effects
							(font
								(size 1.27 1.27)
							)
						)
					)
					(number "20"
						(effects
							(font
								(size 1.27 1.27)
							)
						)
					)
				)
				(pin passive line
					(at 25.4 -43.18 180)
					(length 2.54)
					(name "V_{EE}(R)"
						(effects
							(font
								(size 1.27 1.27)
							)
						)
					)
					(number "10"
						(effects
							(font
								(size 1.27 1.27)
							)
						)
					)
				)
				(pin passive line
					(at 25.4 -43.18 180)
					(length 2.54)
					(hide yes)
					(name "V_{EE}(R)"
						(effects
							(font
								(size 1.27 1.27)
							)
						)
					)
					(number "11"
						(effects
							(font
								(size 1.27 1.27)
							)
						)
					)
				)
				(pin passive line
					(at 25.4 -43.18 180)
					(length 2.54)
					(hide yes)
					(name "V_{EE}(R)"
						(effects
							(font
								(size 1.27 1.27)
							)
						)
					)
					(number "14"
						(effects
							(font
								(size 1.27 1.27)
							)
						)
					)
				)
			)
		)
	(symbol "antmicroWire2BoardConnectors:Amphenol_SFP28_Cage_U773GC16382071"
			(exclude_from_sim no)
			(in_bom yes)
			(on_board yes)
			(property "Reference" "J"
				(at 15.24 -2.54 0)
				(effects
					(font
						(size 1.27 1.27)
						(thickness 0.15)
					)
					(justify left bottom)
				)
			)
			(property "Value" "Amphenol_SFP28_Cage_U773GC16382071"
				(at 15.24 -7.62 0)
				(effects
					(font
						(size 1.27 1.27)
						(thickness 0.15)
					)
					(justify left bottom)
					(hide yes)
				)
			)
			(property "Footprint" "antmicro-footprints:Conn_Amphenol_SFP28_Cage_U773GC16382071"
				(at 15.24 -10.16 0)
				(effects
					(font
						(size 1.27 1.27)
						(thickness 0.15)
					)
					(justify left bottom)
					(hide yes)
				)
			)
			(property "Datasheet" "https://cdn.amphenol-cs.com/media/wysiwyg/files/documentation/datasheet/inputoutput/hsio_cn_ultraport_sfp.pdf"
				(at 15.24 -12.7 0)
				(effects
					(font
						(size 1.27 1.27)
						(thickness 0.15)
					)
					(justify left bottom)
					(hide yes)
				)
			)
			(property "Description" "SFP28 Receptacle Cage"
				(at 15.24 -15.24 0)
				(effects
					(font
						(size 1.27 1.27)
						(thickness 0.15)
					)
					(justify left bottom)
					(hide yes)
				)
			)
			(property "MPN" "U773GC16382071"
				(at 15.24 -5.08 0)
				(effects
					(font
						(size 1.27 1.27)
						(thickness 0.15)
					)
					(justify left bottom)
				)
			)
			(property "Manufacturer" "Amphenol"
				(at 15.24 -17.78 0)
				(effects
					(font
						(size 1.27 1.27)
						(thickness 0.15)
					)
					(justify left bottom)
					(hide yes)
				)
			)
			(property "Author" "Antmicro"
				(at 15.24 -20.32 0)
				(effects
					(font
						(size 1.27 1.27)
						(thickness 0.15)
					)
					(justify left bottom)
					(hide yes)
				)
			)
			(property "License" "Apache-2.0"
				(at 15.24 -22.86 0)
				(effects
					(font
						(size 1.27 1.27)
						(thickness 0.15)
					)
					(justify left bottom)
					(hide yes)
				)
			)
			(property "ki_keywords" "CONNECTOR"
				(at 0 0 0)
				(effects
					(font
						(size 1.27 1.27)
					)
					(hide yes)
				)
			)
			(symbol "Amphenol_SFP28_Cage_U773GC16382071_1_1"
				(rectangle
					(start -15.24 3.81)
					(end -2.54 -3.81)
					(stroke
						(width 0.254)
						(type default)
					)
					(fill
						(type background)
					)
				)
				(text "SFP28_Cage\n"
					(at -14.986 1.778 0)
					(effects
						(font
							(size 1.27 1.27)
							(thickness 0.15)
						)
						(justify left bottom)
					)
				)
				(pin passive line
					(at 0 0 180)
					(length 2.54)
					(name "SH"
						(effects
							(font
								(size 1.27 1.27)
							)
						)
					)
					(number "SH"
						(effects
							(font
								(size 1.27 1.27)
							)
						)
					)
				)
			)
		)
	(symbol "antmicroWire2BoardConnectors:JST_SH_1x4_BM04B-SRSS-TB-LF-SN"
			(exclude_from_sim no)
			(in_bom yes)
			(on_board yes)
			(property "Reference" "J"
				(at 20.32 -5.08 0)
				(effects
					(font
						(size 1.27 1.27)
						(thickness 0.15)
					)
					(justify left bottom)
				)
			)
			(property "Value" "JST_SH_1x4_BM04B-SRSS-TB-LF-SN"
				(at 20.32 -7.62 0)
				(effects
					(font
						(size 1.27 1.27)
						(thickness 0.15)
					)
					(justify left bottom)
					(hide yes)
				)
			)
			(property "Footprint" "antmicro-footprints:Conn_JST_SH_1x4_BM04B-SRSS-TB-LF-SN"
				(at 20.32 -10.16 0)
				(effects
					(font
						(size 1.27 1.27)
						(thickness 0.15)
					)
					(justify left bottom)
					(hide yes)
				)
			)
			(property "Datasheet" "https://www.jst-mfg.com/product/pdf/eng/eSH.pdf"
				(at 20.32 -12.7 0)
				(effects
					(font
						(size 1.27 1.27)
						(thickness 0.15)
					)
					(justify left bottom)
					(hide yes)
				)
			)
			(property "Description" "Pin Header, Top Entry, Wire-to-Board, 1 mm, 1 Rows, 4 Contacts, Surface Mount, SR"
				(at 20.32 -25.4 0)
				(effects
					(font
						(size 1.27 1.27)
					)
					(justify left bottom)
					(hide yes)
				)
			)
			(property "MPN" "BM04B-SRSS-TB(LF)(SN) "
				(at 20.32 -15.24 0)
				(effects
					(font
						(size 1.27 1.27)
						(thickness 0.15)
					)
					(justify left bottom)
				)
			)
			(property "Manufacturer" "JST Automotive Connectors"
				(at 20.32 -17.78 0)
				(effects
					(font
						(size 1.27 1.27)
						(thickness 0.15)
					)
					(justify left bottom)
					(hide yes)
				)
			)
			(property "Author" "Antmicro"
				(at 20.32 -20.32 0)
				(effects
					(font
						(size 1.27 1.27)
						(thickness 0.15)
					)
					(justify left bottom)
					(hide yes)
				)
			)
			(property "License" "Apache-2.0"
				(at 20.32 -22.86 0)
				(effects
					(font
						(size 1.27 1.27)
						(thickness 0.15)
					)
					(justify left bottom)
					(hide yes)
				)
			)
			(property "ki_keywords" "VERTICAL, SMT, WIRE-BOARD, CONNECTOR"
				(at 0 0 0)
				(effects
					(font
						(size 1.27 1.27)
					)
					(hide yes)
				)
			)
			(symbol "JST_SH_1x4_BM04B-SRSS-TB-LF-SN_1_1"
				(rectangle
					(start 2.54 2.54)
					(end 5.08 -12.7)
					(stroke
						(width 0.254)
						(type default)
					)
					(fill
						(type background)
					)
				)
				(rectangle
					(start 2.54 0.127)
					(end 3.81 -0.127)
					(stroke
						(width 0.254)
						(type default)
					)
					(fill
						(type background)
					)
				)
				(rectangle
					(start 2.54 -2.413)
					(end 3.81 -2.667)
					(stroke
						(width 0.254)
						(type default)
					)
					(fill
						(type background)
					)
				)
				(rectangle
					(start 2.54 -4.953)
					(end 3.81 -5.207)
					(stroke
						(width 0.254)
						(type default)
					)
					(fill
						(type background)
					)
				)
				(rectangle
					(start 2.54 -7.493)
					(end 3.81 -7.747)
					(stroke
						(width 0.254)
						(type default)
					)
					(fill
						(type background)
					)
				)
				(rectangle
					(start 2.54 -10.033)
					(end 3.81 -10.287)
					(stroke
						(width 0.254)
						(type default)
					)
					(fill
						(type background)
					)
				)
				(pin passive line
					(at 0 0 0)
					(length 2.54)
					(name "~"
						(effects
							(font
								(size 1.27 1.27)
							)
						)
					)
					(number "1"
						(effects
							(font
								(size 1.27 1.27)
							)
						)
					)
				)
				(pin passive line
					(at 0 -2.54 0)
					(length 2.54)
					(name "~"
						(effects
							(font
								(size 1.27 1.27)
							)
						)
					)
					(number "2"
						(effects
							(font
								(size 1.27 1.27)
							)
						)
					)
				)
				(pin passive line
					(at 0 -5.08 0)
					(length 2.54)
					(name "~"
						(effects
							(font
								(size 1.27 1.27)
							)
						)
					)
					(number "3"
						(effects
							(font
								(size 1.27 1.27)
							)
						)
					)
				)
				(pin passive line
					(at 0 -7.62 0)
					(length 2.54)
					(name "~"
						(effects
							(font
								(size 1.27 1.27)
							)
						)
					)
					(number "4"
						(effects
							(font
								(size 1.27 1.27)
							)
						)
					)
				)
				(pin passive line
					(at 0 -10.16 0)
					(length 2.54)
					(name "~"
						(effects
							(font
								(size 1.27 1.27)
							)
						)
					)
					(number "MP"
						(effects
							(font
								(size 1.27 1.27)
							)
						)
					)
				)
			)
		)
	(symbol "antmicroWire2BoardConnectors:JST_SH_1x4_SM04B-SRSS-TB-LF-SN"
			(exclude_from_sim no)
			(in_bom yes)
			(on_board yes)
			(property "Reference" "J"
				(at 26.67 -2.54 0)
				(effects
					(font
						(size 1.27 1.27)
						(thickness 0.15)
					)
					(justify left bottom)
				)
			)
			(property "Value" "JST_SH_1x4_SM04B-SRSS-TB-LF-SN"
				(at 26.67 -7.62 0)
				(effects
					(font
						(size 1.27 1.27)
						(thickness 0.15)
					)
					(justify left bottom)
					(hide yes)
				)
			)
			(property "Footprint" "antmicro-footprints:Conn_JST_SH_1x4_SM04B-SRSS-TB-LF-SN"
				(at 26.67 -10.16 0)
				(effects
					(font
						(size 1.27 1.27)
						(thickness 0.15)
					)
					(justify left bottom)
					(hide yes)
				)
			)
			(property "Datasheet" "https://www.jst-mfg.com/product/pdf/eng/eSH.pdf"
				(at 26.67 -12.7 0)
				(effects
					(font
						(size 1.27 1.27)
						(thickness 0.15)
					)
					(justify left bottom)
					(hide yes)
				)
			)
			(property "Description" "Pin Header, Right Angle, Wire-to-Board, 1 mm, 1 Rows, 4 Contacts, Surface Mount Right Angle, SH"
				(at 26.67 -22.86 0)
				(effects
					(font
						(size 1.27 1.27)
					)
					(justify left bottom)
					(hide yes)
				)
			)
			(property "MPN" "SM04B-SRSS-TB(LF)(SN)"
				(at 26.67 -5.08 0)
				(effects
					(font
						(size 1.27 1.27)
						(thickness 0.15)
					)
					(justify left bottom)
				)
			)
			(property "Manufacturer" "JST Automotive Connectors"
				(at 26.67 -15.24 0)
				(effects
					(font
						(size 1.27 1.27)
						(thickness 0.15)
					)
					(justify left bottom)
					(hide yes)
				)
			)
			(property "Author" "Antmicro"
				(at 26.67 -17.78 0)
				(effects
					(font
						(size 1.27 1.27)
						(thickness 0.15)
					)
					(justify left bottom)
					(hide yes)
				)
			)
			(property "License" "Apache-2.0"
				(at 26.67 -20.32 0)
				(effects
					(font
						(size 1.27 1.27)
						(thickness 0.15)
					)
					(justify left bottom)
					(hide yes)
				)
			)
			(property "ki_keywords" "VERTICAL, SMT, WIRE-BOARD, CONNECTOR, MALE, HEADER"
				(at 0 0 0)
				(effects
					(font
						(size 1.27 1.27)
					)
					(hide yes)
				)
			)
			(symbol "JST_SH_1x4_SM04B-SRSS-TB-LF-SN_1_1"
				(rectangle
					(start 2.54 2.54)
					(end 5.08 -12.7)
					(stroke
						(width 0.254)
						(type default)
					)
					(fill
						(type background)
					)
				)
				(rectangle
					(start 2.54 0.127)
					(end 3.81 -0.127)
					(stroke
						(width 0.254)
						(type default)
					)
					(fill
						(type background)
					)
				)
				(rectangle
					(start 2.54 -2.413)
					(end 3.81 -2.667)
					(stroke
						(width 0.254)
						(type default)
					)
					(fill
						(type background)
					)
				)
				(rectangle
					(start 2.54 -4.953)
					(end 3.81 -5.207)
					(stroke
						(width 0.254)
						(type default)
					)
					(fill
						(type background)
					)
				)
				(rectangle
					(start 2.54 -7.493)
					(end 3.81 -7.747)
					(stroke
						(width 0.254)
						(type default)
					)
					(fill
						(type background)
					)
				)
				(rectangle
					(start 2.54 -10.033)
					(end 3.81 -10.287)
					(stroke
						(width 0.254)
						(type default)
					)
					(fill
						(type background)
					)
				)
				(pin passive line
					(at 0 0 0)
					(length 2.54)
					(name "~"
						(effects
							(font
								(size 1.27 1.27)
							)
						)
					)
					(number "1"
						(effects
							(font
								(size 1.27 1.27)
							)
						)
					)
				)
				(pin passive line
					(at 0 -2.54 0)
					(length 2.54)
					(name "~"
						(effects
							(font
								(size 1.27 1.27)
							)
						)
					)
					(number "2"
						(effects
							(font
								(size 1.27 1.27)
							)
						)
					)
				)
				(pin passive line
					(at 0 -5.08 0)
					(length 2.54)
					(name "~"
						(effects
							(font
								(size 1.27 1.27)
							)
						)
					)
					(number "3"
						(effects
							(font
								(size 1.27 1.27)
							)
						)
					)
				)
				(pin passive line
					(at 0 -7.62 0)
					(length 2.54)
					(name "~"
						(effects
							(font
								(size 1.27 1.27)
							)
						)
					)
					(number "4"
						(effects
							(font
								(size 1.27 1.27)
							)
						)
					)
				)
				(pin passive line
					(at 0 -10.16 0)
					(length 2.54)
					(name "~"
						(effects
							(font
								(size 1.27 1.27)
							)
						)
					)
					(number "MP"
						(effects
							(font
								(size 1.27 1.27)
							)
						)
					)
				)
			)
		)
	(symbol "antmicroWire2BoardConnectors:Molex_Mini-Fit_2x3_50362462"
			(pin_names
				(hide yes)
			)
			(exclude_from_sim no)
			(in_bom yes)
			(on_board yes)
			(property "Reference" "J"
				(at 29.21 -2.54 0)
				(effects
					(font
						(size 1.27 1.27)
						(thickness 0.15)
					)
					(justify left bottom)
				)
			)
			(property "Value" "Molex_Mini-Fit_2x3_50362462"
				(at 29.21 -7.62 0)
				(effects
					(font
						(size 1.27 1.27)
						(thickness 0.15)
					)
					(justify left bottom)
					(hide yes)
				)
			)
			(property "Footprint" "antmicro-footprints:Molex_Mini-Fit_2x3_50362462"
				(at 29.21 -10.16 0)
				(effects
					(font
						(size 1.27 1.27)
						(thickness 0.15)
					)
					(justify left bottom)
					(hide yes)
				)
			)
			(property "Datasheet" "https://www.molex.com/content/dam/molex/molex-dot-com/products/automated/en-us/salesdrawingpdf/556/5569/050362462_sd.pdf?inline"
				(at 29.21 -12.7 0)
				(effects
					(font
						(size 1.27 1.27)
						(thickness 0.15)
					)
					(justify left bottom)
					(hide yes)
				)
			)
			(property "Description" "Pin Header, Wire-to-Board, 2 Rows, 6 Contacts, Through Hole Right-Angle, Mini-Fit, 13A/pin, 600V, 4.2mm"
				(at 29.21 -22.86 0)
				(effects
					(font
						(size 1.27 1.27)
					)
					(justify left bottom)
					(hide yes)
				)
			)
			(property "MPN" "50362462"
				(at 29.21 -5.08 0)
				(effects
					(font
						(size 1.27 1.27)
						(thickness 0.15)
					)
					(justify left bottom)
				)
			)
			(property "Manufacturer" "Molex"
				(at 29.21 -15.24 0)
				(effects
					(font
						(size 1.27 1.27)
						(thickness 0.15)
					)
					(justify left bottom)
					(hide yes)
				)
			)
			(property "Author" "Antmicro"
				(at 29.21 -17.78 0)
				(effects
					(font
						(size 1.27 1.27)
						(thickness 0.15)
					)
					(justify left bottom)
					(hide yes)
				)
			)
			(property "License" "Apache-2.0"
				(at 29.21 -20.32 0)
				(effects
					(font
						(size 1.27 1.27)
						(thickness 0.15)
					)
					(justify left bottom)
					(hide yes)
				)
			)
			(property "ki_keywords" "CONNECTOR, THT, WIRE-BOARD, HORIZONTAL, POWER"
				(at 0 0 0)
				(effects
					(font
						(size 1.27 1.27)
					)
					(hide yes)
				)
			)
			(symbol "Molex_Mini-Fit_2x3_50362462_1_1"
				(rectangle
					(start 2.54 1.27)
					(end 7.62 -6.35)
					(stroke
						(width 0.254)
						(type default)
					)
					(fill
						(type background)
					)
				)
				(pin input line
					(at 0 0 0)
					(length 2.54)
					(name "1"
						(effects
							(font
								(size 1.27 1.27)
							)
						)
					)
					(number "1"
						(effects
							(font
								(size 1.27 1.27)
							)
						)
					)
				)
				(pin input line
					(at 0 -2.54 0)
					(length 2.54)
					(name "2"
						(effects
							(font
								(size 1.27 1.27)
							)
						)
					)
					(number "2"
						(effects
							(font
								(size 1.27 1.27)
							)
						)
					)
				)
				(pin input line
					(at 0 -5.08 0)
					(length 2.54)
					(name "3"
						(effects
							(font
								(size 1.27 1.27)
							)
						)
					)
					(number "3"
						(effects
							(font
								(size 1.27 1.27)
							)
						)
					)
				)
				(pin input line
					(at 10.16 0 180)
					(length 2.54)
					(name "4"
						(effects
							(font
								(size 1.27 1.27)
							)
						)
					)
					(number "4"
						(effects
							(font
								(size 1.27 1.27)
							)
						)
					)
				)
				(pin input line
					(at 10.16 -2.54 180)
					(length 2.54)
					(name "5"
						(effects
							(font
								(size 1.27 1.27)
							)
						)
					)
					(number "5"
						(effects
							(font
								(size 1.27 1.27)
							)
						)
					)
				)
				(pin input line
					(at 10.16 -5.08 180)
					(length 2.54)
					(name "6"
						(effects
							(font
								(size 1.27 1.27)
							)
						)
					)
					(number "6"
						(effects
							(font
								(size 1.27 1.27)
							)
						)
					)
				)
			)
		)
	(symbol "antmicroWire2BoardConnectors:Molex_PicoBlade_1x4_0533980471"
			(pin_names
				(hide yes)
			)
			(exclude_from_sim no)
			(in_bom yes)
			(on_board yes)
			(property "Reference" "J"
				(at 20.32 -5.08 0)
				(effects
					(font
						(size 1.27 1.27)
						(thickness 0.15)
					)
					(justify left bottom)
				)
			)
			(property "Value" "Molex_PicoBlade_1x4_0533980471"
				(at 20.32 -7.62 0)
				(effects
					(font
						(size 1.27 1.27)
						(thickness 0.15)
					)
					(justify left bottom)
					(hide yes)
				)
			)
			(property "Footprint" "antmicro-footprints:Conn_Molex_PicoBlade_1x4_0533980471"
				(at 20.32 -10.16 0)
				(effects
					(font
						(size 1.27 1.27)
						(thickness 0.15)
					)
					(justify left bottom)
					(hide yes)
				)
			)
			(property "Datasheet" "https://www.molex.com/molex/products/part-detail/pcb_headers/0533980471"
				(at 20.32 -12.7 0)
				(effects
					(font
						(size 1.27 1.27)
						(thickness 0.15)
					)
					(justify left bottom)
					(hide yes)
				)
			)
			(property "Description" "Pin Header, Vertical, Signal, 1.25 mm, 1 Rows, 4 Contacts, Surface Mount Straight"
				(at 20.32 -25.4 0)
				(effects
					(font
						(size 1.27 1.27)
					)
					(justify left bottom)
					(hide yes)
				)
			)
			(property "MPN" "0533980471"
				(at 20.32 -17.78 0)
				(effects
					(font
						(size 1.27 1.27)
						(thickness 0.15)
					)
					(justify left bottom)
				)
			)
			(property "Manufacturer" "Molex"
				(at 20.32 -15.24 0)
				(effects
					(font
						(size 1.27 1.27)
						(thickness 0.15)
					)
					(justify left bottom)
					(hide yes)
				)
			)
			(property "Author" "Antmicro"
				(at 20.32 -20.32 0)
				(effects
					(font
						(size 1.27 1.27)
						(thickness 0.15)
					)
					(justify left bottom)
					(hide yes)
				)
			)
			(property "License" "Apache-2.0"
				(at 20.32 -22.86 0)
				(effects
					(font
						(size 1.27 1.27)
						(thickness 0.15)
					)
					(justify left bottom)
					(hide yes)
				)
			)
			(property "ki_keywords" "PINSTRIP, HEADER, SMT"
				(at 0 0 0)
				(effects
					(font
						(size 1.27 1.27)
					)
					(hide yes)
				)
			)
			(symbol "Molex_PicoBlade_1x4_0533980471_1_1"
				(rectangle
					(start 3.81 1.27)
					(end 6.35 -13.97)
					(stroke
						(width 0.254)
						(type default)
					)
					(fill
						(type background)
					)
				)
				(rectangle
					(start 3.81 0.127)
					(end 5.08 -0.127)
					(stroke
						(width 0.254)
						(type default)
					)
					(fill
						(type background)
					)
				)
				(rectangle
					(start 3.81 -2.413)
					(end 5.08 -2.667)
					(stroke
						(width 0.254)
						(type default)
					)
					(fill
						(type background)
					)
				)
				(rectangle
					(start 3.81 -4.953)
					(end 5.08 -5.207)
					(stroke
						(width 0.254)
						(type default)
					)
					(fill
						(type background)
					)
				)
				(rectangle
					(start 3.81 -7.493)
					(end 5.08 -7.747)
					(stroke
						(width 0.254)
						(type default)
					)
					(fill
						(type background)
					)
				)
				(rectangle
					(start 3.81 -10.033)
					(end 5.08 -10.287)
					(stroke
						(width 0.254)
						(type default)
					)
					(fill
						(type background)
					)
				)
				(rectangle
					(start 3.81 -12.573)
					(end 5.08 -12.827)
					(stroke
						(width 0.254)
						(type default)
					)
					(fill
						(type background)
					)
				)
				(pin passive line
					(at 0 0 0)
					(length 3.81)
					(name "1"
						(effects
							(font
								(size 1.27 1.27)
							)
						)
					)
					(number "1"
						(effects
							(font
								(size 1.27 1.27)
							)
						)
					)
				)
				(pin passive line
					(at 0 -2.54 0)
					(length 3.81)
					(name "2"
						(effects
							(font
								(size 1.27 1.27)
							)
						)
					)
					(number "2"
						(effects
							(font
								(size 1.27 1.27)
							)
						)
					)
				)
				(pin passive line
					(at 0 -5.08 0)
					(length 3.81)
					(name "3"
						(effects
							(font
								(size 1.27 1.27)
							)
						)
					)
					(number "3"
						(effects
							(font
								(size 1.27 1.27)
							)
						)
					)
				)
				(pin passive line
					(at 0 -7.62 0)
					(length 3.81)
					(name "4"
						(effects
							(font
								(size 1.27 1.27)
							)
						)
					)
					(number "4"
						(effects
							(font
								(size 1.27 1.27)
							)
						)
					)
				)
				(pin passive line
					(at 0 -10.16 0)
					(length 3.81)
					(name "MP1"
						(effects
							(font
								(size 1.27 1.27)
							)
						)
					)
					(number "MP1"
						(effects
							(font
								(size 1.27 1.27)
							)
						)
					)
				)
				(pin passive line
					(at 0 -12.7 0)
					(length 3.81)
					(name "MP2"
						(effects
							(font
								(size 1.27 1.27)
							)
						)
					)
					(number "MP2"
						(effects
							(font
								(size 1.27 1.27)
							)
						)
					)
				)
			)
		)
	(symbol "antmicropower:+12V_AON"
			(power)
			(pin_names
				(offset 0)
			)
			(exclude_from_sim no)
			(in_bom yes)
			(on_board yes)
			(property "Reference" "#PWR"
				(at 0 -3.81 0)
				(effects
					(font
						(size 1.27 1.27)
					)
					(hide yes)
				)
			)
			(property "Value" "+12V_AON"
				(at 0 3.556 0)
				(effects
					(font
						(size 1.27 1.27)
					)
				)
			)
			(property "Footprint" ""
				(at 0 0 0)
				(effects
					(font
						(size 1.27 1.27)
					)
					(hide yes)
				)
			)
			(property "Datasheet" ""
				(at 0 0 0)
				(effects
					(font
						(size 1.27 1.27)
					)
					(hide yes)
				)
			)
			(property "Description" ""
				(at 0 -6.35 0)
				(effects
					(font
						(size 1.27 1.27)
					)
					(justify left bottom)
					(hide yes)
				)
			)
			(symbol "+12V_AON_0_1"
				(polyline
					(pts
						(xy -0.762 1.27) (xy 0 2.54)
					)
					(stroke
						(width 0)
						(type default)
					)
					(fill
						(type none)
					)
				)
				(polyline
					(pts
						(xy 0 2.54) (xy 0.762 1.27)
					)
					(stroke
						(width 0)
						(type default)
					)
					(fill
						(type none)
					)
				)
				(polyline
					(pts
						(xy 0 0) (xy 0 2.54)
					)
					(stroke
						(width 0)
						(type default)
					)
					(fill
						(type none)
					)
				)
			)
			(symbol "+12V_AON_1_1"
				(pin power_in line
					(at 0 0 90)
					(length 0)
					(hide yes)
					(name "+12V_AON"
						(effects
							(font
								(size 1.27 1.27)
							)
						)
					)
					(number "1"
						(effects
							(font
								(size 1.27 1.27)
							)
						)
					)
				)
			)
		)
	(symbol "antmicropower:+1V8"
			(power)
			(pin_numbers
				(hide yes)
			)
			(pin_names
				(hide yes)
			)
			(exclude_from_sim no)
			(in_bom yes)
			(on_board yes)
			(property "Reference" "#PWR"
				(at 15.24 -2.54 0)
				(effects
					(font
						(size 1.27 1.27)
						(thickness 0.15)
					)
					(justify left bottom)
					(hide yes)
				)
			)
			(property "Value" "+1V8"
				(at -3.175 2.54 0)
				(effects
					(font
						(size 1.27 1.27)
						(thickness 0.15)
					)
					(justify left bottom)
				)
			)
			(property "Footprint" ""
				(at 15.24 -7.62 0)
				(effects
					(font
						(size 1.27 1.27)
						(thickness 0.15)
					)
					(justify left bottom)
					(hide yes)
				)
			)
			(property "Datasheet" ""
				(at 15.24 -10.16 0)
				(effects
					(font
						(size 1.27 1.27)
						(thickness 0.15)
					)
					(justify left bottom)
					(hide yes)
				)
			)
			(property "Description" ""
				(at 15.24 -12.7 0)
				(effects
					(font
						(size 1.27 1.27)
					)
					(justify left bottom)
					(hide yes)
				)
			)
			(property "Author" "Antmicro"
				(at 15.24 -5.08 0)
				(effects
					(font
						(size 1.27 1.27)
						(thickness 0.15)
					)
					(justify left bottom)
					(hide yes)
				)
			)
			(property "License" "Apache-2.0"
				(at 15.24 -7.62 0)
				(effects
					(font
						(size 1.27 1.27)
						(thickness 0.15)
					)
					(justify left bottom)
					(hide yes)
				)
			)
			(symbol "+1V8_1_1"
				(polyline
					(pts
						(xy -0.762 1.27) (xy 0 2.54)
					)
					(stroke
						(width 0)
						(type default)
					)
					(fill
						(type background)
					)
				)
				(polyline
					(pts
						(xy 0 2.54) (xy 0.762 1.27)
					)
					(stroke
						(width 0)
						(type default)
					)
					(fill
						(type background)
					)
				)
				(polyline
					(pts
						(xy 0 0) (xy 0 2.54)
					)
					(stroke
						(width 0)
						(type default)
					)
					(fill
						(type background)
					)
				)
				(pin power_in line
					(at 0 0 90)
					(length 0)
					(hide yes)
					(name "+1V8"
						(effects
							(font
								(size 1.27 1.27)
							)
						)
					)
					(number "1"
						(effects
							(font
								(size 1.27 1.27)
							)
						)
					)
				)
			)
		)
	(symbol "antmicropower:+24V"
			(power)
			(pin_names
				(offset 0)
			)
			(exclude_from_sim no)
			(in_bom yes)
			(on_board yes)
			(property "Reference" "#PWR"
				(at 0 -3.81 0)
				(effects
					(font
						(size 1.27 1.27)
					)
					(hide yes)
				)
			)
			(property "Value" "+24V"
				(at 0 3.556 0)
				(effects
					(font
						(size 1.27 1.27)
					)
				)
			)
			(property "Footprint" ""
				(at 0 0 0)
				(effects
					(font
						(size 1.27 1.27)
					)
					(hide yes)
				)
			)
			(property "Datasheet" ""
				(at 0 0 0)
				(effects
					(font
						(size 1.27 1.27)
					)
					(hide yes)
				)
			)
			(property "Description" ""
				(at 0 -6.35 0)
				(effects
					(font
						(size 1.27 1.27)
					)
					(justify left bottom)
					(hide yes)
				)
			)
			(symbol "+24V_0_1"
				(polyline
					(pts
						(xy -0.762 1.27) (xy 0 2.54)
					)
					(stroke
						(width 0)
						(type default)
					)
					(fill
						(type none)
					)
				)
				(polyline
					(pts
						(xy 0 2.54) (xy 0.762 1.27)
					)
					(stroke
						(width 0)
						(type default)
					)
					(fill
						(type none)
					)
				)
				(polyline
					(pts
						(xy 0 0) (xy 0 2.54)
					)
					(stroke
						(width 0)
						(type default)
					)
					(fill
						(type none)
					)
				)
			)
			(symbol "+24V_1_1"
				(pin power_in line
					(at 0 0 90)
					(length 0)
					(hide yes)
					(name "+24V"
						(effects
							(font
								(size 1.27 1.27)
							)
						)
					)
					(number "1"
						(effects
							(font
								(size 1.27 1.27)
							)
						)
					)
				)
			)
		)
	(symbol "antmicropower:+3V3"
			(power)
			(pin_numbers
				(hide yes)
			)
			(pin_names
				(hide yes)
			)
			(exclude_from_sim no)
			(in_bom yes)
			(on_board yes)
			(property "Reference" "#PWR"
				(at 15.24 0 0)
				(effects
					(font
						(size 1.27 1.27)
						(thickness 0.15)
					)
					(justify left bottom)
					(hide yes)
				)
			)
			(property "Value" "+3V3"
				(at -3.175 2.54 0)
				(effects
					(font
						(size 1.27 1.27)
						(thickness 0.15)
					)
					(justify left bottom)
				)
			)
			(property "Footprint" ""
				(at 15.24 -7.62 0)
				(effects
					(font
						(size 1.27 1.27)
						(thickness 0.15)
					)
					(justify left bottom)
					(hide yes)
				)
			)
			(property "Datasheet" ""
				(at 15.24 -10.16 0)
				(effects
					(font
						(size 1.27 1.27)
						(thickness 0.15)
					)
					(justify left bottom)
					(hide yes)
				)
			)
			(property "Description" ""
				(at 15.24 -12.7 0)
				(effects
					(font
						(size 1.27 1.27)
					)
					(justify left bottom)
					(hide yes)
				)
			)
			(property "Author" "Antmicro"
				(at 15.24 -2.54 0)
				(effects
					(font
						(size 1.27 1.27)
						(thickness 0.15)
					)
					(justify left bottom)
					(hide yes)
				)
			)
			(property "License" "Apache-2.0"
				(at 15.24 -5.08 0)
				(effects
					(font
						(size 1.27 1.27)
						(thickness 0.15)
					)
					(justify left bottom)
					(hide yes)
				)
			)
			(symbol "+3V3_0_1"
				(polyline
					(pts
						(xy 0 2.54) (xy -0.762 1.27)
					)
					(stroke
						(width 0)
						(type default)
					)
					(fill
						(type none)
					)
				)
				(polyline
					(pts
						(xy 0 2.54) (xy 0.762 1.27)
					)
					(stroke
						(width 0)
						(type default)
					)
					(fill
						(type none)
					)
				)
				(polyline
					(pts
						(xy 0 0) (xy 0 2.54)
					)
					(stroke
						(width 0)
						(type default)
					)
					(fill
						(type none)
					)
				)
			)
			(symbol "+3V3_1_1"
				(pin power_in line
					(at 0 0 90)
					(length 0)
					(hide yes)
					(name "+3V3"
						(effects
							(font
								(size 1.27 1.27)
							)
						)
					)
					(number "1"
						(effects
							(font
								(size 1.27 1.27)
							)
						)
					)
				)
			)
		)
	(symbol "antmicropower:+3V3_AON"
			(power)
			(pin_names
				(offset 0)
			)
			(exclude_from_sim no)
			(in_bom yes)
			(on_board yes)
			(property "Reference" "#PWR"
				(at 0 -3.81 0)
				(effects
					(font
						(size 1.27 1.27)
					)
					(hide yes)
				)
			)
			(property "Value" "+3V3_AON"
				(at 0 3.556 0)
				(effects
					(font
						(size 1.27 1.27)
					)
				)
			)
			(property "Footprint" ""
				(at 0 0 0)
				(effects
					(font
						(size 1.27 1.27)
					)
					(hide yes)
				)
			)
			(property "Datasheet" ""
				(at 0 0 0)
				(effects
					(font
						(size 1.27 1.27)
					)
					(hide yes)
				)
			)
			(property "Description" ""
				(at 0 -6.35 0)
				(effects
					(font
						(size 1.27 1.27)
					)
					(justify left bottom)
					(hide yes)
				)
			)
			(symbol "+3V3_AON_0_1"
				(polyline
					(pts
						(xy -0.762 1.27) (xy 0 2.54)
					)
					(stroke
						(width 0)
						(type default)
					)
					(fill
						(type none)
					)
				)
				(polyline
					(pts
						(xy 0 2.54) (xy 0.762 1.27)
					)
					(stroke
						(width 0)
						(type default)
					)
					(fill
						(type none)
					)
				)
				(polyline
					(pts
						(xy 0 0) (xy 0 2.54)
					)
					(stroke
						(width 0)
						(type default)
					)
					(fill
						(type none)
					)
				)
			)
			(symbol "+3V3_AON_1_1"
				(pin power_in line
					(at 0 0 90)
					(length 0)
					(hide yes)
					(name "+3V3_AON"
						(effects
							(font
								(size 1.27 1.27)
							)
						)
					)
					(number "1"
						(effects
							(font
								(size 1.27 1.27)
							)
						)
					)
				)
			)
		)
	(symbol "antmicropower:+5V"
			(power)
			(pin_numbers
				(hide yes)
			)
			(pin_names
				(hide yes)
			)
			(exclude_from_sim no)
			(in_bom yes)
			(on_board yes)
			(property "Reference" "#PWR"
				(at 15.24 -2.54 0)
				(effects
					(font
						(size 1.27 1.27)
						(thickness 0.15)
					)
					(justify left bottom)
					(hide yes)
				)
			)
			(property "Value" "+5V"
				(at 15.24 -5.08 0)
				(effects
					(font
						(size 1.27 1.27)
						(thickness 0.15)
					)
					(justify left bottom)
				)
			)
			(property "Footprint" ""
				(at 15.24 -7.62 0)
				(effects
					(font
						(size 1.27 1.27)
						(thickness 0.15)
					)
					(justify left bottom)
					(hide yes)
				)
			)
			(property "Datasheet" ""
				(at 15.24 -10.16 0)
				(effects
					(font
						(size 1.27 1.27)
						(thickness 0.15)
					)
					(justify left bottom)
					(hide yes)
				)
			)
			(property "Description" ""
				(at 15.24 -12.7 0)
				(effects
					(font
						(size 1.27 1.27)
					)
					(justify left bottom)
					(hide yes)
				)
			)
			(property "Author" "Antmicro"
				(at 15.24 -7.62 0)
				(effects
					(font
						(size 1.27 1.27)
						(thickness 0.15)
					)
					(justify left bottom)
					(hide yes)
				)
			)
			(property "License" "Apache-2.0"
				(at 15.24 -10.16 0)
				(effects
					(font
						(size 1.27 1.27)
						(thickness 0.15)
					)
					(justify left bottom)
					(hide yes)
				)
			)
			(symbol "+5V_1_1"
				(polyline
					(pts
						(xy -0.762 1.27) (xy 0 2.54)
					)
					(stroke
						(width 0)
						(type default)
					)
					(fill
						(type background)
					)
				)
				(polyline
					(pts
						(xy 0 2.54) (xy 0.762 1.27)
					)
					(stroke
						(width 0)
						(type default)
					)
					(fill
						(type background)
					)
				)
				(polyline
					(pts
						(xy 0 0) (xy 0 2.54)
					)
					(stroke
						(width 0)
						(type default)
					)
					(fill
						(type background)
					)
				)
				(pin power_in line
					(at 0 0 90)
					(length 0)
					(name "+5V"
						(effects
							(font
								(size 1.27 1.27)
							)
						)
					)
					(number "1"
						(effects
							(font
								(size 1.27 1.27)
							)
						)
					)
				)
			)
		)
	(symbol "antmicropower:GND"
			(power)
			(pin_numbers
				(hide yes)
			)
			(pin_names
				(hide yes)
			)
			(exclude_from_sim no)
			(in_bom yes)
			(on_board yes)
			(property "Reference" "#PWR"
				(at 8.89 -2.54 0)
				(effects
					(font
						(size 1.27 1.27)
						(thickness 0.15)
					)
					(justify left bottom)
					(hide yes)
				)
			)
			(property "Value" "GND"
				(at 8.89 -5.08 0)
				(effects
					(font
						(size 1.27 1.27)
						(thickness 0.15)
					)
					(justify left bottom)
				)
			)
			(property "Footprint" ""
				(at 8.89 -7.62 0)
				(effects
					(font
						(size 1.27 1.27)
						(thickness 0.15)
					)
					(justify left bottom)
					(hide yes)
				)
			)
			(property "Datasheet" ""
				(at 8.89 -12.7 0)
				(effects
					(font
						(size 1.27 1.27)
						(thickness 0.15)
					)
					(justify left bottom)
					(hide yes)
				)
			)
			(property "Description" ""
				(at 8.89 -15.24 0)
				(effects
					(font
						(size 1.27 1.27)
					)
					(justify left bottom)
					(hide yes)
				)
			)
			(property "Author" "Antmicro"
				(at 8.89 -7.62 0)
				(effects
					(font
						(size 1.27 1.27)
						(thickness 0.15)
					)
					(justify left bottom)
					(hide yes)
				)
			)
			(property "License" "Apache-2.0"
				(at 8.89 -10.16 0)
				(effects
					(font
						(size 1.27 1.27)
						(thickness 0.15)
					)
					(justify left bottom)
					(hide yes)
				)
			)
			(symbol "GND_1_1"
				(polyline
					(pts
						(xy 0 0) (xy 0 -1.27) (xy 1.27 -1.27) (xy 0 -2.54) (xy -1.27 -1.27) (xy 0 -1.27)
					)
					(stroke
						(width 0)
						(type default)
					)
					(fill
						(type none)
					)
				)
				(pin power_in line
					(at 0 0 270)
					(length 0)
					(name "GND"
						(effects
							(font
								(size 1.27 1.27)
							)
						)
					)
					(number "1"
						(effects
							(font
								(size 1.27 1.27)
							)
						)
					)
				)
			)
		)
	(symbol "antmicropower:PWR_FLAG"
			(power)
			(pin_numbers
				(hide yes)
			)
			(pin_names
				(offset 0)
				(hide yes)
			)
			(exclude_from_sim no)
			(in_bom yes)
			(on_board yes)
			(property "Reference" "#FLG"
				(at 0 1.905 0)
				(effects
					(font
						(size 1.27 1.27)
					)
					(hide yes)
				)
			)
			(property "Value" "PWR_FLAG"
				(at 0 3.81 0)
				(effects
					(font
						(size 1.27 1.27)
					)
				)
			)
			(property "Footprint" ""
				(at 0 0 0)
				(effects
					(font
						(size 1.27 1.27)
					)
					(hide yes)
				)
			)
			(property "Datasheet" ""
				(at 0 0 0)
				(effects
					(font
						(size 1.27 1.27)
					)
					(hide yes)
				)
			)
			(property "Description" ""
				(at 0 -2.54 0)
				(effects
					(font
						(size 1.27 1.27)
					)
					(justify left bottom)
					(hide yes)
				)
			)
			(symbol "PWR_FLAG_0_0"
				(pin power_out line
					(at 0 0 90)
					(length 0)
					(name "pwr"
						(effects
							(font
								(size 1.27 1.27)
							)
						)
					)
					(number "1"
						(effects
							(font
								(size 1.27 1.27)
							)
						)
					)
				)
			)
			(symbol "PWR_FLAG_0_1"
				(polyline
					(pts
						(xy 0 0) (xy 0 1.27) (xy -1.016 1.905) (xy 0 2.54) (xy 1.016 1.905) (xy 0 1.27)
					)
					(stroke
						(width 0)
						(type default)
					)
					(fill
						(type none)
					)
				)
			)
		)
	(symbol "antmicropower:VCC"
			(power)
			(pin_names
				(offset 0)
			)
			(exclude_from_sim no)
			(in_bom yes)
			(on_board yes)
			(property "Reference" "#PWR"
				(at 0 -3.81 0)
				(effects
					(font
						(size 1.27 1.27)
					)
					(hide yes)
				)
			)
			(property "Value" "VCC"
				(at 0 3.81 0)
				(effects
					(font
						(size 1.27 1.27)
					)
				)
			)
			(property "Footprint" ""
				(at 0 0 0)
				(effects
					(font
						(size 1.27 1.27)
					)
					(hide yes)
				)
			)
			(property "Datasheet" ""
				(at 0 0 0)
				(effects
					(font
						(size 1.27 1.27)
					)
					(hide yes)
				)
			)
			(property "Description" ""
				(at 0 -6.35 0)
				(effects
					(font
						(size 1.27 1.27)
					)
					(justify left bottom)
					(hide yes)
				)
			)
			(symbol "VCC_0_1"
				(polyline
					(pts
						(xy -0.762 1.27) (xy 0 2.54)
					)
					(stroke
						(width 0)
						(type default)
					)
					(fill
						(type none)
					)
				)
				(polyline
					(pts
						(xy 0 2.54) (xy 0.762 1.27)
					)
					(stroke
						(width 0)
						(type default)
					)
					(fill
						(type none)
					)
				)
				(polyline
					(pts
						(xy 0 0) (xy 0 2.54)
					)
					(stroke
						(width 0)
						(type default)
					)
					(fill
						(type none)
					)
				)
			)
			(symbol "VCC_1_1"
				(pin power_in line
					(at 0 0 90)
					(length 0)
					(hide yes)
					(name "VCC"
						(effects
							(font
								(size 1.27 1.27)
							)
						)
					)
					(number "1"
						(effects
							(font
								(size 1.27 1.27)
							)
						)
					)
				)
			)
		)
)
